G04 ================== begin FILE IDENTIFICATION RECORD ==================*
G04 Layout Name:  D:/<user>/Wistron_project/16318-2/gbr/16318-2.brd*
G04 Film Name:    TSILK*
G04 File Format:  Gerber RS274X*
G04 File Origin:  Cadence Allegro 16.5-S056*
G04 Origin Date:  Mon Aug 07 11:09:26 2017*
G04 *
G04 Layer:  VIA CLASS/FILMMASKTOP*
G04 Layer:  REF DES/ASSEMBLY_TOP*
G04 Layer:  PACKAGE GEOMETRY/SILKSCREEN_TOP*
G04 Layer:  DRAWING FORMAT/LAYER_PCB_STORY*
G04 Layer:  DRAWING FORMAT/LAYER_SILK_T*
G04 Layer:  BOARD GEOMETRY/SILKSCREEN_TOP*
G04 *
G04 Offset:    (0.00 0.00)*
G04 Mirror:    No*
G04 Mode:      Positive*
G04 Rotation:  0*
G04 FullContactRelief:  No*
G04 UndefLineWidth:     6.00*
G04 ================== end FILE IDENTIFICATION RECORD ====================*
%FSLAX35Y35*MOIN*%
%IR0*IPPOS*OFA0.00000B0.00000*MIA0B0*SFA1.00000B1.00000*%
%ADD10C,.026*%
%ADD11C,.01*%
%ADD12C,.02*%
%ADD13C,.012*%
%ADD14C,.013*%
%ADD15C,.015*%
%ADD16C,.016*%
%ADD17C,.018*%
%ADD18C,.019*%
%ADD19C,.002*%
%ADD20C,.006*%
%ADD21C,.008*%
%ADD22R,.42X.06*%
G75*
%LPD*%
G75*
G36*
G01X17189Y73008D02*
X40811D01*
Y198992D01*
X17189D01*
Y73008D01*
G37*
G36*
G01X79564Y652000D02*
Y657000D01*
X74564Y652000D01*
X79564D01*
G37*
G36*
G01X159939Y496299D02*
X129581D01*
Y459299D01*
X159939D01*
Y496299D01*
G37*
G36*
G01X132060Y459040D02*
Y496549D01*
X157460D01*
Y459040D01*
X132060D01*
G37*
G36*
G01X119250Y512052D02*
Y517052D01*
X121750Y514552D01*
X119250Y512052D01*
G37*
G36*
G01X202651Y675636D02*
Y681584D01*
G03X204601Y684206I-850J2668D01*
G01X222801D01*
G03X224751Y681584I2800J46D01*
G01Y675636D01*
X202651D01*
G37*
G36*
G01X203677Y665698D02*
X201177Y663198D01*
X206177D01*
X203677Y665698D01*
G37*
G36*
G01X148869Y701045D02*
Y705095D01*
X144819Y701045D01*
X148869D01*
G37*
G36*
G01X254979Y496300D02*
X224621D01*
Y459300D01*
X254979D01*
Y496300D01*
G37*
G36*
G01X227100Y459041D02*
Y496550D01*
X252500D01*
Y459041D01*
X227100D01*
G37*
G36*
G01X283200Y598200D02*
X272000D01*
Y580800D01*
X283200D01*
Y598200D01*
G37*
G36*
G01X319993Y192728D02*
X321993Y190728D01*
Y194728D01*
X319993Y192728D01*
G37*
G36*
G01X301996Y379543D02*
Y191717D01*
X309816D01*
Y379543D01*
X301996D01*
G37*
G36*
G01X309170Y521691D02*
Y530491D01*
X313770D01*
Y521691D01*
X309170D01*
G37*
G36*
G01X317621Y555447D02*
Y581087D01*
X332221D01*
Y555447D01*
X317621D01*
G37*
G36*
G01X320150Y624750D02*
Y629750D01*
X315150Y624750D01*
X320150D01*
G37*
G36*
G01X286283Y621015D02*
Y616015D01*
X283783Y618515D01*
X286283Y621015D01*
G37*
G36*
G01X309484Y696220D02*
Y701220D01*
X304484Y696220D01*
X309484D01*
G37*
G36*
G01X395591Y76396D02*
Y71396D01*
X393091Y73896D01*
X395591Y76396D01*
G37*
G36*
G01X365600Y112900D02*
X367000Y111500D01*
Y114300D01*
X365600Y112900D01*
G37*
G36*
G01X340411Y215964D02*
Y204764D01*
X357811D01*
Y215964D01*
X340411D01*
G37*
G36*
G01X374688Y537881D02*
X363488D01*
Y520481D01*
X374688D01*
Y537881D01*
G37*
G36*
G01X374139Y577009D02*
Y546249D01*
X359539D01*
Y577009D01*
X374139D01*
G37*
G36*
G01X375011Y653549D02*
Y650149D01*
X373311Y651849D01*
X375011Y653549D01*
G37*
G36*
G01X349364Y623420D02*
X354364Y628420D01*
X349364D01*
Y623420D01*
G37*
G36*
G01X374600Y702400D02*
X376000Y701000D01*
Y703800D01*
X374600Y702400D01*
G37*
G36*
G01X370810Y696800D02*
Y671160D01*
X356210D01*
Y696800D01*
X370810D01*
G37*
G36*
G01X454150Y44250D02*
X459150Y49250D01*
X454150D01*
Y44250D01*
G37*
G36*
G01X420655Y122016D02*
G02X422655I1000J0D01*
G01Y120016D01*
G02X420655I-1000J0D01*
G01Y122016D01*
G37*
G36*
G01X434828D02*
G02X436828I1000J0D01*
G01Y120016D01*
G02X434828I-1000J0D01*
G01Y122016D01*
G37*
G36*
G01X449001D02*
G02X451001I1000J0D01*
G01Y120016D01*
G02X449001I-1000J0D01*
G01Y122016D01*
G37*
G36*
G01X463174D02*
G02X465174I1000J0D01*
G01Y120016D01*
G02X463174I-1000J0D01*
G01Y122016D01*
G37*
G36*
G01X559999Y188977D02*
Y143306D01*
X558799D01*
Y185571D01*
X419153D01*
Y119154D01*
X419149D01*
Y117016D01*
X469099D01*
Y112866D01*
X510299D01*
Y117016D01*
X558799D01*
Y143302D01*
X559999D01*
Y112116D01*
X416299D01*
Y188977D01*
X559999D01*
G37*
G36*
G01X427742Y182016D02*
G02X429742I1000J0D01*
G01Y180016D01*
G02X427742I-1000J0D01*
G01Y182016D01*
G37*
G36*
G01X441915D02*
G02X443915I1000J0D01*
G01Y180016D01*
G02X441915I-1000J0D01*
G01Y182016D01*
G37*
G36*
G01X456088D02*
G02X458088I1000J0D01*
G01Y180016D01*
G02X456088I-1000J0D01*
G01Y182016D01*
G37*
G36*
G01X470261D02*
G02X472261I1000J0D01*
G01Y180016D01*
G02X470261I-1000J0D01*
G01Y182016D01*
G37*
G36*
G01X522893Y41285D02*
X524593Y39585D01*
X522893Y37885D01*
Y41285D01*
G37*
G36*
G01X505693Y122016D02*
G02X507693I1000J0D01*
G01Y120016D01*
G02X505693I-1000J0D01*
G01Y122016D01*
G37*
G36*
G01X519866D02*
G02X521866I1000J0D01*
G01Y120016D01*
G02X519866I-1000J0D01*
G01Y122016D01*
G37*
G36*
G01X534039D02*
G02X536039I1000J0D01*
G01Y120016D01*
G02X534039I-1000J0D01*
G01Y122016D01*
G37*
G36*
G01X512780Y182016D02*
G02X514780I1000J0D01*
G01Y180016D01*
G02X512780I-1000J0D01*
G01Y182016D01*
G37*
G36*
G01X526953D02*
G02X528953I1000J0D01*
G01Y180016D01*
G02X526953I-1000J0D01*
G01Y182016D01*
G37*
G36*
G01X542511Y44801D02*
X540511Y42801D01*
X544511D01*
X542511Y44801D01*
G37*
G36*
G01X571040Y57365D02*
Y60235D01*
X576160D01*
Y57365D01*
X571040D01*
G37*
G36*
G01X548212Y122016D02*
G02X550212I1000J0D01*
G01Y120016D01*
G02X548212I-1000J0D01*
G01Y122016D01*
G37*
G36*
G01X541126Y182016D02*
G02X543126I1000J0D01*
G01Y180016D01*
G02X541126I-1000J0D01*
G01Y182016D01*
G37*
G36*
G01X555299D02*
G02X557299I1000J0D01*
G01Y180016D01*
G02X555299I-1000J0D01*
G01Y182016D01*
G37*
G36*
G01X603121Y-23326D02*
Y16474D01*
X656721D01*
Y-23326D01*
X603121D01*
G37*
G36*
G01X647271Y18622D02*
G02X644471I-1400J0D01*
G01Y21322D01*
G02X647271I1400J0D01*
G01Y18622D01*
G37*
G36*
G01X615271D02*
G02X612471I-1400J0D01*
G01Y21322D01*
G02X615271I1400J0D01*
G01Y18622D01*
G37*
G36*
G01X648521Y69224D02*
G02X645521I-1500J0D01*
G01Y75224D01*
G02X648521I1500J0D01*
G01Y69224D01*
G37*
G36*
G01X614521D02*
G02X611521I-1500J0D01*
G01Y75224D01*
G02X614521I1500J0D01*
G01Y69224D01*
G37*
G36*
G01X629771Y125374D02*
G02Y128374I0J1500D01*
G01X635771D01*
G02Y125374I0J-1500D01*
G01X629771D01*
G37*
G36*
G01X611871Y83474D02*
G02X607871I-2000J0D01*
G01Y89474D01*
G02X611871I2000J0D01*
G01Y83474D01*
G37*
G36*
G01X611771Y98874D02*
G02X607771I-2000J0D01*
G01Y104874D01*
G02X611771I2000J0D01*
G01Y98874D01*
G37*
G36*
G01Y114124D02*
G02X607771I-2000J0D01*
G01Y120124D01*
G02X611771I2000J0D01*
G01Y114124D01*
G37*
G36*
G01X625134Y356500D02*
X633934D01*
Y351900D01*
X625134D01*
Y356500D01*
G37*
G36*
G01X652946Y448121D02*
X664146D01*
Y465521D01*
X652946D01*
Y448121D01*
G37*
G36*
G01X637060Y547943D02*
X632060D01*
X637060Y542943D01*
Y547943D01*
G37*
G36*
G01X681861Y-23326D02*
Y16474D01*
X735461D01*
Y-23326D01*
X681861D01*
G37*
G36*
G01X726011Y18622D02*
G02X723211I-1400J0D01*
G01Y21322D01*
G02X726011I1400J0D01*
G01Y18622D01*
G37*
G36*
G01X694011D02*
G02X691211I-1400J0D01*
G01Y21322D01*
G02X694011I1400J0D01*
G01Y18622D01*
G37*
G36*
G01X727261Y69224D02*
G02X724261I-1500J0D01*
G01Y75224D01*
G02X727261I1500J0D01*
G01Y69224D01*
G37*
G36*
G01X693261D02*
G02X690261I-1500J0D01*
G01Y75224D01*
G02X693261I1500J0D01*
G01Y69224D01*
G37*
G36*
G01X708511Y125374D02*
G02Y128374I0J1500D01*
G01X714511D01*
G02Y125374I0J-1500D01*
G01X708511D01*
G37*
G36*
G01X690611Y83474D02*
G02X686611I-2000J0D01*
G01Y89474D01*
G02X690611I2000J0D01*
G01Y83474D01*
G37*
G36*
G01X690511Y98874D02*
G02X686511I-2000J0D01*
G01Y104874D01*
G02X690511I2000J0D01*
G01Y98874D01*
G37*
G36*
G01Y114124D02*
G02X686511I-2000J0D01*
G01Y120124D01*
G02X690511I2000J0D01*
G01Y114124D01*
G37*
G36*
G01X731722Y492508D02*
Y487508D01*
X736722Y492508D01*
X731722D01*
G37*
G36*
G01X714346Y591449D02*
X710296D01*
X714346Y587399D01*
Y591449D01*
G37*
G36*
G01X760140Y52610D02*
Y55480D01*
X765260D01*
Y52610D01*
X760140D01*
G37*
G36*
G01X812476Y50692D02*
X809606D01*
Y55812D01*
X812476D01*
Y50692D01*
G37*
G36*
G01X809968Y205386D02*
Y199386D01*
X815968Y205386D01*
X809968D01*
G37*
G36*
G01X834700Y387600D02*
X845900D01*
Y405000D01*
X834700D01*
Y387600D01*
G37*
G36*
G01X824064Y486000D02*
Y491000D01*
X819064Y486000D01*
X824064D01*
G37*
G36*
G01X867021Y565300D02*
X866839Y565057D01*
X866778Y564875D01*
X866595Y564631D01*
X866534Y564449D01*
X866352Y564206D01*
X866291Y564023D01*
X866109Y563780D01*
X865987Y563476D01*
X865804Y563233D01*
X865744Y563050D01*
X865561Y562807D01*
X865500Y562624D01*
X865318Y562381D01*
X865257Y562198D01*
X865075Y561955D01*
X864953Y561651D01*
X864770Y561408D01*
X864710Y561226D01*
X864527Y560982D01*
X864467Y560800D01*
X864284Y560556D01*
X864223Y560374D01*
X864041Y560131D01*
X863980Y559948D01*
X863798Y559705D01*
X863676Y559401D01*
X863493Y559157D01*
X863433Y558975D01*
X863250Y558732D01*
X863189Y558550D01*
X863007Y558306D01*
Y558245D01*
X862885Y558124D01*
X862824Y558185D01*
X862763Y559157D01*
X862703Y559219D01*
X862642Y560374D01*
X862581Y560435D01*
X862520Y561651D01*
X862459Y561712D01*
X862399Y562868D01*
X862338Y562928D01*
X862277Y564145D01*
X862216Y564206D01*
X862156Y565361D01*
X862094Y565422D01*
Y565544D01*
X857229D01*
X857290Y565483D01*
X857351Y564875D01*
X857411Y564814D01*
X857472Y564206D01*
X857533Y564145D01*
X857594Y563597D01*
X857655Y563537D01*
X857716Y562928D01*
X857776Y562868D01*
X857837Y562259D01*
X857898Y562198D01*
X857959Y561651D01*
X858020Y561591D01*
X858080Y560982D01*
X858141Y560921D01*
X858202Y560313D01*
X858263Y560252D01*
X858324Y559705D01*
X858385Y559644D01*
X858445Y559036D01*
X858506Y558975D01*
X858567Y558367D01*
X858628Y558306D01*
X858689Y557759D01*
X858750Y557698D01*
X858810Y557090D01*
X858871Y557029D01*
X858932Y556421D01*
X858993Y556360D01*
X859054Y555813D01*
X859115Y555752D01*
X859175Y555144D01*
X859236Y555083D01*
X859297Y554474D01*
X859357Y554414D01*
X859419Y553867D01*
X859479Y553806D01*
X859540Y553197D01*
X859601Y553137D01*
X859662Y552528D01*
X859722Y552467D01*
X859601Y552224D01*
X859419Y551981D01*
X859297Y551677D01*
X859115Y551433D01*
X859054Y551251D01*
X858871Y551008D01*
X858810Y550826D01*
X858628Y550582D01*
X858567Y550400D01*
X858385Y550156D01*
X858263Y549852D01*
X858080Y549609D01*
X858020Y549426D01*
X857837Y549183D01*
X857776Y549001D01*
X857594Y548757D01*
X857533Y548575D01*
X857351Y548332D01*
X857229Y548028D01*
X857046Y547784D01*
X856986Y547602D01*
X856803Y547359D01*
X856743Y547176D01*
X856560Y546933D01*
X856499Y546750D01*
X856317Y546507D01*
X856195Y546203D01*
X856074Y546081D01*
X861182D01*
X861243Y546264D01*
X861426Y546507D01*
X861486Y546690D01*
X861669Y546933D01*
X861730Y547115D01*
X861912Y547359D01*
X862034Y547663D01*
X862216Y547906D01*
X862277Y548089D01*
X862459Y548332D01*
X862520Y548514D01*
X862703Y548757D01*
X862763Y548940D01*
X862946Y549183D01*
X863068Y549487D01*
X863250Y549731D01*
X863311Y549913D01*
X863493Y550156D01*
X863554Y550339D01*
X863737Y550582D01*
X863798Y550765D01*
X863980Y551008D01*
X864041Y551190D01*
X864223Y551433D01*
X864345Y551738D01*
X864527Y551981D01*
X864588Y552163D01*
X864770Y552407D01*
X864831Y552589D01*
X865014Y552832D01*
X865075Y553015D01*
X865257Y553258D01*
X865379Y553562D01*
X865561Y553806D01*
X865622Y553988D01*
X865804Y554231D01*
X865865Y554414D01*
X866048Y554657D01*
X866109Y554839D01*
X866291Y555083D01*
X866413Y555387D01*
X866595Y555630D01*
X866656Y555813D01*
X866839Y556056D01*
X866899Y556238D01*
X867082Y556481D01*
X867143Y556664D01*
X867325Y556907D01*
X867386Y557090D01*
X867568Y557333D01*
X867690Y557637D01*
X867872Y557880D01*
X867933Y558063D01*
X868116Y558306D01*
X868176Y558489D01*
X868359Y558732D01*
X868420Y558914D01*
X868602Y559157D01*
X868724Y559462D01*
X868906Y559705D01*
X868967Y559887D01*
X869150Y560131D01*
X869210Y560313D01*
X869393Y560556D01*
X869454Y560739D01*
X869636Y560982D01*
X869758Y561286D01*
X869940Y561530D01*
X870001Y561712D01*
X870183Y561955D01*
X870244Y562138D01*
X870427Y562381D01*
X870487Y562563D01*
X870670Y562807D01*
X870792Y563111D01*
X870974Y563354D01*
X871035Y563537D01*
X871217Y563780D01*
X871278Y563962D01*
X871461Y564206D01*
X871522Y564388D01*
X871704Y564631D01*
X871765Y564814D01*
X871947Y565057D01*
X872069Y565361D01*
X872191Y565483D01*
Y565604D01*
X867143D01*
X867021Y565300D01*
G37*
G36*
G01X832841Y564996D02*
X832901Y564935D01*
X832962Y564145D01*
X833023Y564084D01*
X833084Y563354D01*
X833144Y563293D01*
X833206Y562563D01*
X833266Y562503D01*
X833327Y561773D01*
X833388Y561712D01*
X833449Y560982D01*
X833509Y560921D01*
X833570Y560192D01*
X833631Y560131D01*
X833692Y559340D01*
X833753Y559279D01*
X833814Y558550D01*
X833874Y558489D01*
X833935Y557759D01*
X833996Y557698D01*
X834057Y556968D01*
X834118Y556907D01*
X834178Y556178D01*
X834239Y556117D01*
X834300Y555387D01*
X834361Y555326D01*
X834422Y554535D01*
X834483Y554474D01*
X834543Y553745D01*
X834604Y553684D01*
X834665Y552954D01*
X834726Y552893D01*
Y552589D01*
X839226D01*
X839348Y552832D01*
X839531Y553076D01*
X839652Y553380D01*
X839835Y553623D01*
X839956Y553927D01*
X840139Y554170D01*
X840261Y554474D01*
X840443Y554718D01*
X840565Y555022D01*
X840747Y555265D01*
X840869Y555569D01*
X841051Y555813D01*
X841112Y555995D01*
X841294Y556238D01*
X841416Y556543D01*
X841598Y556786D01*
X841720Y557090D01*
X841903Y557333D01*
X842024Y557637D01*
X842207Y557880D01*
X842328Y558185D01*
X842511Y558428D01*
X842632Y558732D01*
X842815Y558975D01*
X842876Y559157D01*
X843058Y559401D01*
X843180Y559705D01*
X843362Y559948D01*
X843545Y560313D01*
X843606Y560252D01*
X843666Y559766D01*
X843727Y559036D01*
X843788Y558671D01*
X843849Y557820D01*
X843909Y557759D01*
X843970Y556664D01*
X844031Y556603D01*
X844092Y555509D01*
X844153Y555448D01*
X844214Y554292D01*
X844274Y554231D01*
X844335Y553137D01*
X844396Y553076D01*
Y552589D01*
X848836D01*
X848957Y552832D01*
X849140Y553076D01*
X849201Y553258D01*
X849383Y553502D01*
X849444Y553684D01*
X849627Y553927D01*
X849687Y554109D01*
X849870Y554353D01*
X849931Y554535D01*
X850113Y554779D01*
X850174Y554961D01*
X850356Y555204D01*
X850417Y555387D01*
X850600Y555630D01*
X850661Y555813D01*
X850843Y556056D01*
X850904Y556238D01*
X851086Y556481D01*
X851208Y556786D01*
X851391Y557029D01*
X851451Y557211D01*
X851633Y557455D01*
X851694Y557637D01*
X851877Y557880D01*
X851938Y558063D01*
X852120Y558306D01*
X852181Y558489D01*
X852363Y558732D01*
X852424Y558914D01*
X852607Y559157D01*
X852668Y559340D01*
X852850Y559583D01*
X852911Y559766D01*
X853093Y560009D01*
X853154Y560192D01*
X853337Y560435D01*
X853397Y560617D01*
X853580Y560861D01*
X853702Y561165D01*
X853884Y561408D01*
X853945Y561591D01*
X854127Y561834D01*
X854188Y562016D01*
X854370Y562259D01*
X854431Y562442D01*
X854614Y562685D01*
X854674Y562868D01*
X854857Y563111D01*
X854918Y563293D01*
X855100Y563537D01*
X855161Y563719D01*
X855344Y563962D01*
X855404Y564145D01*
X855587Y564388D01*
X855648Y564570D01*
X855830Y564814D01*
X855952Y565118D01*
X856134Y565361D01*
X856195Y565483D01*
Y565544D01*
X851147D01*
X850904Y565057D01*
X850843Y564814D01*
X850661Y564510D01*
X850600Y564267D01*
X850478Y564084D01*
X850417Y563841D01*
X850235Y563537D01*
X850174Y563293D01*
X849991Y562989D01*
X849931Y562746D01*
X849809Y562563D01*
X849748Y562320D01*
X849566Y562016D01*
X849505Y561773D01*
X849322Y561469D01*
X849262Y561226D01*
X849140Y561043D01*
X849079Y560800D01*
X848897Y560496D01*
X848836Y560252D01*
X848654Y559948D01*
X848593Y559705D01*
X848471Y559522D01*
X848410Y559279D01*
X848228Y558975D01*
X848167Y558732D01*
X847985Y558428D01*
X847924Y558185D01*
X847802Y558002D01*
X847741Y557759D01*
X847559Y557455D01*
X847498Y557515D01*
X847437Y558489D01*
X847376Y558854D01*
X847315Y559827D01*
X847255Y560192D01*
X847194Y561165D01*
X847133Y561530D01*
X847072Y562503D01*
X847011Y562868D01*
X846950Y563841D01*
X846890Y564206D01*
X846829Y565179D01*
X846768Y565544D01*
X842267D01*
Y565483D01*
X842085Y565239D01*
X841903Y564814D01*
X841720Y564570D01*
X841538Y564145D01*
X841355Y563902D01*
X841173Y563476D01*
X840990Y563233D01*
X840869Y562928D01*
X840686Y562685D01*
X840504Y562259D01*
X840321Y562016D01*
X840139Y561591D01*
X839956Y561347D01*
X839774Y560921D01*
X839591Y560678D01*
X839470Y560374D01*
X839287Y560131D01*
X839105Y559705D01*
X838922Y559462D01*
X838740Y559036D01*
X838557Y558793D01*
X838375Y558367D01*
X838193Y558124D01*
X838071Y557820D01*
X837889Y557576D01*
X837767Y557333D01*
X837706Y557394D01*
X837645Y558732D01*
X837584Y559462D01*
X837524Y560800D01*
X837463Y561530D01*
X837402Y562868D01*
X837341Y563719D01*
X837280Y564935D01*
X837220Y565544D01*
X832780D01*
X832841Y564996D01*
G37*
G36*
G01X829921Y571991D02*
X829435Y571930D01*
X829252Y571808D01*
X829009Y571747D01*
X828766Y571626D01*
X828461Y571382D01*
X828401D01*
X827732Y570652D01*
Y570592D01*
X827549Y570348D01*
X827428Y570105D01*
X827367Y569801D01*
X827306Y569740D01*
X827245Y569132D01*
X827306Y568341D01*
X827367Y568280D01*
X827428Y568037D01*
X827610Y567794D01*
Y567733D01*
X828157Y567246D01*
X828218D01*
X828340Y567125D01*
X828583Y567064D01*
X828644Y567003D01*
X829131Y566943D01*
X829191Y566881D01*
X830165Y566943D01*
X830225Y567003D01*
X830530Y567064D01*
X830590Y567125D01*
X830833Y567186D01*
X831077Y567307D01*
X831442Y567611D01*
X831502D01*
X832172Y568341D01*
X832232Y568524D01*
X832415Y568767D01*
X832476Y569010D01*
X832537Y569071D01*
X832597Y569558D01*
X832658Y569619D01*
X832597Y570531D01*
X832537Y570592D01*
X832476Y570835D01*
X832354Y571078D01*
X831928Y571565D01*
X831685Y571747D01*
X831320Y571930D01*
X830894Y571991D01*
X830833Y572051D01*
X829982D01*
X829921Y571991D01*
G37*
G36*
G01X826394Y565179D02*
X826333Y565118D01*
X826272Y564631D01*
X826211Y564570D01*
X826150Y564084D01*
X826090Y564023D01*
X826029Y563476D01*
X825968Y563415D01*
X825907Y562928D01*
X825846Y562868D01*
X825785Y562381D01*
X825725Y562320D01*
X825664Y561773D01*
X825603Y561712D01*
X825542Y561226D01*
X825481Y561165D01*
X825420Y560678D01*
X825360Y560617D01*
X825299Y560070D01*
X825238Y560009D01*
X825177Y559522D01*
X825117Y559462D01*
X825056Y558975D01*
X824995Y558914D01*
X824934Y558367D01*
X824873Y558306D01*
X824812Y557820D01*
X824752Y557759D01*
X824691Y557272D01*
X824630Y557211D01*
X824569Y556664D01*
X824508Y556603D01*
X824448Y556117D01*
X824387Y556056D01*
X824326Y555569D01*
X824265Y555509D01*
X824204Y554961D01*
X824143Y554900D01*
X824083Y554414D01*
X824022Y554353D01*
X823961Y553867D01*
X823900Y553806D01*
X823839Y553258D01*
X823778Y553197D01*
X823718Y552711D01*
X823657Y552650D01*
Y552589D01*
X829009D01*
X829070Y552954D01*
X829131Y553015D01*
X829191Y553502D01*
X829252Y553562D01*
X829313Y554109D01*
X829374Y554170D01*
X829435Y554657D01*
X829495Y554718D01*
X829556Y555204D01*
X829617Y555265D01*
X829678Y555813D01*
X829739Y555873D01*
X829800Y556360D01*
X829860Y556421D01*
X829921Y556907D01*
X829982Y556968D01*
X830043Y557515D01*
X830104Y557576D01*
X830165Y558063D01*
X830225Y558124D01*
X830286Y558610D01*
X830347Y558671D01*
X830408Y559219D01*
X830469Y559279D01*
X830530Y559766D01*
X830590Y559827D01*
X830651Y560313D01*
X830712Y560374D01*
X830773Y560861D01*
X830833Y560921D01*
X830894Y561469D01*
X830955Y561530D01*
X831016Y562016D01*
X831077Y562077D01*
X831137Y562563D01*
X831198Y562624D01*
X831259Y563172D01*
X831320Y563233D01*
X831381Y563719D01*
X831442Y563780D01*
X831502Y564267D01*
X831563Y564327D01*
X831624Y564875D01*
X831685Y564935D01*
X831746Y565422D01*
X831807Y565483D01*
Y565544D01*
X826454D01*
X826394Y565179D01*
G37*
G36*
G01X802127Y564814D02*
X802188Y564327D01*
X802248Y564267D01*
X802309Y563537D01*
X802370Y563476D01*
X802431Y562685D01*
X802492Y562624D01*
X802553Y561894D01*
X802613Y561834D01*
X802674Y561104D01*
X802735Y561043D01*
X802796Y560313D01*
X802857Y560252D01*
X802917Y559522D01*
X802978Y559462D01*
X803039Y558671D01*
X803100Y558610D01*
X803161Y557880D01*
X803222Y557820D01*
X803282Y557090D01*
X803343Y557029D01*
X803404Y556299D01*
X803465Y556238D01*
X803526Y555509D01*
X803587Y555448D01*
X803647Y554718D01*
X803708Y554657D01*
X803769Y553867D01*
X803830Y553806D01*
X803891Y553076D01*
X803952Y553015D01*
X804012Y552589D01*
X808452D01*
X808635Y552832D01*
X808756Y553137D01*
X808939Y553380D01*
X809060Y553684D01*
X809243Y553927D01*
X809304Y554109D01*
X809486Y554353D01*
X809607Y554657D01*
X809790Y554900D01*
X809912Y555204D01*
X810094Y555448D01*
X810216Y555752D01*
X810398Y555995D01*
X810459Y556178D01*
X810641Y556421D01*
X810763Y556725D01*
X810946Y556968D01*
X811067Y557272D01*
X811250Y557515D01*
X811371Y557820D01*
X811554Y558063D01*
X811676Y558367D01*
X811858Y558610D01*
X811919Y558793D01*
X812101Y559036D01*
X812223Y559340D01*
X812405Y559583D01*
X812527Y559887D01*
X812709Y560131D01*
Y560192D01*
X812831Y560313D01*
X812892Y560252D01*
X812953Y559157D01*
X813013Y559097D01*
X813074Y558002D01*
X813135Y557941D01*
X813196Y556846D01*
X813257Y556786D01*
X813318Y555630D01*
X813378Y555569D01*
X813439Y554474D01*
X813500Y554414D01*
X813561Y553319D01*
X813622Y553258D01*
X813682Y552589D01*
X818122D01*
X818244Y552893D01*
X818426Y553137D01*
X818487Y553319D01*
X818670Y553562D01*
X818730Y553745D01*
X818913Y553988D01*
X818974Y554170D01*
X819156Y554414D01*
X819278Y554718D01*
X819460Y554961D01*
X819521Y555144D01*
X819704Y555387D01*
X819765Y555569D01*
X819947Y555813D01*
X820007Y555995D01*
X820190Y556238D01*
X820251Y556421D01*
X820433Y556664D01*
X820494Y556846D01*
X820677Y557090D01*
X820737Y557272D01*
X820920Y557515D01*
X820981Y557698D01*
X821163Y557941D01*
X821224Y558124D01*
X821407Y558367D01*
X821528Y558671D01*
X821711Y558914D01*
X821771Y559097D01*
X821954Y559340D01*
X822015Y559522D01*
X822197Y559766D01*
X822258Y559948D01*
X822441Y560192D01*
X822501Y560374D01*
X822684Y560617D01*
X822744Y560800D01*
X822927Y561043D01*
X822988Y561226D01*
X823170Y561469D01*
X823231Y561651D01*
X823413Y561894D01*
X823474Y562077D01*
X823657Y562320D01*
X823778Y562624D01*
X823961Y562868D01*
X824022Y563050D01*
X824204Y563293D01*
X824265Y563476D01*
X824448Y563719D01*
X824508Y563902D01*
X824691Y564145D01*
X824752Y564327D01*
X824934Y564570D01*
X824995Y564753D01*
X825177Y564996D01*
X825238Y565179D01*
X825420Y565422D01*
Y565483D01*
X825481Y565544D01*
X820372D01*
X820312Y565300D01*
X820069Y564875D01*
X820007Y564631D01*
X819825Y564327D01*
X819765Y564084D01*
X819643Y563902D01*
X819582Y563658D01*
X819400Y563354D01*
X819339Y563111D01*
X819156Y562807D01*
X819095Y562563D01*
X818974Y562381D01*
X818913Y562138D01*
X818730Y561834D01*
X818670Y561591D01*
X818487Y561286D01*
X818426Y561043D01*
X818305Y560861D01*
X818244Y560617D01*
X818061Y560313D01*
X818001Y560070D01*
X817818Y559766D01*
X817757Y559522D01*
X817636Y559340D01*
X817575Y559097D01*
X817393Y558793D01*
X817331Y558550D01*
X817149Y558245D01*
X817088Y558002D01*
X816967Y557820D01*
X816906Y557576D01*
X816784Y557455D01*
X816724Y557515D01*
X816663Y558732D01*
X816602Y558793D01*
X816541Y560070D01*
X816480Y560131D01*
X816419Y561408D01*
X816359Y561469D01*
X816298Y562807D01*
X816237Y562868D01*
X816176Y564145D01*
X816115Y564206D01*
X816054Y565483D01*
X815994Y565544D01*
X811493D01*
X811311Y565118D01*
X811128Y564875D01*
X810946Y564449D01*
X810763Y564206D01*
X810581Y563780D01*
X810398Y563537D01*
X810216Y563111D01*
X810033Y562868D01*
X809912Y562563D01*
X809729Y562320D01*
X809547Y561894D01*
X809364Y561651D01*
X809182Y561226D01*
X808999Y560982D01*
X808878Y560678D01*
X808695Y560435D01*
X808513Y560009D01*
X808330Y559766D01*
X808148Y559340D01*
X807965Y559097D01*
X807783Y558671D01*
X807600Y558428D01*
X807479Y558124D01*
X807296Y557880D01*
X807114Y557455D01*
X806993Y557333D01*
X806931Y557394D01*
X806871Y559340D01*
X806810Y559401D01*
X806749Y561408D01*
X806688Y561469D01*
X806628Y563476D01*
X806567Y563537D01*
X806506Y565544D01*
X802005D01*
X802127Y564814D01*
G37*
G36*
G01X886111Y597400D02*
G02I-11811J0D01*
G37*
G36*
G01X837100Y591300D02*
Y602100D01*
X838900D01*
Y591300D01*
X837100D01*
G37*
G36*
G01X840700D02*
Y602100D01*
X842500D01*
Y591300D01*
X840700D01*
G37*
G36*
G01X831700D02*
Y602100D01*
X833500D01*
Y591300D01*
X831700D01*
G37*
G36*
G01X842500Y600300D02*
Y602100D01*
X847000D01*
Y600300D01*
X842500D01*
G37*
G36*
G01X833500Y595800D02*
Y597600D01*
X837100D01*
Y595800D01*
X833500D01*
G37*
G36*
G01X842500D02*
Y597600D01*
X845200D01*
Y595800D01*
X842500D01*
G37*
G36*
G01X895050Y225000D02*
X890050D01*
X892550Y227500D01*
X895050Y225000D01*
G37*
G36*
G01X867100Y510600D02*
Y505600D01*
X887100D01*
Y510600D01*
X867100D01*
G37*
G36*
G01X904485Y568037D02*
X904607Y567794D01*
X904060D01*
X903999Y567855D01*
X903817Y568280D01*
X903634Y568524D01*
Y568645D01*
X903452Y568706D01*
X903026Y568767D01*
Y567794D01*
X902600D01*
Y569590D01*
X903026D01*
Y569132D01*
X903330D01*
X903938Y569193D01*
X903999Y569375D01*
X903938Y569740D01*
X903756D01*
X903695Y569801D01*
X903026D01*
Y569591D01*
X902600D01*
Y570166D01*
X903756D01*
X904120Y570105D01*
X904364Y569922D01*
X904425Y569680D01*
X904485Y569619D01*
X904425Y569254D01*
X904181Y568950D01*
X903938Y568889D01*
X903877Y568828D01*
X903999Y568706D01*
X904060D01*
X904120Y568645D01*
X904242Y568463D01*
X904303Y568280D01*
X904485Y568037D01*
G37*
G36*
G01X904972Y567307D02*
X904668Y567064D01*
X904425Y567003D01*
X904242Y566881D01*
X903208Y566821D01*
X903148Y566881D01*
X902783Y566943D01*
X902418Y567125D01*
X902174Y567307D01*
X901749Y567794D01*
X901506Y568280D01*
X901444Y569193D01*
X901445Y569199D01*
X901830D01*
X901809Y569010D01*
X901870Y568402D01*
X901992Y568159D01*
X902235Y567855D01*
Y567794D01*
X902661Y567429D01*
X902904Y567307D01*
X903330Y567246D01*
X903391Y567186D01*
X904120Y567246D01*
X904181Y567307D01*
X904425Y567368D01*
X904790Y567672D01*
X905215Y568159D01*
X905276Y568402D01*
X905337Y568463D01*
X905398Y568889D01*
X905337Y569497D01*
X905276Y569558D01*
X905215Y569801D01*
X904911Y570166D01*
Y570287D01*
X904790D01*
X904425Y570592D01*
X904303D01*
X904242Y570652D01*
X903877Y570713D01*
X903817Y570774D01*
X903087Y570713D01*
X903026Y570652D01*
X902783Y570592D01*
X902539Y570409D01*
X902478D01*
X902053Y569922D01*
X901870Y569558D01*
X901830Y569200D01*
X901445D01*
X901506Y569680D01*
X901749Y570166D01*
X901931Y570409D01*
X902418Y570835D01*
X902783Y571017D01*
X903148Y571078D01*
X903208Y571139D01*
X903999D01*
X904060Y571078D01*
X904425Y571017D01*
X904668Y570896D01*
X904972Y570652D01*
X905033D01*
X905459Y570166D01*
X905580Y569922D01*
X905641Y569680D01*
X905702Y569619D01*
X905763Y568524D01*
X905702Y568463D01*
X905641Y568159D01*
X905459Y567794D01*
X905033Y567307D01*
X904972D01*
G37*
G36*
G01X897187Y565787D02*
X896457Y565726D01*
X896396Y565665D01*
X895971Y565604D01*
X895910Y565544D01*
X895606Y565483D01*
X895424Y565361D01*
X895180Y565300D01*
X894572Y564996D01*
X894268Y564753D01*
X894207D01*
X893842Y564449D01*
X893781D01*
X892869Y563537D01*
X892808Y563597D01*
X892869Y564023D01*
X892930Y564084D01*
X892991Y564570D01*
X893052Y564631D01*
X893112Y565118D01*
X893173Y565179D01*
X893234Y565483D01*
Y565544D01*
X888612D01*
X888551Y565483D01*
X888490Y564996D01*
X888429Y564935D01*
X888369Y564388D01*
X888307Y564327D01*
X888247Y563841D01*
X888186Y563780D01*
X888125Y563293D01*
X888064Y563233D01*
X888004Y562685D01*
X887943Y562624D01*
X887882Y562138D01*
X887821Y562077D01*
X887760Y561591D01*
X887699Y561530D01*
X887639Y561043D01*
X887578Y560982D01*
X887517Y560435D01*
X887456Y560374D01*
X887395Y559887D01*
X887335Y559827D01*
X887274Y559340D01*
X887213Y559279D01*
X887152Y558732D01*
X887091Y558671D01*
X887030Y558185D01*
X886970Y558124D01*
X886909Y557637D01*
X886848Y557576D01*
X886787Y557029D01*
X886726Y556968D01*
X886665Y556481D01*
X886605Y556421D01*
X886544Y555934D01*
X886483Y555873D01*
X886422Y555387D01*
X886361Y555326D01*
X886300Y554779D01*
X886240Y554718D01*
X886179Y554231D01*
X886118Y554170D01*
X886057Y553684D01*
X885996Y553623D01*
X885936Y553076D01*
X885875Y553015D01*
X885814Y552589D01*
X890801D01*
X890862Y552954D01*
X890923Y553015D01*
X890983Y553562D01*
X891044Y553623D01*
X891105Y554109D01*
X891166Y554170D01*
X891227Y554657D01*
X891288Y554718D01*
X891348Y555204D01*
X891409Y555265D01*
X891470Y555752D01*
X891531Y555813D01*
X891592Y556360D01*
X891653Y556421D01*
X891713Y556907D01*
X891774Y556968D01*
X891835Y557455D01*
X891896Y557515D01*
X891957Y558002D01*
X892018Y558063D01*
X892078Y558550D01*
X892139Y558610D01*
X892200Y559036D01*
X892261Y559097D01*
X892322Y559401D01*
X892383Y559462D01*
X892443Y559705D01*
X892504Y559766D01*
X892565Y560009D01*
X892626Y560070D01*
X892687Y560313D01*
X892869Y560556D01*
X892930Y560739D01*
X893173Y561043D01*
Y561104D01*
X893599Y561591D01*
X893660D01*
X894085Y561955D01*
X894450Y562138D01*
X894937Y562198D01*
X894998Y562259D01*
X895606Y562198D01*
X895849Y562016D01*
X895971D01*
Y561894D01*
X896093Y561773D01*
X896153Y561408D01*
X896214Y561347D01*
X896153Y560617D01*
X896093Y560556D01*
X896031Y559948D01*
X895971Y559887D01*
X895910Y559340D01*
X895849Y559279D01*
X895788Y558793D01*
X895728Y558732D01*
X895667Y558185D01*
X895606Y558124D01*
X895545Y557637D01*
X895484Y557576D01*
X895424Y557090D01*
X895363Y557029D01*
X895302Y556481D01*
X895241Y556421D01*
X895180Y555934D01*
X895119Y555873D01*
X895059Y555326D01*
X894998Y555265D01*
X894937Y554779D01*
X894876Y554718D01*
X894815Y554231D01*
X894754Y554170D01*
X894694Y553623D01*
X894633Y553562D01*
X894572Y553076D01*
X894511Y553015D01*
X894450Y552589D01*
X899437D01*
X899498Y553076D01*
X899559Y553137D01*
X899620Y553623D01*
X899681Y553684D01*
X899742Y554231D01*
X899802Y554292D01*
X899863Y554779D01*
X899924Y554839D01*
X899985Y555387D01*
X900046Y555448D01*
X900107Y555934D01*
X900167Y555995D01*
X900228Y556481D01*
X900289Y556543D01*
X900350Y557090D01*
X900411Y557150D01*
X900471Y557637D01*
X900532Y557698D01*
X900593Y558245D01*
X900654Y558306D01*
X900715Y558793D01*
X900776Y558854D01*
X900836Y559401D01*
X900897Y559462D01*
X900958Y559948D01*
X901019Y560009D01*
X901080Y560556D01*
X901141Y560617D01*
X901201Y561226D01*
X901262Y561286D01*
X901323Y562016D01*
X901384Y562077D01*
X901323Y563658D01*
X901262Y563719D01*
X901201Y563962D01*
X901141Y564023D01*
Y564145D01*
X900958Y564388D01*
Y564449D01*
X900532Y564935D01*
X900046Y565361D01*
X899559Y565604D01*
X899255Y565665D01*
X899194Y565726D01*
X898586Y565787D01*
X898525Y565848D01*
X897248D01*
X897187Y565787D01*
G37*
G36*
G01X881739D02*
X881009Y565726D01*
X880948Y565665D01*
X880583Y565604D01*
X880523Y565544D01*
X880219Y565483D01*
X880158Y565422D01*
X879915Y565361D01*
X879854Y565300D01*
X879611Y565239D01*
X879367Y565118D01*
X879124Y564935D01*
X879063D01*
X878759Y564692D01*
X878698D01*
X878212Y564267D01*
X878151D01*
X877482Y563597D01*
X877421Y563658D01*
X877482Y564145D01*
X877543Y564206D01*
X877604Y564692D01*
X877664Y564753D01*
X877725Y565239D01*
X877786Y565300D01*
Y565544D01*
X873164D01*
X873103Y565118D01*
X873042Y565057D01*
X872981Y564510D01*
X872920Y564449D01*
X872859Y563962D01*
X872799Y563902D01*
X872738Y563415D01*
X872677Y563354D01*
X872616Y562807D01*
X872556Y562746D01*
X872494Y562259D01*
X872434Y562198D01*
X872373Y561712D01*
X872312Y561651D01*
X872251Y561165D01*
X872191Y561104D01*
X872130Y560556D01*
X872069Y560496D01*
X872008Y560009D01*
X871947Y559948D01*
X871887Y559462D01*
X871826Y559401D01*
X871765Y558854D01*
X871704Y558793D01*
X871643Y558306D01*
X871582Y558245D01*
X871522Y557759D01*
X871461Y557698D01*
X871400Y557150D01*
X871339Y557090D01*
X871278Y556603D01*
X871217Y556543D01*
X871157Y556056D01*
X871096Y555995D01*
X871035Y555509D01*
X870974Y555448D01*
X870913Y554900D01*
X870852Y554839D01*
X870792Y554353D01*
X870731Y554292D01*
X870670Y553806D01*
X870609Y553745D01*
X870548Y553197D01*
X870487Y553137D01*
X870427Y552650D01*
X870366Y552589D01*
X875414D01*
X875475Y553137D01*
X875535Y553197D01*
X875596Y553684D01*
X875657Y553745D01*
X875718Y554231D01*
X875779Y554292D01*
X875840Y554779D01*
X875900Y554839D01*
X875961Y555326D01*
X876022Y555387D01*
X876083Y555934D01*
X876144Y555995D01*
X876205Y556481D01*
X876265Y556543D01*
X876326Y557029D01*
X876387Y557090D01*
X876448Y557576D01*
X876509Y557637D01*
X876570Y558124D01*
X876630Y558185D01*
X876691Y558671D01*
X876752Y558732D01*
X876813Y559097D01*
X876874Y559157D01*
X876934Y559462D01*
X876995Y559522D01*
X877056Y559827D01*
X877482Y560678D01*
X877725Y560982D01*
Y561043D01*
X878272Y561651D01*
X878576Y561894D01*
X879063Y562138D01*
X879550Y562198D01*
X879611Y562259D01*
X880219Y562198D01*
X880583Y561894D01*
X880705Y561712D01*
X880766Y561226D01*
X880705Y560435D01*
X880644Y560374D01*
X880583Y559827D01*
X880523Y559766D01*
X880462Y559219D01*
X880401Y559157D01*
X880340Y558610D01*
X880280Y558550D01*
X880219Y558063D01*
X880158Y558002D01*
X880097Y557455D01*
X880036Y557394D01*
X879975Y556907D01*
X879915Y556846D01*
X879854Y556360D01*
X879793Y556299D01*
X879732Y555752D01*
X879671Y555691D01*
X879611Y555204D01*
X879550Y555144D01*
X879489Y554596D01*
X879428Y554535D01*
X879367Y554049D01*
X879306Y553988D01*
X879246Y553502D01*
X879185Y553441D01*
X879124Y552893D01*
X879063Y552832D01*
Y552589D01*
X883989D01*
X884050Y552893D01*
X884111Y552954D01*
X884172Y553502D01*
X884233Y553562D01*
X884294Y554049D01*
X884354Y554109D01*
X884415Y554657D01*
X884476Y554718D01*
X884537Y555204D01*
X884598Y555265D01*
X884658Y555752D01*
X884719Y555813D01*
X884780Y556360D01*
X884841Y556421D01*
X884902Y556907D01*
X884963Y556968D01*
X885023Y557515D01*
X885084Y557576D01*
X885145Y558063D01*
X885206Y558124D01*
X885267Y558610D01*
X885328Y558671D01*
X885388Y559219D01*
X885449Y559279D01*
X885510Y559766D01*
X885571Y559827D01*
X885631Y560374D01*
X885693Y560435D01*
X885753Y561043D01*
X885814Y561104D01*
X885875Y561773D01*
X885936Y561834D01*
X885996Y562807D01*
X885936Y563537D01*
X885875Y563597D01*
X885814Y563902D01*
X885753Y563962D01*
X885693Y564206D01*
X885510Y564449D01*
Y564510D01*
X885084Y564996D01*
X884658Y565361D01*
X884294Y565544D01*
X884050Y565604D01*
X883989Y565665D01*
X883564Y565726D01*
X883503Y565787D01*
X882530Y565848D01*
X881800D01*
X881739Y565787D01*
G37*
%LPC*%
G75*
G36*
G01X874300Y586770D02*
X876375Y586975D01*
X878370Y587580D01*
X880205Y588560D01*
X881274Y589440D01*
X878834Y591880D01*
X878404D01*
X878306Y591888D01*
X877605Y592100D01*
X877280Y592275D01*
Y591880D01*
X875680D01*
Y595035D01*
X872963Y597752D01*
X872555Y597420D01*
X871919Y597079D01*
X871263Y596880D01*
X868705D01*
Y591880D01*
X867135D01*
Y603580D01*
X866340Y604374D01*
X865460Y603305D01*
X864480Y601470D01*
X863875Y599475D01*
X863670Y597400D01*
X863875Y595325D01*
X864480Y593330D01*
X865460Y591495D01*
X866785Y589885D01*
X868395Y588560D01*
X870230Y587580D01*
X872225Y586975D01*
X874300Y586770D01*
G37*
G36*
G01X882259Y590425D02*
X883140Y591495D01*
X884120Y593330D01*
X884725Y595325D01*
X884930Y597400D01*
X884725Y599475D01*
X884120Y601470D01*
X883140Y603305D01*
X881815Y604915D01*
X880205Y606240D01*
X878370Y607220D01*
X876375Y607825D01*
X874300Y608030D01*
X872225Y607825D01*
X870230Y607220D01*
X868395Y606240D01*
X867324Y605358D01*
X868566Y604115D01*
X870955D01*
X871229Y604080D01*
X871920Y603870D01*
X872555Y603530D01*
X873115Y603075D01*
X873570Y602515D01*
X873910Y601880D01*
X874120Y601190D01*
X874190Y600475D01*
X874120Y599760D01*
X873910Y599070D01*
X873806Y598877D01*
X875680Y597003D01*
Y603920D01*
X877280D01*
Y599865D01*
X877605Y600040D01*
X878300Y600250D01*
X879025Y600320D01*
X879750Y600250D01*
X880445Y600040D01*
X881085Y599695D01*
X881645Y599235D01*
X882105Y598675D01*
X882450Y598035D01*
X882659Y597342D01*
X882730Y596615D01*
Y595525D01*
X882660Y594800D01*
X882450Y594105D01*
X882105Y593465D01*
X881645Y592905D01*
X881085Y592445D01*
X880535Y592149D01*
X882259Y590425D01*
G37*
G36*
G01X879335Y593349D02*
X879455Y593360D01*
X879871Y593490D01*
X880253Y593692D01*
X880589Y593969D01*
X880862Y594303D01*
X881063Y594684D01*
X881191Y595098D01*
X881230Y595525D01*
Y596615D01*
X881192Y597045D01*
X881060Y597460D01*
X880860Y597840D01*
X880585Y598175D01*
X880250Y598451D01*
X879868Y598651D01*
X879453Y598780D01*
X879026Y598820D01*
X878596Y598780D01*
X878180Y598650D01*
X877800Y598450D01*
X877465Y598175D01*
X877280Y597950D01*
Y595403D01*
X879335Y593349D01*
G37*
G36*
G01X868705Y598455D02*
X871315D01*
X871345Y598465D01*
X871725Y598665D01*
X871907Y598808D01*
X868705Y602010D01*
Y598455D01*
G37*
G36*
G01X872646Y600036D02*
X872650Y600050D01*
X872690Y600475D01*
X872650Y600900D01*
X872525Y601305D01*
X872325Y601685D01*
X872055Y602015D01*
X871725Y602285D01*
X871345Y602485D01*
X871260Y602515D01*
X870166D01*
X872646Y600036D01*
G37*
G54D22*
X629921Y9874D03*
X708661D03*
%LPD*%
G75*
G54D10*
X601500Y363600D03*
G54D20*
G01X13215Y-125739D02*
X14089Y-124864D01*
X14744Y-123406D01*
X15181Y-121363D01*
X14744Y-119614D01*
X13871Y-118447D01*
X12342Y-117572D01*
X6447D01*
Y-135072D01*
X13652D01*
X15181Y-133906D01*
X16054Y-132155D01*
X16491Y-130114D01*
X16054Y-128072D01*
X14744Y-126322D01*
X13215Y-125739D01*
X6447D01*
G01X25912Y-135072D02*
Y-123406D01*
G01Y-125739D02*
X27004Y-124572D01*
X28096Y-123697D01*
X29624Y-123406D01*
X30715Y-123697D01*
X32026Y-124572D01*
G01X41884Y-140322D02*
X43194Y-140905D01*
X44941Y-140322D01*
X46032Y-139156D01*
X46906Y-137697D01*
X48215Y-133031D01*
X51054Y-123406D01*
G01X44067D02*
X48215Y-133031D01*
G01X67462Y-124864D02*
X65934Y-123697D01*
X64624Y-123406D01*
X62877Y-123989D01*
X61567Y-125155D01*
X60694Y-127197D01*
X60475Y-129239D01*
X60694Y-131281D01*
X61567Y-133031D01*
X62877Y-134489D01*
X64624Y-135072D01*
X66152Y-134489D01*
X67462Y-133322D01*
G01X78194Y-127197D02*
X85181D01*
X84526Y-125155D01*
X83434Y-123989D01*
X81906Y-123406D01*
X80377Y-123697D01*
X79067Y-124572D01*
X78194Y-126614D01*
X77757Y-128364D01*
Y-130114D01*
X78194Y-131864D01*
X79286Y-133614D01*
X80596Y-134780D01*
X82124Y-135072D01*
X83652Y-134489D01*
X85181Y-132739D01*
G01X121272Y-119031D02*
X119962Y-118155D01*
X118434Y-117572D01*
X116687D01*
X114722Y-118447D01*
X113194Y-119905D01*
X112102Y-121656D01*
X111229Y-124572D01*
X111010Y-127197D01*
X111447Y-129822D01*
X112102Y-131572D01*
X113412Y-133322D01*
X114941Y-134489D01*
X116469Y-135072D01*
X117997D01*
X119526Y-134489D01*
X120836Y-133614D01*
X121928Y-132448D01*
G01X137899Y-135072D02*
Y-123406D01*
G01Y-125447D02*
X137026Y-124281D01*
X135715Y-123697D01*
X134187Y-123406D01*
X132659Y-123989D01*
X131349Y-125155D01*
X130475Y-126905D01*
X130039Y-129239D01*
X130475Y-131572D01*
X131349Y-133322D01*
X132659Y-134489D01*
X134187Y-135072D01*
X135715Y-134780D01*
X137026Y-133906D01*
X137899Y-132739D01*
G01X147757Y-135072D02*
Y-123406D01*
G01Y-126322D02*
X148631Y-124864D01*
X149941Y-123697D01*
X151687Y-123406D01*
X153215Y-123697D01*
X154526Y-124864D01*
X155181Y-126905D01*
Y-135072D01*
G01X164384Y-140322D02*
X165694Y-140905D01*
X167441Y-140322D01*
X168532Y-139156D01*
X169406Y-137697D01*
X170715Y-133031D01*
X173554Y-123406D01*
G01X166567D02*
X170715Y-133031D01*
G01X186469Y-135072D02*
X185159Y-134780D01*
X183849Y-133614D01*
X182975Y-131572D01*
X182539Y-129239D01*
X182975Y-126905D01*
X183849Y-124864D01*
X185159Y-123697D01*
X186469Y-123406D01*
X187779Y-123697D01*
X189089Y-124864D01*
X189962Y-126905D01*
X190181Y-129239D01*
X189962Y-131572D01*
X189089Y-133614D01*
X187779Y-134780D01*
X186469Y-135072D01*
G01X200257D02*
Y-123406D01*
G01Y-126322D02*
X201131Y-124864D01*
X202441Y-123697D01*
X204187Y-123406D01*
X205715Y-123697D01*
X207026Y-124864D01*
X207681Y-126905D01*
Y-135072D01*
G01X236349Y-117572D02*
X241589D01*
G01X238969D02*
Y-135072D01*
G01X236349D02*
X241589D01*
G01X256469D02*
X254722Y-134780D01*
X253194Y-133614D01*
X251884Y-131864D01*
X251010Y-129822D01*
X250574Y-127489D01*
Y-125155D01*
X251010Y-122822D01*
X251884Y-120780D01*
X253194Y-119031D01*
X254722Y-117864D01*
X256469Y-117572D01*
X258215Y-117864D01*
X259744Y-119031D01*
X261054Y-120780D01*
X261928Y-122822D01*
X262364Y-125155D01*
Y-127489D01*
X261928Y-129822D01*
X261054Y-131864D01*
X259744Y-133614D01*
X258215Y-134780D01*
X256469Y-135072D01*
G01X268292D02*
Y-117572D01*
X273969Y-132155D01*
X279646Y-117572D01*
Y-135072D01*
G01X307877Y-140905D02*
X305694Y-137989D01*
X304602Y-135072D01*
Y-123406D01*
X305694Y-120489D01*
X307877Y-117572D01*
G01X321010Y-123406D02*
X323631Y-135072D01*
X326469Y-123406D01*
X329307Y-135072D01*
X331928Y-123406D01*
G01X340039Y-135655D02*
X347899Y-117572D01*
G01X376349D02*
X381589D01*
G01X378969D02*
Y-135072D01*
G01X376349D02*
X381589D01*
G01X396469D02*
X394722Y-134780D01*
X393194Y-133614D01*
X391884Y-131864D01*
X391010Y-129822D01*
X390574Y-127489D01*
Y-125155D01*
X391010Y-122822D01*
X391884Y-120780D01*
X393194Y-119031D01*
X394722Y-117864D01*
X396469Y-117572D01*
X398215Y-117864D01*
X399744Y-119031D01*
X401054Y-120780D01*
X401928Y-122822D01*
X402364Y-125155D01*
Y-127489D01*
X401928Y-129822D01*
X401054Y-131864D01*
X399744Y-133614D01*
X398215Y-134780D01*
X396469Y-135072D01*
G01X418772Y-119031D02*
X417462Y-118155D01*
X415934Y-117572D01*
X414187D01*
X412222Y-118447D01*
X410694Y-119905D01*
X409602Y-121656D01*
X408729Y-124572D01*
X408510Y-127197D01*
X408947Y-129822D01*
X409602Y-131572D01*
X410912Y-133322D01*
X412441Y-134489D01*
X413969Y-135072D01*
X415497D01*
X417026Y-134489D01*
X418336Y-133614D01*
X419428Y-132448D01*
G01X432561Y-140905D02*
X434744Y-137989D01*
X435836Y-135072D01*
Y-123406D01*
X434744Y-120489D01*
X432561Y-117572D01*
G01X180792Y-90072D02*
Y-72572D01*
X186469Y-87155D01*
X192146Y-72572D01*
Y-90072D01*
G01X203969D02*
X202659Y-89780D01*
X201349Y-88614D01*
X200475Y-86572D01*
X200039Y-84239D01*
X200475Y-81905D01*
X201349Y-79864D01*
X202659Y-78697D01*
X203969Y-78406D01*
X205279Y-78697D01*
X206589Y-79864D01*
X207462Y-81905D01*
X207681Y-84239D01*
X207462Y-86572D01*
X206589Y-88614D01*
X205279Y-89780D01*
X203969Y-90072D01*
G01X225399Y-72572D02*
Y-90072D01*
G01Y-87448D02*
X224526Y-88906D01*
X223215Y-89780D01*
X221687Y-90072D01*
X219941Y-89489D01*
X218631Y-88031D01*
X217757Y-86281D01*
X217539Y-84239D01*
X217757Y-82197D01*
X218631Y-80447D01*
X219941Y-78989D01*
X221687Y-78406D01*
X223215Y-78697D01*
X224307Y-79281D01*
X225399Y-80447D01*
G01X235694Y-82197D02*
X242681D01*
X242026Y-80155D01*
X240934Y-78989D01*
X239406Y-78406D01*
X237877Y-78697D01*
X236567Y-79572D01*
X235694Y-81614D01*
X235257Y-83364D01*
Y-85114D01*
X235694Y-86864D01*
X236786Y-88614D01*
X238096Y-89780D01*
X239624Y-90072D01*
X241152Y-89489D01*
X242681Y-87739D01*
G01X256469Y-90072D02*
Y-72572D01*
G01X490269Y-135072D02*
Y-117572D01*
X487649Y-121072D01*
G01Y-135072D02*
X492889D01*
G01X503621Y-127781D02*
X505149Y-125739D01*
X506459Y-124572D01*
X508206Y-123989D01*
X509734Y-124572D01*
X510826Y-125739D01*
X511699Y-127489D01*
X511917Y-129530D01*
X511699Y-131281D01*
X510826Y-133031D01*
X509515Y-134489D01*
X507987Y-135072D01*
X506241Y-134489D01*
X504712Y-132739D01*
X503839Y-130114D01*
X503621Y-127197D01*
X504057Y-123406D01*
X504712Y-121363D01*
X505804Y-119322D01*
X507332Y-117864D01*
X508861Y-117572D01*
X510389Y-118155D01*
X511481Y-119614D01*
G01X520466Y-131572D02*
X521775Y-133614D01*
X523522Y-134780D01*
X525487Y-135072D01*
X527234Y-134780D01*
X528981Y-133322D01*
X530072Y-131572D01*
X530291Y-129822D01*
X529854Y-127781D01*
X528326Y-126322D01*
X526797Y-125739D01*
X524832D01*
G01X526797D02*
X528107Y-124864D01*
X529199Y-123406D01*
X529636Y-121656D01*
X529199Y-119905D01*
X528107Y-118447D01*
X526142Y-117572D01*
X524177Y-117864D01*
X522212Y-119031D01*
G01X542769Y-135072D02*
Y-117572D01*
X540149Y-121072D01*
G01Y-135072D02*
X545389D01*
G01X560269D02*
X561797Y-134780D01*
X563544Y-133906D01*
X564636Y-132448D01*
X565072Y-130405D01*
X564636Y-128364D01*
X563326Y-126614D01*
X561361Y-125739D01*
X559177D01*
X557867Y-125155D01*
X556775Y-123697D01*
X556339Y-121656D01*
X556994Y-119614D01*
X558522Y-118155D01*
X560269Y-117572D01*
X562015Y-118155D01*
X563544Y-119614D01*
X564199Y-121656D01*
X563762Y-123697D01*
X562671Y-125155D01*
X561361Y-125739D01*
X559177D01*
X557212Y-126614D01*
X555902Y-128364D01*
X555466Y-130405D01*
X555902Y-132448D01*
X556994Y-133906D01*
X558741Y-134780D01*
X560269Y-135072D01*
G01X477152Y-90072D02*
Y-72572D01*
X482392D01*
X484139Y-73447D01*
X485449Y-75489D01*
X485886Y-77822D01*
X485449Y-80155D01*
X484357Y-81905D01*
X482392Y-82781D01*
X477152D01*
G01X503822Y-74031D02*
X502512Y-73155D01*
X500984Y-72572D01*
X499237D01*
X497272Y-73447D01*
X495744Y-74905D01*
X494652Y-76656D01*
X493779Y-79572D01*
X493560Y-82197D01*
X493997Y-84822D01*
X494652Y-86572D01*
X495962Y-88322D01*
X497491Y-89489D01*
X499019Y-90072D01*
X500547D01*
X502076Y-89489D01*
X503386Y-88614D01*
X504478Y-87448D01*
G01X518265Y-80739D02*
X519139Y-79864D01*
X519794Y-78406D01*
X520231Y-76363D01*
X519794Y-74614D01*
X518921Y-73447D01*
X517392Y-72572D01*
X511497D01*
Y-90072D01*
X518702D01*
X520231Y-88906D01*
X521104Y-87155D01*
X521541Y-85114D01*
X521104Y-83072D01*
X519794Y-81322D01*
X518265Y-80739D01*
X511497D01*
G01X527469Y-95905D02*
X540569D01*
G01X546497Y-90072D02*
Y-72572D01*
X556541Y-90072D01*
Y-72572D01*
G01X569019Y-90072D02*
X567272Y-89780D01*
X565744Y-88614D01*
X564434Y-86864D01*
X563560Y-84822D01*
X563124Y-82489D01*
Y-80155D01*
X563560Y-77822D01*
X564434Y-75780D01*
X565744Y-74031D01*
X567272Y-72864D01*
X569019Y-72572D01*
X570765Y-72864D01*
X572294Y-74031D01*
X573604Y-75780D01*
X574478Y-77822D01*
X574914Y-80155D01*
Y-82489D01*
X574478Y-84822D01*
X573604Y-86864D01*
X572294Y-88614D01*
X570765Y-89780D01*
X569019Y-90072D01*
G01X647421Y-120489D02*
X648731Y-118739D01*
X650259Y-117864D01*
X652006Y-117572D01*
X654189Y-118155D01*
X655717Y-119614D01*
X656154Y-121363D01*
X655936Y-123114D01*
X655062Y-124572D01*
X650696Y-127489D01*
X648731Y-129530D01*
X647421Y-132448D01*
X646984Y-135072D01*
X656154D01*
G01X619860Y-72572D02*
X625319Y-90072D01*
X630778Y-72572D01*
G01X647186Y-90072D02*
X638452D01*
Y-72572D01*
X647186D01*
G01X643692Y-81030D02*
X638452D01*
G01X655952Y-90072D02*
Y-72572D01*
X661411D01*
X663157Y-73447D01*
X664249Y-74614D01*
X664686Y-76947D01*
X664249Y-79281D01*
X662939Y-80739D01*
X661411Y-81614D01*
X655952D01*
G01X661411D02*
X664686Y-90072D01*
G01X677819Y-90655D02*
X677382Y-90364D01*
Y-89780D01*
X677819Y-89489D01*
X678256Y-89780D01*
Y-90364D01*
X677819Y-90655D01*
G01X757769Y-117572D02*
Y-135072D01*
G01X752747Y-117572D02*
X762791D01*
G01X770684Y-132739D02*
X772431Y-134197D01*
X774396Y-135072D01*
X776142D01*
X777889Y-134197D01*
X779199Y-132739D01*
X779854Y-130697D01*
X779417Y-128656D01*
X778326Y-126905D01*
X776361Y-125739D01*
X773741Y-125155D01*
X772212Y-123989D01*
X771557Y-121947D01*
X771994Y-119905D01*
X773086Y-118447D01*
X774614Y-117572D01*
X776142D01*
X777671Y-118155D01*
X778981Y-119614D01*
G01X790149Y-117572D02*
X795389D01*
G01X792769D02*
Y-135072D01*
G01X790149D02*
X795389D01*
G01X805902Y-117572D02*
Y-135072D01*
X814636D01*
G01X822966D02*
Y-117572D01*
G01X831262D02*
X822966Y-128364D01*
G01X832572Y-135072D02*
X826677Y-123406D01*
G01X753402Y-72572D02*
Y-90072D01*
X762136D01*
G01X779199D02*
Y-78406D01*
G01Y-80447D02*
X778326Y-79281D01*
X777015Y-78697D01*
X775487Y-78406D01*
X773959Y-78989D01*
X772649Y-80155D01*
X771775Y-81905D01*
X771339Y-84239D01*
X771775Y-86572D01*
X772649Y-88322D01*
X773959Y-89489D01*
X775487Y-90072D01*
X777015Y-89780D01*
X778326Y-88906D01*
X779199Y-87739D01*
G01X788184Y-95322D02*
X789494Y-95905D01*
X791241Y-95322D01*
X792332Y-94156D01*
X793206Y-92697D01*
X794515Y-88031D01*
X797354Y-78406D01*
G01X790367D02*
X794515Y-88031D01*
G01X806994Y-82197D02*
X813981D01*
X813326Y-80155D01*
X812234Y-78989D01*
X810706Y-78406D01*
X809177Y-78697D01*
X807867Y-79572D01*
X806994Y-81614D01*
X806557Y-83364D01*
Y-85114D01*
X806994Y-86864D01*
X808086Y-88614D01*
X809396Y-89780D01*
X810924Y-90072D01*
X812452Y-89489D01*
X813981Y-87739D01*
G01X824712Y-90072D02*
Y-78406D01*
G01Y-80739D02*
X825804Y-79572D01*
X826896Y-78697D01*
X828424Y-78406D01*
X829515Y-78697D01*
X830826Y-79572D01*
G01X917819Y-135072D02*
X916072Y-134780D01*
X914544Y-133614D01*
X913234Y-131864D01*
X912360Y-129822D01*
X911924Y-127489D01*
Y-125155D01*
X912360Y-122822D01*
X913234Y-120780D01*
X914544Y-119031D01*
X916072Y-117864D01*
X917819Y-117572D01*
X919565Y-117864D01*
X921094Y-119031D01*
X922404Y-120780D01*
X923278Y-122822D01*
X923714Y-125155D01*
Y-127489D01*
X923278Y-129822D01*
X922404Y-131864D01*
X921094Y-133614D01*
X919565Y-134780D01*
X917819Y-135072D01*
G01X919565Y-130405D02*
X922186Y-135072D01*
G01X930516Y-117572D02*
Y-130114D01*
X931389Y-132739D01*
X933136Y-134489D01*
X935319Y-135072D01*
X937502Y-134489D01*
X939249Y-132739D01*
X940122Y-130114D01*
Y-117572D01*
G01X950199D02*
X955439D01*
G01X952819D02*
Y-135072D01*
G01X950199D02*
X955439D01*
G01X965297D02*
Y-117572D01*
X975341Y-135072D01*
Y-117572D01*
G01X992622Y-119031D02*
X991312Y-118155D01*
X989784Y-117572D01*
X988037D01*
X986072Y-118447D01*
X984544Y-119905D01*
X983452Y-121656D01*
X982579Y-124572D01*
X982360Y-127197D01*
X982797Y-129822D01*
X983452Y-131572D01*
X984762Y-133322D01*
X986291Y-134489D01*
X987819Y-135072D01*
X989347D01*
X990876Y-134489D01*
X992186Y-133614D01*
X993278Y-132448D01*
G01X1005319Y-135072D02*
Y-127197D01*
X1000952Y-117572D01*
G01X1009686D02*
X1005319Y-127197D01*
G01X895516Y-90072D02*
Y-72572D01*
X899882D01*
X901629Y-73447D01*
X902939Y-74614D01*
X904031Y-76363D01*
X904904Y-78406D01*
X905122Y-81322D01*
X904904Y-84239D01*
X904031Y-86281D01*
X902939Y-88031D01*
X901629Y-89197D01*
X899882Y-90072D01*
X895516D01*
G01X914544Y-82197D02*
X921531D01*
X920876Y-80155D01*
X919784Y-78989D01*
X918256Y-78406D01*
X916727Y-78697D01*
X915417Y-79572D01*
X914544Y-81614D01*
X914107Y-83364D01*
Y-85114D01*
X914544Y-86864D01*
X915636Y-88614D01*
X916946Y-89780D01*
X918474Y-90072D01*
X920002Y-89489D01*
X921531Y-87739D01*
G01X932044Y-88031D02*
X933136Y-89197D01*
X934664Y-90072D01*
X935974D01*
X937284Y-89489D01*
X938157Y-88614D01*
X938594Y-87448D01*
X938376Y-85697D01*
X937502Y-84822D01*
X933572Y-83072D01*
X932699Y-81030D01*
X933136Y-79572D01*
X934009Y-78697D01*
X935319Y-78406D01*
X936629Y-78697D01*
X937939Y-79572D01*
G01X952819Y-78406D02*
Y-90072D01*
G01Y-73739D02*
X952382Y-73447D01*
Y-72864D01*
X952819Y-72572D01*
X953256Y-72864D01*
Y-73447D01*
X952819Y-73739D01*
G01X967262Y-94447D02*
X968791Y-95614D01*
X970537Y-95905D01*
X972065Y-95614D01*
X973376Y-94156D01*
X974249Y-92114D01*
Y-78406D01*
G01Y-80739D02*
X973376Y-79572D01*
X972065Y-78697D01*
X970537Y-78406D01*
X968791Y-78989D01*
X967699Y-80155D01*
X966825Y-82197D01*
X966389Y-84239D01*
X966607Y-85989D01*
X967481Y-88031D01*
X968791Y-89489D01*
X970537Y-90072D01*
X971847Y-89780D01*
X973376Y-88614D01*
X974249Y-87448D01*
G01X984107Y-90072D02*
Y-78406D01*
G01Y-81322D02*
X984981Y-79864D01*
X986291Y-78697D01*
X988037Y-78406D01*
X989565Y-78697D01*
X990876Y-79864D01*
X991531Y-81905D01*
Y-90072D01*
G01X1002044Y-82197D02*
X1009031D01*
X1008376Y-80155D01*
X1007284Y-78989D01*
X1005756Y-78406D01*
X1004227Y-78697D01*
X1002917Y-79572D01*
X1002044Y-81614D01*
X1001607Y-83364D01*
Y-85114D01*
X1002044Y-86864D01*
X1003136Y-88614D01*
X1004446Y-89780D01*
X1005974Y-90072D01*
X1007502Y-89489D01*
X1009031Y-87739D01*
G01X1019762Y-90072D02*
Y-78406D01*
G01Y-80739D02*
X1020854Y-79572D01*
X1021946Y-78697D01*
X1023474Y-78406D01*
X1024565Y-78697D01*
X1025876Y-79572D01*
G01X1066519Y-117572D02*
X1064772Y-118155D01*
X1063462Y-119614D01*
X1062589Y-121363D01*
X1061934Y-123697D01*
X1061716Y-126322D01*
X1061934Y-128947D01*
X1062589Y-131281D01*
X1063462Y-133031D01*
X1064772Y-134489D01*
X1066519Y-135072D01*
X1068265Y-134489D01*
X1069576Y-133031D01*
X1070449Y-131281D01*
X1071104Y-128947D01*
X1071322Y-126322D01*
X1071104Y-123697D01*
X1070449Y-121363D01*
X1069576Y-119614D01*
X1068265Y-118155D01*
X1066519Y-117572D01*
G01X1084019Y-135072D02*
X1085547Y-134780D01*
X1087294Y-133906D01*
X1088386Y-132448D01*
X1088822Y-130405D01*
X1088386Y-128364D01*
X1087076Y-126614D01*
X1085111Y-125739D01*
X1082927D01*
X1081617Y-125155D01*
X1080525Y-123697D01*
X1080089Y-121656D01*
X1080744Y-119614D01*
X1082272Y-118155D01*
X1084019Y-117572D01*
X1085765Y-118155D01*
X1087294Y-119614D01*
X1087949Y-121656D01*
X1087512Y-123697D01*
X1086421Y-125155D01*
X1085111Y-125739D01*
X1082927D01*
X1080962Y-126614D01*
X1079652Y-128364D01*
X1079216Y-130405D01*
X1079652Y-132448D01*
X1080744Y-133906D01*
X1082491Y-134780D01*
X1084019Y-135072D01*
G01X1097589Y-135655D02*
X1105449Y-117572D01*
G01X1119019D02*
X1117272Y-118155D01*
X1115962Y-119614D01*
X1115089Y-121363D01*
X1114434Y-123697D01*
X1114216Y-126322D01*
X1114434Y-128947D01*
X1115089Y-131281D01*
X1115962Y-133031D01*
X1117272Y-134489D01*
X1119019Y-135072D01*
X1120765Y-134489D01*
X1122076Y-133031D01*
X1122949Y-131281D01*
X1123604Y-128947D01*
X1123822Y-126322D01*
X1123604Y-123697D01*
X1122949Y-121363D01*
X1122076Y-119614D01*
X1120765Y-118155D01*
X1119019Y-117572D01*
G01X1136082Y-135072D02*
X1136519Y-131281D01*
X1137174Y-128072D01*
X1138047Y-125155D01*
X1139139Y-121947D01*
X1140886Y-117572D01*
X1132152D01*
G01X1150089Y-135655D02*
X1157949Y-117572D01*
G01X1167371Y-120489D02*
X1168681Y-118739D01*
X1170209Y-117864D01*
X1171956Y-117572D01*
X1174139Y-118155D01*
X1175667Y-119614D01*
X1176104Y-121363D01*
X1175886Y-123114D01*
X1175012Y-124572D01*
X1170646Y-127489D01*
X1168681Y-129530D01*
X1167371Y-132448D01*
X1166934Y-135072D01*
X1176104D01*
G01X1189019Y-117572D02*
X1187272Y-118155D01*
X1185962Y-119614D01*
X1185089Y-121363D01*
X1184434Y-123697D01*
X1184216Y-126322D01*
X1184434Y-128947D01*
X1185089Y-131281D01*
X1185962Y-133031D01*
X1187272Y-134489D01*
X1189019Y-135072D01*
X1190765Y-134489D01*
X1192076Y-133031D01*
X1192949Y-131281D01*
X1193604Y-128947D01*
X1193822Y-126322D01*
X1193604Y-123697D01*
X1192949Y-121363D01*
X1192076Y-119614D01*
X1190765Y-118155D01*
X1189019Y-117572D01*
G01X1206519Y-135072D02*
Y-117572D01*
X1203899Y-121072D01*
G01Y-135072D02*
X1209139D01*
G01X1223582D02*
X1224019Y-131281D01*
X1224674Y-128072D01*
X1225547Y-125155D01*
X1226639Y-121947D01*
X1228386Y-117572D01*
X1219652D01*
G01X1114216Y-90072D02*
Y-72572D01*
X1118582D01*
X1120329Y-73447D01*
X1121639Y-74614D01*
X1122731Y-76363D01*
X1123604Y-78406D01*
X1123822Y-81322D01*
X1123604Y-84239D01*
X1122731Y-86281D01*
X1121639Y-88031D01*
X1120329Y-89197D01*
X1118582Y-90072D01*
X1114216D01*
G01X1140449D02*
Y-78406D01*
G01Y-80447D02*
X1139576Y-79281D01*
X1138265Y-78697D01*
X1136737Y-78406D01*
X1135209Y-78989D01*
X1133899Y-80155D01*
X1133025Y-81905D01*
X1132589Y-84239D01*
X1133025Y-86572D01*
X1133899Y-88322D01*
X1135209Y-89489D01*
X1136737Y-90072D01*
X1138265Y-89780D01*
X1139576Y-88906D01*
X1140449Y-87739D01*
G01X1154019Y-72572D02*
Y-90072D01*
G01X1150962Y-78406D02*
X1157076D01*
G01X1168244Y-82197D02*
X1175231D01*
X1174576Y-80155D01*
X1173484Y-78989D01*
X1171956Y-78406D01*
X1170427Y-78697D01*
X1169117Y-79572D01*
X1168244Y-81614D01*
X1167807Y-83364D01*
Y-85114D01*
X1168244Y-86864D01*
X1169336Y-88614D01*
X1170646Y-89780D01*
X1172174Y-90072D01*
X1173702Y-89489D01*
X1175231Y-87739D01*
G01X67589Y452500D02*
X47000D01*
Y468000D01*
X14500D01*
Y456000D01*
X5000D01*
Y406000D01*
X39400D01*
Y417000D01*
X79600D01*
G01X13200Y433617D02*
X10700D01*
Y434658D01*
X10825Y434992D01*
X10992Y435200D01*
X11325Y435283D01*
X11658Y435200D01*
X11867Y434950D01*
X11992Y434658D01*
Y433617D01*
G01Y434658D02*
X13200Y435283D01*
G01X12700Y436633D02*
X12992Y436883D01*
X13158Y437217D01*
X13200Y437592D01*
X13158Y437925D01*
X12950Y438258D01*
X12700Y438467D01*
X12450Y438508D01*
X12158Y438425D01*
X11950Y438133D01*
X11867Y437842D01*
Y437467D01*
G01Y437842D02*
X11742Y438092D01*
X11533Y438300D01*
X11283Y438383D01*
X11033Y438300D01*
X10825Y438092D01*
X10700Y437717D01*
X10742Y437342D01*
X10908Y436967D01*
G01X10700Y440650D02*
X10783Y440317D01*
X10992Y440067D01*
X11242Y439900D01*
X11575Y439775D01*
X11950Y439733D01*
X12325Y439775D01*
X12658Y439900D01*
X12908Y440067D01*
X13117Y440317D01*
X13200Y440650D01*
X13117Y440983D01*
X12908Y441233D01*
X12658Y441400D01*
X12325Y441525D01*
X11950Y441567D01*
X11575Y441525D01*
X11242Y441400D01*
X10992Y441233D01*
X10783Y440983D01*
X10700Y440650D01*
G01Y443750D02*
X10783Y443417D01*
X10992Y443167D01*
X11242Y443000D01*
X11575Y442875D01*
X11950Y442833D01*
X12325Y442875D01*
X12658Y443000D01*
X12908Y443167D01*
X13117Y443417D01*
X13200Y443750D01*
X13117Y444083D01*
X12908Y444333D01*
X12658Y444500D01*
X12325Y444625D01*
X11950Y444667D01*
X11575Y444625D01*
X11242Y444500D01*
X10992Y444333D01*
X10783Y444083D01*
X10700Y443750D01*
G01X13200Y419517D02*
X10700D01*
Y420558D01*
X10825Y420892D01*
X10992Y421100D01*
X11325Y421183D01*
X11658Y421100D01*
X11867Y420850D01*
X11992Y420558D01*
Y419517D01*
G01Y420558D02*
X13200Y421183D01*
G01Y423367D02*
X12658Y423450D01*
X12200Y423575D01*
X11783Y423742D01*
X11325Y423950D01*
X10700Y424283D01*
Y422617D01*
G01X13200Y426550D02*
X10700D01*
X11200Y426050D01*
G01X13200D02*
Y427050D01*
G01Y430150D02*
X10700D01*
X12492Y428608D01*
Y430692D01*
G01X13300Y522333D02*
X12633Y522416D01*
X12050Y522750D01*
X11550Y523250D01*
X11217Y523833D01*
X11050Y524500D01*
Y525166D01*
X11217Y525833D01*
X11550Y526416D01*
X12050Y526916D01*
X12633Y527250D01*
X13300Y527333D01*
X13967Y527250D01*
X14550Y526916D01*
X15050Y526416D01*
X15383Y525833D01*
X15550Y525166D01*
Y524500D01*
X15383Y523833D01*
X15050Y523250D01*
X14550Y522750D01*
X13967Y522416D01*
X13300Y522333D01*
G01X17150Y523000D02*
X17817Y522583D01*
X18567Y522333D01*
X19233D01*
X19900Y522583D01*
X20400Y523000D01*
X20650Y523583D01*
X20483Y524166D01*
X20067Y524666D01*
X19317Y525000D01*
X18317Y525166D01*
X17733Y525500D01*
X17483Y526083D01*
X17650Y526666D01*
X18067Y527083D01*
X18650Y527333D01*
X19233D01*
X19817Y527166D01*
X20317Y526750D01*
G01X26333Y526916D02*
X25833Y527166D01*
X25250Y527333D01*
X24583D01*
X23833Y527083D01*
X23250Y526666D01*
X22833Y526166D01*
X22500Y525333D01*
X22417Y524583D01*
X22583Y523833D01*
X22833Y523333D01*
X23333Y522833D01*
X23917Y522500D01*
X24500Y522333D01*
X25083D01*
X25667Y522500D01*
X26167Y522750D01*
X26583Y523083D01*
G01X30100Y522333D02*
Y527333D01*
X29100Y526333D01*
G01Y522333D02*
X31100D01*
G01X35700Y522166D02*
X35533Y522250D01*
Y522416D01*
X35700Y522500D01*
X35867Y522416D01*
Y522250D01*
X35700Y522166D01*
G01Y524416D02*
X35533Y524500D01*
Y524666D01*
X35700Y524750D01*
X35867Y524666D01*
Y524500D01*
X35700Y524416D01*
G01X39717Y526500D02*
X40217Y527000D01*
X40800Y527250D01*
X41467Y527333D01*
X42300Y527166D01*
X42883Y526750D01*
X43050Y526250D01*
X42967Y525750D01*
X42633Y525333D01*
X40967Y524500D01*
X40217Y523916D01*
X39717Y523083D01*
X39550Y522333D01*
X43050D01*
G01X47900D02*
Y527333D01*
X44817Y523750D01*
X48983D01*
G01X50333Y522333D02*
Y527333D01*
X52500Y523166D01*
X54667Y527333D01*
Y522333D01*
G01X56350D02*
Y527333D01*
G01X59850D02*
Y522333D01*
G01Y524833D02*
X56350D01*
G01X62117Y527333D02*
X65283D01*
X62117Y522333D01*
X65283D01*
G01X39344Y506D02*
Y11906D01*
X31694D01*
Y30706D01*
X29644D01*
Y41306D01*
X64844D01*
Y30706D01*
X62794D01*
Y11906D01*
X55144D01*
Y506D01*
X39344D01*
G01X86588Y549D02*
Y21849D01*
X78938D01*
Y40499D01*
X76788D01*
Y51149D01*
X84488D01*
Y42549D01*
X104488D01*
Y51149D01*
X112188D01*
Y40499D01*
X110038D01*
Y21849D01*
X102388D01*
Y549D01*
X86588D01*
G01X39834Y57267D02*
X37334D01*
Y58308D01*
X37459Y58642D01*
X37626Y58850D01*
X37959Y58933D01*
X38292Y58850D01*
X38501Y58600D01*
X38626Y58308D01*
Y57267D01*
G01Y58308D02*
X39834Y58933D01*
G01X38792Y60408D02*
X38501Y60700D01*
X38334Y60950D01*
X38251Y61283D01*
X38334Y61575D01*
X38501Y61783D01*
X38751Y61950D01*
X39042Y61992D01*
X39292Y61950D01*
X39542Y61783D01*
X39751Y61533D01*
X39834Y61242D01*
X39751Y60908D01*
X39501Y60617D01*
X39126Y60450D01*
X38709Y60408D01*
X38167Y60492D01*
X37876Y60617D01*
X37584Y60825D01*
X37376Y61117D01*
X37334Y61408D01*
X37417Y61700D01*
X37626Y61908D01*
G01X39459Y63383D02*
X39667Y63633D01*
X39792Y63925D01*
X39834Y64300D01*
X39751Y64675D01*
X39584Y64967D01*
X39292Y65175D01*
X38959Y65217D01*
X38626Y65133D01*
X38417Y64925D01*
X38251Y64633D01*
X38209Y64342D01*
X38251Y64050D01*
X38417Y63675D01*
X37334Y63800D01*
Y64925D01*
G01X40780Y53460D02*
X36780D01*
Y46060D01*
G01X60486Y56009D02*
X57986D01*
Y57050D01*
X58111Y57384D01*
X58278Y57592D01*
X58611Y57675D01*
X58944Y57592D01*
X59153Y57342D01*
X59278Y57050D01*
Y56009D01*
G01Y57050D02*
X60486Y57675D01*
G01Y60442D02*
X57986D01*
X59778Y58900D01*
Y60984D01*
G01X60486Y62959D02*
X59944Y63042D01*
X59486Y63167D01*
X59069Y63334D01*
X58611Y63542D01*
X57986Y63875D01*
Y62209D01*
G01X56010Y47110D02*
X60010D01*
Y54510D01*
G01X79236Y65549D02*
X76736D01*
Y66590D01*
X76861Y66924D01*
X77028Y67132D01*
X77361Y67215D01*
X77694Y67132D01*
X77903Y66882D01*
X78028Y66590D01*
Y65549D01*
G01Y66590D02*
X79236Y67215D01*
G01Y69982D02*
X76736D01*
X78528Y68440D01*
Y70524D01*
G01X78861Y71665D02*
X79069Y71915D01*
X79194Y72207D01*
X79236Y72582D01*
X79153Y72957D01*
X78986Y73249D01*
X78694Y73457D01*
X78361Y73499D01*
X78028Y73415D01*
X77819Y73207D01*
X77653Y72915D01*
X77611Y72624D01*
X77653Y72332D01*
X77819Y71957D01*
X76736Y72082D01*
Y73207D01*
G01X77570Y53060D02*
X81570D01*
Y60460D01*
G01X42542Y58417D02*
X42417Y58167D01*
X42334Y57875D01*
Y57542D01*
X42459Y57167D01*
X42667Y56875D01*
X42917Y56667D01*
X43334Y56500D01*
X43709Y56458D01*
X44084Y56542D01*
X44334Y56667D01*
X44584Y56917D01*
X44751Y57208D01*
X44834Y57500D01*
Y57792D01*
X44751Y58083D01*
X44626Y58333D01*
X44459Y58542D01*
G01X44334Y59683D02*
X44626Y59933D01*
X44792Y60267D01*
X44834Y60642D01*
X44792Y60975D01*
X44584Y61308D01*
X44334Y61517D01*
X44084Y61558D01*
X43792Y61475D01*
X43584Y61183D01*
X43501Y60892D01*
Y60517D01*
G01Y60892D02*
X43376Y61142D01*
X43167Y61350D01*
X42917Y61433D01*
X42667Y61350D01*
X42459Y61142D01*
X42334Y60767D01*
X42376Y60392D01*
X42542Y60017D01*
G01X44834Y63700D02*
X42334D01*
X42834Y63200D01*
G01X44834D02*
Y64200D01*
G01X26734Y26117D02*
X24234D01*
Y27158D01*
X24359Y27492D01*
X24526Y27700D01*
X24859Y27783D01*
X25192Y27700D01*
X25401Y27450D01*
X25526Y27158D01*
Y26117D01*
G01Y27158D02*
X26734Y27783D01*
G01X26401Y29175D02*
X26609Y29508D01*
X26734Y29883D01*
Y30217D01*
X26609Y30550D01*
X26401Y30800D01*
X26109Y30925D01*
X25817Y30842D01*
X25567Y30633D01*
X25401Y30258D01*
X25317Y29758D01*
X25151Y29467D01*
X24859Y29342D01*
X24567Y29425D01*
X24359Y29633D01*
X24234Y29925D01*
Y30217D01*
X24317Y30508D01*
X24526Y30758D01*
G01X24234Y33150D02*
X26734D01*
G01X24234Y32192D02*
Y34108D01*
G01X26734Y36250D02*
X24234D01*
X24734Y35750D01*
G01X26734D02*
Y36750D01*
G01X29803Y58987D02*
Y61487D01*
X30637D01*
X30970Y61362D01*
X31220Y61195D01*
X31428Y60945D01*
X31595Y60654D01*
X31637Y60237D01*
X31595Y59820D01*
X31428Y59529D01*
X31220Y59279D01*
X30970Y59112D01*
X30637Y58987D01*
X29803D01*
G01X32903Y59487D02*
X33153Y59195D01*
X33487Y59029D01*
X33862Y58987D01*
X34195Y59029D01*
X34528Y59237D01*
X34737Y59487D01*
X34778Y59737D01*
X34695Y60029D01*
X34403Y60237D01*
X34112Y60320D01*
X33737D01*
G01X34112D02*
X34362Y60445D01*
X34570Y60654D01*
X34653Y60904D01*
X34570Y61154D01*
X34362Y61362D01*
X33987Y61487D01*
X33612Y61445D01*
X33237Y61279D01*
G01X36170Y45070D02*
X31970D01*
G01X36170Y56770D02*
Y45070D01*
G01X31970Y56770D02*
X36170D01*
G01X31970Y45070D02*
Y56770D01*
G01X49338Y66607D02*
X49213Y66357D01*
X49130Y66065D01*
Y65732D01*
X49255Y65357D01*
X49463Y65065D01*
X49713Y64857D01*
X50130Y64690D01*
X50505Y64648D01*
X50880Y64732D01*
X51130Y64857D01*
X51380Y65107D01*
X51547Y65398D01*
X51630Y65690D01*
Y65982D01*
X51547Y66273D01*
X51422Y66523D01*
X51255Y66732D01*
G01Y67873D02*
X51463Y68123D01*
X51588Y68415D01*
X51630Y68790D01*
X51547Y69165D01*
X51380Y69457D01*
X51088Y69665D01*
X50755Y69707D01*
X50422Y69623D01*
X50213Y69415D01*
X50047Y69123D01*
X50005Y68832D01*
X50047Y68540D01*
X50213Y68165D01*
X49130Y68290D01*
Y69415D01*
G01X49547Y71098D02*
X49297Y71348D01*
X49172Y71640D01*
X49130Y71973D01*
X49213Y72390D01*
X49422Y72682D01*
X49672Y72765D01*
X49922Y72723D01*
X50130Y72557D01*
X50547Y71723D01*
X50838Y71348D01*
X51255Y71098D01*
X51630Y71015D01*
Y72765D01*
G01X51338Y74282D02*
X51547Y74573D01*
X51630Y74907D01*
X51547Y75240D01*
X51297Y75532D01*
X50922Y75740D01*
X50547Y75823D01*
X50088D01*
X49713Y75740D01*
X49380Y75532D01*
X49213Y75282D01*
X49130Y74990D01*
X49213Y74657D01*
X49380Y74407D01*
X49630Y74240D01*
X49963Y74157D01*
X50255Y74240D01*
X50547Y74448D01*
X50713Y74698D01*
X50755Y74990D01*
X50672Y75323D01*
X50463Y75573D01*
X50088Y75823D01*
G01X46960Y56130D02*
Y61630D01*
X54960D01*
Y56030D01*
G01X46960Y44030D02*
Y49530D01*
G01Y44030D02*
X54960D01*
Y49530D01*
G01X62108Y54377D02*
X61983Y54127D01*
X61900Y53835D01*
Y53502D01*
X62025Y53127D01*
X62233Y52835D01*
X62483Y52627D01*
X62900Y52460D01*
X63275Y52418D01*
X63650Y52502D01*
X63900Y52627D01*
X64150Y52877D01*
X64317Y53168D01*
X64400Y53460D01*
Y53752D01*
X64317Y54043D01*
X64192Y54293D01*
X64025Y54502D01*
G01Y55643D02*
X64233Y55893D01*
X64358Y56185D01*
X64400Y56560D01*
X64317Y56935D01*
X64150Y57227D01*
X63858Y57435D01*
X63525Y57477D01*
X63192Y57393D01*
X62983Y57185D01*
X62817Y56893D01*
X62775Y56602D01*
X62817Y56310D01*
X62983Y55935D01*
X61900Y56060D01*
Y57185D01*
G01X62317Y58868D02*
X62067Y59118D01*
X61942Y59410D01*
X61900Y59743D01*
X61983Y60160D01*
X62192Y60452D01*
X62442Y60535D01*
X62692Y60493D01*
X62900Y60327D01*
X63317Y59493D01*
X63608Y59118D01*
X64025Y58868D01*
X64400Y58785D01*
Y60535D01*
G01Y62760D02*
X64358Y63052D01*
X64233Y63385D01*
X64025Y63593D01*
X63733Y63677D01*
X63442Y63593D01*
X63192Y63343D01*
X63067Y62968D01*
Y62552D01*
X62983Y62302D01*
X62775Y62093D01*
X62483Y62010D01*
X62192Y62135D01*
X61983Y62427D01*
X61900Y62760D01*
X61983Y63093D01*
X62192Y63385D01*
X62483Y63510D01*
X62775Y63427D01*
X62983Y63218D01*
X63067Y62968D01*
Y62552D01*
X63192Y62177D01*
X63442Y61927D01*
X63733Y61843D01*
X64025Y61927D01*
X64233Y62135D01*
X64358Y62468D01*
X64400Y62760D01*
G01X67090Y61100D02*
Y66600D01*
X75090D01*
Y61000D01*
G01X67090Y49000D02*
Y54500D01*
G01Y49000D02*
X75090D01*
Y54500D01*
G01X61100Y153900D02*
Y126100D01*
X88900D01*
Y153900D01*
X61100D01*
G01Y185400D02*
Y157600D01*
X88900D01*
Y185400D01*
X61100D01*
G01X22167Y461933D02*
X22700Y462283D01*
X23100Y462867D01*
X23367Y463683D01*
X23100Y464383D01*
X22567Y464850D01*
X21633Y465200D01*
X18033D01*
Y458200D01*
X22433D01*
X23367Y458667D01*
X23900Y459367D01*
X24167Y460183D01*
X23900Y461000D01*
X23100Y461700D01*
X22167Y461933D01*
X18033D01*
G01X76454Y452500D02*
X85000D01*
Y457000D01*
X104500D01*
Y422500D01*
X95500D01*
G01X65008Y441967D02*
X64883Y441717D01*
X64800Y441425D01*
Y441092D01*
X64925Y440717D01*
X65133Y440425D01*
X65383Y440217D01*
X65800Y440050D01*
X66175Y440008D01*
X66550Y440092D01*
X66800Y440217D01*
X67050Y440467D01*
X67217Y440758D01*
X67300Y441050D01*
Y441342D01*
X67217Y441633D01*
X67092Y441883D01*
X66925Y442092D01*
G01X67300Y444150D02*
X64800D01*
X65300Y443650D01*
G01X67300D02*
Y444650D01*
G01X65217Y446458D02*
X64967Y446708D01*
X64842Y447000D01*
X64800Y447333D01*
X64883Y447750D01*
X65092Y448042D01*
X65342Y448125D01*
X65592Y448083D01*
X65800Y447917D01*
X66217Y447083D01*
X66508Y446708D01*
X66925Y446458D01*
X67300Y446375D01*
Y448125D01*
G01X65217Y449558D02*
X64967Y449808D01*
X64842Y450100D01*
X64800Y450433D01*
X64883Y450850D01*
X65092Y451142D01*
X65342Y451225D01*
X65592Y451183D01*
X65800Y451017D01*
X66217Y450183D01*
X66508Y449808D01*
X66925Y449558D01*
X67300Y449475D01*
Y451225D01*
G01X69361Y432127D02*
X69236Y431877D01*
X69153Y431585D01*
Y431252D01*
X69278Y430877D01*
X69486Y430585D01*
X69736Y430377D01*
X70153Y430210D01*
X70528Y430168D01*
X70903Y430252D01*
X71153Y430377D01*
X71403Y430627D01*
X71570Y430918D01*
X71653Y431210D01*
Y431502D01*
X71570Y431793D01*
X71445Y432043D01*
X71278Y432252D01*
G01X71653Y434310D02*
X71611Y434602D01*
X71486Y434935D01*
X71278Y435143D01*
X70986Y435227D01*
X70695Y435143D01*
X70445Y434893D01*
X70320Y434518D01*
Y434102D01*
X70236Y433852D01*
X70028Y433643D01*
X69736Y433560D01*
X69445Y433685D01*
X69236Y433977D01*
X69153Y434310D01*
X69236Y434643D01*
X69445Y434935D01*
X69736Y435060D01*
X70028Y434977D01*
X70236Y434768D01*
X70320Y434518D01*
Y434102D01*
X70445Y433727D01*
X70695Y433477D01*
X70986Y433393D01*
X71278Y433477D01*
X71486Y433685D01*
X71611Y434018D01*
X71653Y434310D01*
G01Y437910D02*
X69153D01*
X70945Y436368D01*
Y438452D01*
G01X61658Y432717D02*
X61533Y432467D01*
X61450Y432175D01*
Y431842D01*
X61575Y431467D01*
X61783Y431175D01*
X62033Y430967D01*
X62450Y430800D01*
X62825Y430758D01*
X63200Y430842D01*
X63450Y430967D01*
X63700Y431217D01*
X63867Y431508D01*
X63950Y431800D01*
Y432092D01*
X63867Y432383D01*
X63742Y432633D01*
X63575Y432842D01*
G01X63950Y434900D02*
X63908Y435192D01*
X63783Y435525D01*
X63575Y435733D01*
X63283Y435817D01*
X62992Y435733D01*
X62742Y435483D01*
X62617Y435108D01*
Y434692D01*
X62533Y434442D01*
X62325Y434233D01*
X62033Y434150D01*
X61742Y434275D01*
X61533Y434567D01*
X61450Y434900D01*
X61533Y435233D01*
X61742Y435525D01*
X62033Y435650D01*
X62325Y435567D01*
X62533Y435358D01*
X62617Y435108D01*
Y434692D01*
X62742Y434317D01*
X62992Y434067D01*
X63283Y433983D01*
X63575Y434067D01*
X63783Y434275D01*
X63908Y434608D01*
X63950Y434900D01*
G01X63575Y437083D02*
X63783Y437333D01*
X63908Y437625D01*
X63950Y438000D01*
X63867Y438375D01*
X63700Y438667D01*
X63408Y438875D01*
X63075Y438917D01*
X62742Y438833D01*
X62533Y438625D01*
X62367Y438333D01*
X62325Y438042D01*
X62367Y437750D01*
X62533Y437375D01*
X61450Y437500D01*
Y438625D01*
G01X65668Y432737D02*
X65543Y432487D01*
X65460Y432195D01*
Y431862D01*
X65585Y431487D01*
X65793Y431195D01*
X66043Y430987D01*
X66460Y430820D01*
X66835Y430778D01*
X67210Y430862D01*
X67460Y430987D01*
X67710Y431237D01*
X67877Y431528D01*
X67960Y431820D01*
Y432112D01*
X67877Y432403D01*
X67752Y432653D01*
X67585Y432862D01*
G01X67960Y434920D02*
X67918Y435212D01*
X67793Y435545D01*
X67585Y435753D01*
X67293Y435837D01*
X67002Y435753D01*
X66752Y435503D01*
X66627Y435128D01*
Y434712D01*
X66543Y434462D01*
X66335Y434253D01*
X66043Y434170D01*
X65752Y434295D01*
X65543Y434587D01*
X65460Y434920D01*
X65543Y435253D01*
X65752Y435545D01*
X66043Y435670D01*
X66335Y435587D01*
X66543Y435378D01*
X66627Y435128D01*
Y434712D01*
X66752Y434337D01*
X67002Y434087D01*
X67293Y434003D01*
X67585Y434087D01*
X67793Y434295D01*
X67918Y434628D01*
X67960Y434920D01*
G01X66918Y437228D02*
X66627Y437520D01*
X66460Y437770D01*
X66377Y438103D01*
X66460Y438395D01*
X66627Y438603D01*
X66877Y438770D01*
X67168Y438812D01*
X67418Y438770D01*
X67668Y438603D01*
X67877Y438353D01*
X67960Y438062D01*
X67877Y437728D01*
X67627Y437437D01*
X67252Y437270D01*
X66835Y437228D01*
X66293Y437312D01*
X66002Y437437D01*
X65710Y437645D01*
X65502Y437937D01*
X65460Y438228D01*
X65543Y438520D01*
X65752Y438728D01*
G01X72514Y441959D02*
X72389Y441709D01*
X72306Y441417D01*
Y441084D01*
X72431Y440709D01*
X72639Y440417D01*
X72889Y440209D01*
X73306Y440042D01*
X73681Y440000D01*
X74056Y440084D01*
X74306Y440209D01*
X74556Y440459D01*
X74723Y440750D01*
X74806Y441042D01*
Y441334D01*
X74723Y441625D01*
X74598Y441875D01*
X74431Y442084D01*
G01X74806Y444142D02*
X72306D01*
X72806Y443642D01*
G01X74806D02*
Y444642D01*
G01Y447242D02*
X72306D01*
X72806Y446742D01*
G01X74806D02*
Y447742D01*
G01Y450342D02*
X74764Y450634D01*
X74639Y450967D01*
X74431Y451175D01*
X74139Y451259D01*
X73848Y451175D01*
X73598Y450925D01*
X73473Y450550D01*
Y450134D01*
X73389Y449884D01*
X73181Y449675D01*
X72889Y449592D01*
X72598Y449717D01*
X72389Y450009D01*
X72306Y450342D01*
X72389Y450675D01*
X72598Y450967D01*
X72889Y451092D01*
X73181Y451009D01*
X73389Y450800D01*
X73473Y450550D01*
Y450134D01*
X73598Y449759D01*
X73848Y449509D01*
X74139Y449425D01*
X74431Y449509D01*
X74639Y449717D01*
X74764Y450050D01*
X74806Y450342D01*
G01X46176Y434585D02*
X43676D01*
Y435626D01*
X43801Y435960D01*
X43968Y436168D01*
X44301Y436251D01*
X44634Y436168D01*
X44843Y435918D01*
X44968Y435626D01*
Y434585D01*
G01Y435626D02*
X46176Y436251D01*
G01Y438518D02*
X43676D01*
X44176Y438018D01*
G01X46176D02*
Y439018D01*
G01Y441535D02*
X45634Y441618D01*
X45176Y441743D01*
X44759Y441910D01*
X44301Y442118D01*
X43676Y442451D01*
Y440785D01*
G01X45884Y444010D02*
X46093Y444301D01*
X46176Y444635D01*
X46093Y444968D01*
X45843Y445260D01*
X45468Y445468D01*
X45093Y445551D01*
X44634D01*
X44259Y445468D01*
X43926Y445260D01*
X43759Y445010D01*
X43676Y444718D01*
X43759Y444385D01*
X43926Y444135D01*
X44176Y443968D01*
X44509Y443885D01*
X44801Y443968D01*
X45093Y444176D01*
X45259Y444426D01*
X45301Y444718D01*
X45218Y445051D01*
X45009Y445301D01*
X44634Y445551D01*
G01X38000Y443817D02*
X35500D01*
Y444858D01*
X35625Y445192D01*
X35792Y445400D01*
X36125Y445483D01*
X36458Y445400D01*
X36667Y445150D01*
X36792Y444858D01*
Y443817D01*
G01Y444858D02*
X38000Y445483D01*
G01Y447750D02*
X35500D01*
X36000Y447250D01*
G01X38000D02*
Y448250D01*
G01Y450850D02*
X37958Y451142D01*
X37833Y451475D01*
X37625Y451683D01*
X37333Y451767D01*
X37042Y451683D01*
X36792Y451433D01*
X36667Y451058D01*
Y450642D01*
X36583Y450392D01*
X36375Y450183D01*
X36083Y450100D01*
X35792Y450225D01*
X35583Y450517D01*
X35500Y450850D01*
X35583Y451183D01*
X35792Y451475D01*
X36083Y451600D01*
X36375Y451517D01*
X36583Y451308D01*
X36667Y451058D01*
Y450642D01*
X36792Y450267D01*
X37042Y450017D01*
X37333Y449933D01*
X37625Y450017D01*
X37833Y450225D01*
X37958Y450558D01*
X38000Y450850D01*
G01Y453867D02*
X37458Y453950D01*
X37000Y454075D01*
X36583Y454242D01*
X36125Y454450D01*
X35500Y454783D01*
Y453117D01*
G01X33900Y443817D02*
X31400D01*
Y444858D01*
X31525Y445192D01*
X31692Y445400D01*
X32025Y445483D01*
X32358Y445400D01*
X32567Y445150D01*
X32692Y444858D01*
Y443817D01*
G01Y444858D02*
X33900Y445483D01*
G01Y447750D02*
X31400D01*
X31900Y447250D01*
G01X33900D02*
Y448250D01*
G01Y450850D02*
X33858Y451142D01*
X33733Y451475D01*
X33525Y451683D01*
X33233Y451767D01*
X32942Y451683D01*
X32692Y451433D01*
X32567Y451058D01*
Y450642D01*
X32483Y450392D01*
X32275Y450183D01*
X31983Y450100D01*
X31692Y450225D01*
X31483Y450517D01*
X31400Y450850D01*
X31483Y451183D01*
X31692Y451475D01*
X31983Y451600D01*
X32275Y451517D01*
X32483Y451308D01*
X32567Y451058D01*
Y450642D01*
X32692Y450267D01*
X32942Y450017D01*
X33233Y449933D01*
X33525Y450017D01*
X33733Y450225D01*
X33858Y450558D01*
X33900Y450850D01*
G01Y453950D02*
X33858Y454242D01*
X33733Y454575D01*
X33525Y454783D01*
X33233Y454867D01*
X32942Y454783D01*
X32692Y454533D01*
X32567Y454158D01*
Y453742D01*
X32483Y453492D01*
X32275Y453283D01*
X31983Y453200D01*
X31692Y453325D01*
X31483Y453617D01*
X31400Y453950D01*
X31483Y454283D01*
X31692Y454575D01*
X31983Y454700D01*
X32275Y454617D01*
X32483Y454408D01*
X32567Y454158D01*
Y453742D01*
X32692Y453367D01*
X32942Y453117D01*
X33233Y453033D01*
X33525Y453117D01*
X33733Y453325D01*
X33858Y453658D01*
X33900Y453950D01*
G01X17300Y433617D02*
X14800D01*
Y434658D01*
X14925Y434992D01*
X15092Y435200D01*
X15425Y435283D01*
X15758Y435200D01*
X15967Y434950D01*
X16092Y434658D01*
Y433617D01*
G01Y434658D02*
X17300Y435283D01*
G01X15217Y436758D02*
X14967Y437008D01*
X14842Y437300D01*
X14800Y437633D01*
X14883Y438050D01*
X15092Y438342D01*
X15342Y438425D01*
X15592Y438383D01*
X15800Y438217D01*
X16217Y437383D01*
X16508Y437008D01*
X16925Y436758D01*
X17300Y436675D01*
Y438425D01*
G01X17008Y439942D02*
X17217Y440233D01*
X17300Y440567D01*
X17217Y440900D01*
X16967Y441192D01*
X16592Y441400D01*
X16217Y441483D01*
X15758D01*
X15383Y441400D01*
X15050Y441192D01*
X14883Y440942D01*
X14800Y440650D01*
X14883Y440317D01*
X15050Y440067D01*
X15300Y439900D01*
X15633Y439817D01*
X15925Y439900D01*
X16217Y440108D01*
X16383Y440358D01*
X16425Y440650D01*
X16342Y440983D01*
X16133Y441233D01*
X15758Y441483D01*
G01X17008Y443042D02*
X17217Y443333D01*
X17300Y443667D01*
X17217Y444000D01*
X16967Y444292D01*
X16592Y444500D01*
X16217Y444583D01*
X15758D01*
X15383Y444500D01*
X15050Y444292D01*
X14883Y444042D01*
X14800Y443750D01*
X14883Y443417D01*
X15050Y443167D01*
X15300Y443000D01*
X15633Y442917D01*
X15925Y443000D01*
X16217Y443208D01*
X16383Y443458D01*
X16425Y443750D01*
X16342Y444083D01*
X16133Y444333D01*
X15758Y444583D01*
G01X64000Y418017D02*
X61500D01*
Y419058D01*
X61625Y419392D01*
X61792Y419600D01*
X62125Y419683D01*
X62458Y419600D01*
X62667Y419350D01*
X62792Y419058D01*
Y418017D01*
G01Y419058D02*
X64000Y419683D01*
G01X61917Y421158D02*
X61667Y421408D01*
X61542Y421700D01*
X61500Y422033D01*
X61583Y422450D01*
X61792Y422742D01*
X62042Y422825D01*
X62292Y422783D01*
X62500Y422617D01*
X62917Y421783D01*
X63208Y421408D01*
X63625Y421158D01*
X64000Y421075D01*
Y422825D01*
G01X63708Y424342D02*
X63917Y424633D01*
X64000Y424967D01*
X63917Y425300D01*
X63667Y425592D01*
X63292Y425800D01*
X62917Y425883D01*
X62458D01*
X62083Y425800D01*
X61750Y425592D01*
X61583Y425342D01*
X61500Y425050D01*
X61583Y424717D01*
X61750Y424467D01*
X62000Y424300D01*
X62333Y424217D01*
X62625Y424300D01*
X62917Y424508D01*
X63083Y424758D01*
X63125Y425050D01*
X63042Y425383D01*
X62833Y425633D01*
X62458Y425883D01*
G01X64000Y428067D02*
X63458Y428150D01*
X63000Y428275D01*
X62583Y428442D01*
X62125Y428650D01*
X61500Y428983D01*
Y427317D01*
G01X57985Y421174D02*
X55485D01*
Y422215D01*
X55610Y422549D01*
X55777Y422757D01*
X56110Y422840D01*
X56443Y422757D01*
X56652Y422507D01*
X56777Y422215D01*
Y421174D01*
G01Y422215D02*
X57985Y422840D01*
G01X55902Y424315D02*
X55652Y424565D01*
X55527Y424857D01*
X55485Y425190D01*
X55568Y425607D01*
X55777Y425899D01*
X56027Y425982D01*
X56277Y425940D01*
X56485Y425774D01*
X56902Y424940D01*
X57193Y424565D01*
X57610Y424315D01*
X57985Y424232D01*
Y425982D01*
G01X57693Y427499D02*
X57902Y427790D01*
X57985Y428124D01*
X57902Y428457D01*
X57652Y428749D01*
X57277Y428957D01*
X56902Y429040D01*
X56443D01*
X56068Y428957D01*
X55735Y428749D01*
X55568Y428499D01*
X55485Y428207D01*
X55568Y427874D01*
X55735Y427624D01*
X55985Y427457D01*
X56318Y427374D01*
X56610Y427457D01*
X56902Y427665D01*
X57068Y427915D01*
X57110Y428207D01*
X57027Y428540D01*
X56818Y428790D01*
X56443Y429040D01*
G01X57985Y431307D02*
X57943Y431599D01*
X57818Y431932D01*
X57610Y432140D01*
X57318Y432224D01*
X57027Y432140D01*
X56777Y431890D01*
X56652Y431515D01*
Y431099D01*
X56568Y430849D01*
X56360Y430640D01*
X56068Y430557D01*
X55777Y430682D01*
X55568Y430974D01*
X55485Y431307D01*
X55568Y431640D01*
X55777Y431932D01*
X56068Y432057D01*
X56360Y431974D01*
X56568Y431765D01*
X56652Y431515D01*
Y431099D01*
X56777Y430724D01*
X57027Y430474D01*
X57318Y430390D01*
X57610Y430474D01*
X57818Y430682D01*
X57943Y431015D01*
X57985Y431307D01*
G01X29800Y443817D02*
X27300D01*
Y444858D01*
X27425Y445192D01*
X27592Y445400D01*
X27925Y445483D01*
X28258Y445400D01*
X28467Y445150D01*
X28592Y444858D01*
Y443817D01*
G01Y444858D02*
X29800Y445483D01*
G01X29300Y446833D02*
X29592Y447083D01*
X29758Y447417D01*
X29800Y447792D01*
X29758Y448125D01*
X29550Y448458D01*
X29300Y448667D01*
X29050Y448708D01*
X28758Y448625D01*
X28550Y448333D01*
X28467Y448042D01*
Y447667D01*
G01Y448042D02*
X28342Y448292D01*
X28133Y448500D01*
X27883Y448583D01*
X27633Y448500D01*
X27425Y448292D01*
X27300Y447917D01*
X27342Y447542D01*
X27508Y447167D01*
G01X29800Y450850D02*
X27300D01*
X27800Y450350D01*
G01X29800D02*
Y451350D01*
G01X29300Y453033D02*
X29592Y453283D01*
X29758Y453617D01*
X29800Y453992D01*
X29758Y454325D01*
X29550Y454658D01*
X29300Y454867D01*
X29050Y454908D01*
X28758Y454825D01*
X28550Y454533D01*
X28467Y454242D01*
Y453867D01*
G01Y454242D02*
X28342Y454492D01*
X28133Y454700D01*
X27883Y454783D01*
X27633Y454700D01*
X27425Y454492D01*
X27300Y454117D01*
X27342Y453742D01*
X27508Y453367D01*
G01X17300Y419517D02*
X14800D01*
Y420558D01*
X14925Y420892D01*
X15092Y421100D01*
X15425Y421183D01*
X15758Y421100D01*
X15967Y420850D01*
X16092Y420558D01*
Y419517D01*
G01Y420558D02*
X17300Y421183D01*
G01X16800Y422533D02*
X17092Y422783D01*
X17258Y423117D01*
X17300Y423492D01*
X17258Y423825D01*
X17050Y424158D01*
X16800Y424367D01*
X16550Y424408D01*
X16258Y424325D01*
X16050Y424033D01*
X15967Y423742D01*
Y423367D01*
G01Y423742D02*
X15842Y423992D01*
X15633Y424200D01*
X15383Y424283D01*
X15133Y424200D01*
X14925Y423992D01*
X14800Y423617D01*
X14842Y423242D01*
X15008Y422867D01*
G01X17300Y426550D02*
X14800D01*
X15300Y426050D01*
G01X17300D02*
Y427050D01*
G01Y429567D02*
X16758Y429650D01*
X16300Y429775D01*
X15883Y429942D01*
X15425Y430150D01*
X14800Y430483D01*
Y428817D01*
G01X21600Y419517D02*
X19100D01*
Y420558D01*
X19225Y420892D01*
X19392Y421100D01*
X19725Y421183D01*
X20058Y421100D01*
X20267Y420850D01*
X20392Y420558D01*
Y419517D01*
G01Y420558D02*
X21600Y421183D01*
G01X21100Y422533D02*
X21392Y422783D01*
X21558Y423117D01*
X21600Y423492D01*
X21558Y423825D01*
X21350Y424158D01*
X21100Y424367D01*
X20850Y424408D01*
X20558Y424325D01*
X20350Y424033D01*
X20267Y423742D01*
Y423367D01*
G01Y423742D02*
X20142Y423992D01*
X19933Y424200D01*
X19683Y424283D01*
X19433Y424200D01*
X19225Y423992D01*
X19100Y423617D01*
X19142Y423242D01*
X19308Y422867D01*
G01X19517Y425758D02*
X19267Y426008D01*
X19142Y426300D01*
X19100Y426633D01*
X19183Y427050D01*
X19392Y427342D01*
X19642Y427425D01*
X19892Y427383D01*
X20100Y427217D01*
X20517Y426383D01*
X20808Y426008D01*
X21225Y425758D01*
X21600Y425675D01*
Y427425D01*
G01Y429650D02*
X21558Y429942D01*
X21433Y430275D01*
X21225Y430483D01*
X20933Y430567D01*
X20642Y430483D01*
X20392Y430233D01*
X20267Y429858D01*
Y429442D01*
X20183Y429192D01*
X19975Y428983D01*
X19683Y428900D01*
X19392Y429025D01*
X19183Y429317D01*
X19100Y429650D01*
X19183Y429983D01*
X19392Y430275D01*
X19683Y430400D01*
X19975Y430317D01*
X20183Y430108D01*
X20267Y429858D01*
Y429442D01*
X20392Y429067D01*
X20642Y428817D01*
X20933Y428733D01*
X21225Y428817D01*
X21433Y429025D01*
X21558Y429358D01*
X21600Y429650D01*
G01X50276Y434585D02*
X47776D01*
Y435626D01*
X47901Y435960D01*
X48068Y436168D01*
X48401Y436251D01*
X48734Y436168D01*
X48943Y435918D01*
X49068Y435626D01*
Y434585D01*
G01Y435626D02*
X50276Y436251D01*
G01X48193Y437726D02*
X47943Y437976D01*
X47818Y438268D01*
X47776Y438601D01*
X47859Y439018D01*
X48068Y439310D01*
X48318Y439393D01*
X48568Y439351D01*
X48776Y439185D01*
X49193Y438351D01*
X49484Y437976D01*
X49901Y437726D01*
X50276Y437643D01*
Y439393D01*
G01X47776Y441618D02*
X47859Y441285D01*
X48068Y441035D01*
X48318Y440868D01*
X48651Y440743D01*
X49026Y440701D01*
X49401Y440743D01*
X49734Y440868D01*
X49984Y441035D01*
X50193Y441285D01*
X50276Y441618D01*
X50193Y441951D01*
X49984Y442201D01*
X49734Y442368D01*
X49401Y442493D01*
X49026Y442535D01*
X48651Y442493D01*
X48318Y442368D01*
X48068Y442201D01*
X47859Y441951D01*
X47776Y441618D01*
G01X50276Y445218D02*
X47776D01*
X49568Y443676D01*
Y445760D01*
G01X54376Y434585D02*
X51876D01*
Y435626D01*
X52001Y435960D01*
X52168Y436168D01*
X52501Y436251D01*
X52834Y436168D01*
X53043Y435918D01*
X53168Y435626D01*
Y434585D01*
G01Y435626D02*
X54376Y436251D01*
G01X52293Y437726D02*
X52043Y437976D01*
X51918Y438268D01*
X51876Y438601D01*
X51959Y439018D01*
X52168Y439310D01*
X52418Y439393D01*
X52668Y439351D01*
X52876Y439185D01*
X53293Y438351D01*
X53584Y437976D01*
X54001Y437726D01*
X54376Y437643D01*
Y439393D01*
G01X51876Y441618D02*
X51959Y441285D01*
X52168Y441035D01*
X52418Y440868D01*
X52751Y440743D01*
X53126Y440701D01*
X53501Y440743D01*
X53834Y440868D01*
X54084Y441035D01*
X54293Y441285D01*
X54376Y441618D01*
X54293Y441951D01*
X54084Y442201D01*
X53834Y442368D01*
X53501Y442493D01*
X53126Y442535D01*
X52751Y442493D01*
X52418Y442368D01*
X52168Y442201D01*
X51959Y441951D01*
X51876Y441618D01*
G01X53876Y443801D02*
X54168Y444051D01*
X54334Y444385D01*
X54376Y444760D01*
X54334Y445093D01*
X54126Y445426D01*
X53876Y445635D01*
X53626Y445676D01*
X53334Y445593D01*
X53126Y445301D01*
X53043Y445010D01*
Y444635D01*
G01Y445010D02*
X52918Y445260D01*
X52709Y445468D01*
X52459Y445551D01*
X52209Y445468D01*
X52001Y445260D01*
X51876Y444885D01*
X51918Y444510D01*
X52084Y444135D01*
G01X53733Y420017D02*
X51233D01*
Y421058D01*
X51358Y421392D01*
X51525Y421600D01*
X51858Y421683D01*
X52191Y421600D01*
X52400Y421350D01*
X52525Y421058D01*
Y420017D01*
G01Y421058D02*
X53733Y421683D01*
G01Y423950D02*
X51233D01*
X51733Y423450D01*
G01X53733D02*
Y424450D01*
G01X52691Y426258D02*
X52400Y426550D01*
X52233Y426800D01*
X52150Y427133D01*
X52233Y427425D01*
X52400Y427633D01*
X52650Y427800D01*
X52941Y427842D01*
X53191Y427800D01*
X53441Y427633D01*
X53650Y427383D01*
X53733Y427092D01*
X53650Y426758D01*
X53400Y426467D01*
X53025Y426300D01*
X52608Y426258D01*
X52066Y426342D01*
X51775Y426467D01*
X51483Y426675D01*
X51275Y426967D01*
X51233Y427258D01*
X51316Y427550D01*
X51525Y427758D01*
G01X53733Y430150D02*
X53691Y430442D01*
X53566Y430775D01*
X53358Y430983D01*
X53066Y431067D01*
X52775Y430983D01*
X52525Y430733D01*
X52400Y430358D01*
Y429942D01*
X52316Y429692D01*
X52108Y429483D01*
X51816Y429400D01*
X51525Y429525D01*
X51316Y429817D01*
X51233Y430150D01*
X51316Y430483D01*
X51525Y430775D01*
X51816Y430900D01*
X52108Y430817D01*
X52316Y430608D01*
X52400Y430358D01*
Y429942D01*
X52525Y429567D01*
X52775Y429317D01*
X53066Y429233D01*
X53358Y429317D01*
X53566Y429525D01*
X53691Y429858D01*
X53733Y430150D01*
G01X49733Y420017D02*
X47233D01*
Y421058D01*
X47358Y421392D01*
X47525Y421600D01*
X47858Y421683D01*
X48191Y421600D01*
X48400Y421350D01*
X48525Y421058D01*
Y420017D01*
G01Y421058D02*
X49733Y421683D01*
G01Y423950D02*
X47233D01*
X47733Y423450D01*
G01X49733D02*
Y424450D01*
G01Y426967D02*
X49191Y427050D01*
X48733Y427175D01*
X48316Y427342D01*
X47858Y427550D01*
X47233Y427883D01*
Y426217D01*
G01Y430150D02*
X47316Y429817D01*
X47525Y429567D01*
X47775Y429400D01*
X48108Y429275D01*
X48483Y429233D01*
X48858Y429275D01*
X49191Y429400D01*
X49441Y429567D01*
X49650Y429817D01*
X49733Y430150D01*
X49650Y430483D01*
X49441Y430733D01*
X49191Y430900D01*
X48858Y431025D01*
X48483Y431067D01*
X48108Y431025D01*
X47775Y430900D01*
X47525Y430733D01*
X47316Y430483D01*
X47233Y430150D01*
G01X45733Y420017D02*
X43233D01*
Y421058D01*
X43358Y421392D01*
X43525Y421600D01*
X43858Y421683D01*
X44191Y421600D01*
X44400Y421350D01*
X44525Y421058D01*
Y420017D01*
G01Y421058D02*
X45733Y421683D01*
G01Y423950D02*
X43233D01*
X43733Y423450D01*
G01X45733D02*
Y424450D01*
G01Y426967D02*
X45191Y427050D01*
X44733Y427175D01*
X44316Y427342D01*
X43858Y427550D01*
X43233Y427883D01*
Y426217D01*
G01X45733Y430150D02*
X43233D01*
X43733Y429650D01*
G01X45733D02*
Y430650D01*
G01X41733Y420017D02*
X39233D01*
Y421058D01*
X39358Y421392D01*
X39525Y421600D01*
X39858Y421683D01*
X40191Y421600D01*
X40400Y421350D01*
X40525Y421058D01*
Y420017D01*
G01Y421058D02*
X41733Y421683D01*
G01Y423950D02*
X39233D01*
X39733Y423450D01*
G01X41733D02*
Y424450D01*
G01Y426967D02*
X41191Y427050D01*
X40733Y427175D01*
X40316Y427342D01*
X39858Y427550D01*
X39233Y427883D01*
Y426217D01*
G01X39650Y429358D02*
X39400Y429608D01*
X39275Y429900D01*
X39233Y430233D01*
X39316Y430650D01*
X39525Y430942D01*
X39775Y431025D01*
X40025Y430983D01*
X40233Y430817D01*
X40650Y429983D01*
X40941Y429608D01*
X41358Y429358D01*
X41733Y429275D01*
Y431025D01*
G01X37733Y411417D02*
X35233D01*
Y412458D01*
X35358Y412792D01*
X35525Y413000D01*
X35858Y413083D01*
X36191Y413000D01*
X36400Y412750D01*
X36525Y412458D01*
Y411417D01*
G01Y412458D02*
X37733Y413083D01*
G01Y415350D02*
X35233D01*
X35733Y414850D01*
G01X37733D02*
Y415850D01*
G01Y418367D02*
X37191Y418450D01*
X36733Y418575D01*
X36316Y418742D01*
X35858Y418950D01*
X35233Y419283D01*
Y417617D01*
G01X37233Y420633D02*
X37525Y420883D01*
X37691Y421217D01*
X37733Y421592D01*
X37691Y421925D01*
X37483Y422258D01*
X37233Y422467D01*
X36983Y422508D01*
X36691Y422425D01*
X36483Y422133D01*
X36400Y421842D01*
Y421467D01*
G01Y421842D02*
X36275Y422092D01*
X36066Y422300D01*
X35816Y422383D01*
X35566Y422300D01*
X35358Y422092D01*
X35233Y421717D01*
X35275Y421342D01*
X35441Y420967D01*
G01X33733Y411417D02*
X31233D01*
Y412458D01*
X31358Y412792D01*
X31525Y413000D01*
X31858Y413083D01*
X32191Y413000D01*
X32400Y412750D01*
X32525Y412458D01*
Y411417D01*
G01Y412458D02*
X33733Y413083D01*
G01Y415350D02*
X31233D01*
X31733Y414850D01*
G01X33733D02*
Y415850D01*
G01Y418367D02*
X33191Y418450D01*
X32733Y418575D01*
X32316Y418742D01*
X31858Y418950D01*
X31233Y419283D01*
Y417617D01*
G01X33733Y422050D02*
X31233D01*
X33025Y420508D01*
Y422592D01*
G01X42046Y435325D02*
X39546D01*
Y436366D01*
X39671Y436700D01*
X39838Y436908D01*
X40171Y436991D01*
X40504Y436908D01*
X40713Y436658D01*
X40838Y436366D01*
Y435325D01*
G01Y436366D02*
X42046Y436991D01*
G01Y439258D02*
X39546D01*
X40046Y438758D01*
G01X42046D02*
Y439758D01*
G01Y442358D02*
X42004Y442650D01*
X41879Y442983D01*
X41671Y443191D01*
X41379Y443275D01*
X41088Y443191D01*
X40838Y442941D01*
X40713Y442566D01*
Y442150D01*
X40629Y441900D01*
X40421Y441691D01*
X40129Y441608D01*
X39838Y441733D01*
X39629Y442025D01*
X39546Y442358D01*
X39629Y442691D01*
X39838Y442983D01*
X40129Y443108D01*
X40421Y443025D01*
X40629Y442816D01*
X40713Y442566D01*
Y442150D01*
X40838Y441775D01*
X41088Y441525D01*
X41379Y441441D01*
X41671Y441525D01*
X41879Y441733D01*
X42004Y442066D01*
X42046Y442358D01*
G01X39546Y445458D02*
X39629Y445125D01*
X39838Y444875D01*
X40088Y444708D01*
X40421Y444583D01*
X40796Y444541D01*
X41171Y444583D01*
X41504Y444708D01*
X41754Y444875D01*
X41963Y445125D01*
X42046Y445458D01*
X41963Y445791D01*
X41754Y446041D01*
X41504Y446208D01*
X41171Y446333D01*
X40796Y446375D01*
X40421Y446333D01*
X40088Y446208D01*
X39838Y446041D01*
X39629Y445791D01*
X39546Y445458D01*
G01X25700Y443817D02*
X23200D01*
Y444858D01*
X23325Y445192D01*
X23492Y445400D01*
X23825Y445483D01*
X24158Y445400D01*
X24367Y445150D01*
X24492Y444858D01*
Y443817D01*
G01Y444858D02*
X25700Y445483D01*
G01X25200Y446833D02*
X25492Y447083D01*
X25658Y447417D01*
X25700Y447792D01*
X25658Y448125D01*
X25450Y448458D01*
X25200Y448667D01*
X24950Y448708D01*
X24658Y448625D01*
X24450Y448333D01*
X24367Y448042D01*
Y447667D01*
G01Y448042D02*
X24242Y448292D01*
X24033Y448500D01*
X23783Y448583D01*
X23533Y448500D01*
X23325Y448292D01*
X23200Y447917D01*
X23242Y447542D01*
X23408Y447167D01*
G01X23200Y450850D02*
X23283Y450517D01*
X23492Y450267D01*
X23742Y450100D01*
X24075Y449975D01*
X24450Y449933D01*
X24825Y449975D01*
X25158Y450100D01*
X25408Y450267D01*
X25617Y450517D01*
X25700Y450850D01*
X25617Y451183D01*
X25408Y451433D01*
X25158Y451600D01*
X24825Y451725D01*
X24450Y451767D01*
X24075Y451725D01*
X23742Y451600D01*
X23492Y451433D01*
X23283Y451183D01*
X23200Y450850D01*
G01X25408Y453242D02*
X25617Y453533D01*
X25700Y453867D01*
X25617Y454200D01*
X25367Y454492D01*
X24992Y454700D01*
X24617Y454783D01*
X24158D01*
X23783Y454700D01*
X23450Y454492D01*
X23283Y454242D01*
X23200Y453950D01*
X23283Y453617D01*
X23450Y453367D01*
X23700Y453200D01*
X24033Y453117D01*
X24325Y453200D01*
X24617Y453408D01*
X24783Y453658D01*
X24825Y453950D01*
X24742Y454283D01*
X24533Y454533D01*
X24158Y454783D01*
G01X45500Y455517D02*
X43000D01*
Y456558D01*
X43125Y456892D01*
X43292Y457100D01*
X43625Y457183D01*
X43958Y457100D01*
X44167Y456850D01*
X44292Y456558D01*
Y455517D01*
G01Y456558D02*
X45500Y457183D01*
G01X45000Y458533D02*
X45292Y458783D01*
X45458Y459117D01*
X45500Y459492D01*
X45458Y459825D01*
X45250Y460158D01*
X45000Y460367D01*
X44750Y460408D01*
X44458Y460325D01*
X44250Y460033D01*
X44167Y459742D01*
Y459367D01*
G01Y459742D02*
X44042Y459992D01*
X43833Y460200D01*
X43583Y460283D01*
X43333Y460200D01*
X43125Y459992D01*
X43000Y459617D01*
X43042Y459242D01*
X43208Y458867D01*
G01X44458Y461758D02*
X44167Y462050D01*
X44000Y462300D01*
X43917Y462633D01*
X44000Y462925D01*
X44167Y463133D01*
X44417Y463300D01*
X44708Y463342D01*
X44958Y463300D01*
X45208Y463133D01*
X45417Y462883D01*
X45500Y462592D01*
X45417Y462258D01*
X45167Y461967D01*
X44792Y461800D01*
X44375Y461758D01*
X43833Y461842D01*
X43542Y461967D01*
X43250Y462175D01*
X43042Y462467D01*
X43000Y462758D01*
X43083Y463050D01*
X43292Y463258D01*
G01X45500Y465567D02*
X44958Y465650D01*
X44500Y465775D01*
X44083Y465942D01*
X43625Y466150D01*
X43000Y466483D01*
Y464817D01*
G01X58500Y434517D02*
X56000D01*
Y435558D01*
X56125Y435892D01*
X56292Y436100D01*
X56625Y436183D01*
X56958Y436100D01*
X57167Y435850D01*
X57292Y435558D01*
Y434517D01*
G01Y435558D02*
X58500Y436183D01*
G01Y438950D02*
X56000D01*
X57792Y437408D01*
Y439492D01*
G01X56000Y441550D02*
X56083Y441217D01*
X56292Y440967D01*
X56542Y440800D01*
X56875Y440675D01*
X57250Y440633D01*
X57625Y440675D01*
X57958Y440800D01*
X58208Y440967D01*
X58417Y441217D01*
X58500Y441550D01*
X58417Y441883D01*
X58208Y442133D01*
X57958Y442300D01*
X57625Y442425D01*
X57250Y442467D01*
X56875Y442425D01*
X56542Y442300D01*
X56292Y442133D01*
X56083Y441883D01*
X56000Y441550D01*
G01Y444650D02*
X56083Y444317D01*
X56292Y444067D01*
X56542Y443900D01*
X56875Y443775D01*
X57250Y443733D01*
X57625Y443775D01*
X57958Y443900D01*
X58208Y444067D01*
X58417Y444317D01*
X58500Y444650D01*
X58417Y444983D01*
X58208Y445233D01*
X57958Y445400D01*
X57625Y445525D01*
X57250Y445567D01*
X56875Y445525D01*
X56542Y445400D01*
X56292Y445233D01*
X56083Y444983D01*
X56000Y444650D01*
G01X62350Y440367D02*
X59850D01*
Y441408D01*
X59975Y441742D01*
X60142Y441950D01*
X60475Y442033D01*
X60808Y441950D01*
X61017Y441700D01*
X61142Y441408D01*
Y440367D01*
G01Y441408D02*
X62350Y442033D01*
G01Y444800D02*
X59850D01*
X61642Y443258D01*
Y445342D01*
G01X59850Y447400D02*
X59933Y447067D01*
X60142Y446817D01*
X60392Y446650D01*
X60725Y446525D01*
X61100Y446483D01*
X61475Y446525D01*
X61808Y446650D01*
X62058Y446817D01*
X62267Y447067D01*
X62350Y447400D01*
X62267Y447733D01*
X62058Y447983D01*
X61808Y448150D01*
X61475Y448275D01*
X61100Y448317D01*
X60725Y448275D01*
X60392Y448150D01*
X60142Y447983D01*
X59933Y447733D01*
X59850Y447400D01*
G01X62058Y449792D02*
X62267Y450083D01*
X62350Y450417D01*
X62267Y450750D01*
X62017Y451042D01*
X61642Y451250D01*
X61267Y451333D01*
X60808D01*
X60433Y451250D01*
X60100Y451042D01*
X59933Y450792D01*
X59850Y450500D01*
X59933Y450167D01*
X60100Y449917D01*
X60350Y449750D01*
X60683Y449667D01*
X60975Y449750D01*
X61267Y449958D01*
X61433Y450208D01*
X61475Y450500D01*
X61392Y450833D01*
X61183Y451083D01*
X60808Y451333D01*
G01X71034Y440217D02*
X68534D01*
Y441258D01*
X68659Y441592D01*
X68826Y441800D01*
X69159Y441883D01*
X69492Y441800D01*
X69701Y441550D01*
X69826Y441258D01*
Y440217D01*
G01Y441258D02*
X71034Y441883D01*
G01Y444650D02*
X68534D01*
X70326Y443108D01*
Y445192D01*
G01X71034Y447250D02*
X68534D01*
X69034Y446750D01*
G01X71034D02*
Y447750D01*
G01X68951Y449558D02*
X68701Y449808D01*
X68576Y450100D01*
X68534Y450433D01*
X68617Y450850D01*
X68826Y451142D01*
X69076Y451225D01*
X69326Y451183D01*
X69534Y451017D01*
X69951Y450183D01*
X70242Y449808D01*
X70659Y449558D01*
X71034Y449475D01*
Y451225D01*
G01X70720Y420497D02*
Y417997D01*
G01X69762Y420497D02*
X71678D01*
G01X72987Y417997D02*
Y420497D01*
X73987D01*
X74320Y420372D01*
X74570Y420080D01*
X74653Y419747D01*
X74570Y419414D01*
X74362Y419164D01*
X73987Y419039D01*
X72987D01*
G01X76003Y418372D02*
X76253Y418164D01*
X76545Y418039D01*
X76920Y417997D01*
X77295Y418080D01*
X77587Y418247D01*
X77795Y418539D01*
X77837Y418872D01*
X77753Y419205D01*
X77545Y419414D01*
X77253Y419580D01*
X76962Y419622D01*
X76670Y419580D01*
X76295Y419414D01*
X76420Y420497D01*
X77545D01*
G01X79103Y418497D02*
X79353Y418205D01*
X79687Y418039D01*
X80062Y417997D01*
X80395Y418039D01*
X80728Y418247D01*
X80937Y418497D01*
X80978Y418747D01*
X80895Y419039D01*
X80603Y419247D01*
X80312Y419330D01*
X79937D01*
G01X80312D02*
X80562Y419455D01*
X80770Y419664D01*
X80853Y419914D01*
X80770Y420164D01*
X80562Y420372D01*
X80187Y420497D01*
X79812Y420455D01*
X79437Y420289D01*
G01X32433Y428150D02*
X34933D01*
G01X32433Y427192D02*
Y429108D01*
G01X34933Y430417D02*
X32433D01*
Y431417D01*
X32558Y431750D01*
X32850Y432000D01*
X33183Y432083D01*
X33516Y432000D01*
X33766Y431792D01*
X33891Y431417D01*
Y430417D01*
G01X34933Y434350D02*
X32433D01*
X32933Y433850D01*
G01X34933D02*
Y434850D01*
G01X34433Y436533D02*
X34725Y436783D01*
X34891Y437117D01*
X34933Y437492D01*
X34891Y437825D01*
X34683Y438158D01*
X34433Y438367D01*
X34183Y438408D01*
X33891Y438325D01*
X33683Y438033D01*
X33600Y437742D01*
Y437367D01*
G01Y437742D02*
X33475Y437992D01*
X33266Y438200D01*
X33016Y438283D01*
X32766Y438200D01*
X32558Y437992D01*
X32433Y437617D01*
X32475Y437242D01*
X32641Y436867D01*
G01X28133Y427750D02*
X30633D01*
G01X28133Y426792D02*
Y428708D01*
G01X30633Y430017D02*
X28133D01*
Y431017D01*
X28258Y431350D01*
X28550Y431600D01*
X28883Y431683D01*
X29216Y431600D01*
X29466Y431392D01*
X29591Y431017D01*
Y430017D01*
G01X30633Y433950D02*
X28133D01*
X28633Y433450D01*
G01X30633D02*
Y434450D01*
G01Y437550D02*
X28133D01*
X29925Y436008D01*
Y438092D01*
G01X22933Y409840D02*
X25433D01*
G01X22933Y408882D02*
Y410798D01*
G01X25433Y412107D02*
X22933D01*
Y413107D01*
X23058Y413440D01*
X23350Y413690D01*
X23683Y413773D01*
X24016Y413690D01*
X24266Y413482D01*
X24391Y413107D01*
Y412107D01*
G01X25433Y416040D02*
X22933D01*
X23433Y415540D01*
G01X25433D02*
Y416540D01*
G01Y419140D02*
X25391Y419432D01*
X25266Y419765D01*
X25058Y419973D01*
X24766Y420057D01*
X24475Y419973D01*
X24225Y419723D01*
X24100Y419348D01*
Y418932D01*
X24016Y418682D01*
X23808Y418473D01*
X23516Y418390D01*
X23225Y418515D01*
X23016Y418807D01*
X22933Y419140D01*
X23016Y419473D01*
X23225Y419765D01*
X23516Y419890D01*
X23808Y419807D01*
X24016Y419598D01*
X24100Y419348D01*
Y418932D01*
X24225Y418557D01*
X24475Y418307D01*
X24766Y418223D01*
X25058Y418307D01*
X25266Y418515D01*
X25391Y418848D01*
X25433Y419140D01*
G01X25141Y421532D02*
X25350Y421823D01*
X25433Y422157D01*
X25350Y422490D01*
X25100Y422782D01*
X24725Y422990D01*
X24350Y423073D01*
X23891D01*
X23516Y422990D01*
X23183Y422782D01*
X23016Y422532D01*
X22933Y422240D01*
X23016Y421907D01*
X23183Y421657D01*
X23433Y421490D01*
X23766Y421407D01*
X24058Y421490D01*
X24350Y421698D01*
X24516Y421948D01*
X24558Y422240D01*
X24475Y422573D01*
X24266Y422823D01*
X23891Y423073D01*
G01X24463Y425250D02*
X26963D01*
G01X24463Y424292D02*
Y426208D01*
G01X26963Y427517D02*
X24463D01*
Y428517D01*
X24588Y428850D01*
X24880Y429100D01*
X25213Y429183D01*
X25546Y429100D01*
X25796Y428892D01*
X25921Y428517D01*
Y427517D01*
G01X26963Y431450D02*
X24463D01*
X24963Y430950D01*
G01X26963D02*
Y431950D01*
G01Y434550D02*
X26921Y434842D01*
X26796Y435175D01*
X26588Y435383D01*
X26296Y435467D01*
X26005Y435383D01*
X25755Y435133D01*
X25630Y434758D01*
Y434342D01*
X25546Y434092D01*
X25338Y433883D01*
X25046Y433800D01*
X24755Y433925D01*
X24546Y434217D01*
X24463Y434550D01*
X24546Y434883D01*
X24755Y435175D01*
X25046Y435300D01*
X25338Y435217D01*
X25546Y435008D01*
X25630Y434758D01*
Y434342D01*
X25755Y433967D01*
X26005Y433717D01*
X26296Y433633D01*
X26588Y433717D01*
X26796Y433925D01*
X26921Y434258D01*
X26963Y434550D01*
G01X25921Y436858D02*
X25630Y437150D01*
X25463Y437400D01*
X25380Y437733D01*
X25463Y438025D01*
X25630Y438233D01*
X25880Y438400D01*
X26171Y438442D01*
X26421Y438400D01*
X26671Y438233D01*
X26880Y437983D01*
X26963Y437692D01*
X26880Y437358D01*
X26630Y437067D01*
X26255Y436900D01*
X25838Y436858D01*
X25296Y436942D01*
X25005Y437067D01*
X24713Y437275D01*
X24505Y437567D01*
X24463Y437858D01*
X24546Y438150D01*
X24755Y438358D01*
G01X27433Y410000D02*
X29933D01*
G01X27433Y409042D02*
Y410958D01*
G01X29933Y412267D02*
X27433D01*
Y413267D01*
X27558Y413600D01*
X27850Y413850D01*
X28183Y413933D01*
X28516Y413850D01*
X28766Y413642D01*
X28891Y413267D01*
Y412267D01*
G01X29933Y416200D02*
X27433D01*
X27933Y415700D01*
G01X29933D02*
Y416700D01*
G01Y419300D02*
X29891Y419592D01*
X29766Y419925D01*
X29558Y420133D01*
X29266Y420217D01*
X28975Y420133D01*
X28725Y419883D01*
X28600Y419508D01*
Y419092D01*
X28516Y418842D01*
X28308Y418633D01*
X28016Y418550D01*
X27725Y418675D01*
X27516Y418967D01*
X27433Y419300D01*
X27516Y419633D01*
X27725Y419925D01*
X28016Y420050D01*
X28308Y419967D01*
X28516Y419758D01*
X28600Y419508D01*
Y419092D01*
X28725Y418717D01*
X28975Y418467D01*
X29266Y418383D01*
X29558Y418467D01*
X29766Y418675D01*
X29891Y419008D01*
X29933Y419300D01*
G01Y422317D02*
X29391Y422400D01*
X28933Y422525D01*
X28516Y422692D01*
X28058Y422900D01*
X27433Y423233D01*
Y421567D01*
G01X19083Y433140D02*
X21583D01*
G01X19083Y432182D02*
Y434098D01*
G01X21583Y435407D02*
X19083D01*
Y436407D01*
X19208Y436740D01*
X19500Y436990D01*
X19833Y437073D01*
X20166Y436990D01*
X20416Y436782D01*
X20541Y436407D01*
Y435407D01*
G01X21583Y439340D02*
X19083D01*
X19583Y438840D01*
G01X21583D02*
Y439840D01*
G01Y442440D02*
X21541Y442732D01*
X21416Y443065D01*
X21208Y443273D01*
X20916Y443357D01*
X20625Y443273D01*
X20375Y443023D01*
X20250Y442648D01*
Y442232D01*
X20166Y441982D01*
X19958Y441773D01*
X19666Y441690D01*
X19375Y441815D01*
X19166Y442107D01*
X19083Y442440D01*
X19166Y442773D01*
X19375Y443065D01*
X19666Y443190D01*
X19958Y443107D01*
X20166Y442898D01*
X20250Y442648D01*
Y442232D01*
X20375Y441857D01*
X20625Y441607D01*
X20916Y441523D01*
X21208Y441607D01*
X21416Y441815D01*
X21541Y442148D01*
X21583Y442440D01*
G01Y445540D02*
X21541Y445832D01*
X21416Y446165D01*
X21208Y446373D01*
X20916Y446457D01*
X20625Y446373D01*
X20375Y446123D01*
X20250Y445748D01*
Y445332D01*
X20166Y445082D01*
X19958Y444873D01*
X19666Y444790D01*
X19375Y444915D01*
X19166Y445207D01*
X19083Y445540D01*
X19166Y445873D01*
X19375Y446165D01*
X19666Y446290D01*
X19958Y446207D01*
X20166Y445998D01*
X20250Y445748D01*
Y445332D01*
X20375Y444957D01*
X20625Y444707D01*
X20916Y444623D01*
X21208Y444707D01*
X21416Y444915D01*
X21541Y445248D01*
X21583Y445540D01*
G01X28800Y461000D02*
Y458500D01*
G01X27842Y461000D02*
X29758D01*
G01X31067Y458500D02*
Y461000D01*
X32067D01*
X32400Y460875D01*
X32650Y460583D01*
X32733Y460250D01*
X32650Y459917D01*
X32442Y459667D01*
X32067Y459542D01*
X31067D01*
G01X35000Y458500D02*
Y461000D01*
X34500Y460500D01*
G01Y458500D02*
X35500D01*
G01X37392Y458792D02*
X37683Y458583D01*
X38017Y458500D01*
X38350Y458583D01*
X38642Y458833D01*
X38850Y459208D01*
X38933Y459583D01*
Y460042D01*
X38850Y460417D01*
X38642Y460750D01*
X38392Y460917D01*
X38100Y461000D01*
X37767Y460917D01*
X37517Y460750D01*
X37350Y460500D01*
X37267Y460167D01*
X37350Y459875D01*
X37558Y459583D01*
X37808Y459417D01*
X38100Y459375D01*
X38433Y459458D01*
X38683Y459667D01*
X38933Y460042D01*
G01X41200Y458500D02*
Y461000D01*
X40700Y460500D01*
G01Y458500D02*
X41700D01*
G01X57333Y509517D02*
X54833D01*
Y510558D01*
X54958Y510892D01*
X55125Y511100D01*
X55458Y511183D01*
X55791Y511100D01*
X56000Y510850D01*
X56125Y510558D01*
Y509517D01*
G01Y510558D02*
X57333Y511183D01*
G01X55250Y512658D02*
X55000Y512908D01*
X54875Y513200D01*
X54833Y513533D01*
X54916Y513950D01*
X55125Y514242D01*
X55375Y514325D01*
X55625Y514283D01*
X55833Y514117D01*
X56250Y513283D01*
X56541Y512908D01*
X56958Y512658D01*
X57333Y512575D01*
Y514325D01*
G01X55250Y515758D02*
X55000Y516008D01*
X54875Y516300D01*
X54833Y516633D01*
X54916Y517050D01*
X55125Y517342D01*
X55375Y517425D01*
X55625Y517383D01*
X55833Y517217D01*
X56250Y516383D01*
X56541Y516008D01*
X56958Y515758D01*
X57333Y515675D01*
Y517425D01*
G01X56291Y518858D02*
X56000Y519150D01*
X55833Y519400D01*
X55750Y519733D01*
X55833Y520025D01*
X56000Y520233D01*
X56250Y520400D01*
X56541Y520442D01*
X56791Y520400D01*
X57041Y520233D01*
X57250Y519983D01*
X57333Y519692D01*
X57250Y519358D01*
X57000Y519067D01*
X56625Y518900D01*
X56208Y518858D01*
X55666Y518942D01*
X55375Y519067D01*
X55083Y519275D01*
X54875Y519567D01*
X54833Y519858D01*
X54916Y520150D01*
X55125Y520358D01*
G01X57334Y497017D02*
X54834D01*
Y498058D01*
X54959Y498392D01*
X55126Y498600D01*
X55459Y498683D01*
X55792Y498600D01*
X56001Y498350D01*
X56126Y498058D01*
Y497017D01*
G01Y498058D02*
X57334Y498683D01*
G01X55251Y500158D02*
X55001Y500408D01*
X54876Y500700D01*
X54834Y501033D01*
X54917Y501450D01*
X55126Y501742D01*
X55376Y501825D01*
X55626Y501783D01*
X55834Y501617D01*
X56251Y500783D01*
X56542Y500408D01*
X56959Y500158D01*
X57334Y500075D01*
Y501825D01*
G01X55251Y503258D02*
X55001Y503508D01*
X54876Y503800D01*
X54834Y504133D01*
X54917Y504550D01*
X55126Y504842D01*
X55376Y504925D01*
X55626Y504883D01*
X55834Y504717D01*
X56251Y503883D01*
X56542Y503508D01*
X56959Y503258D01*
X57334Y503175D01*
Y504925D01*
G01X56959Y506233D02*
X57167Y506483D01*
X57292Y506775D01*
X57334Y507150D01*
X57251Y507525D01*
X57084Y507817D01*
X56792Y508025D01*
X56459Y508067D01*
X56126Y507983D01*
X55917Y507775D01*
X55751Y507483D01*
X55709Y507192D01*
X55751Y506900D01*
X55917Y506525D01*
X54834Y506650D01*
Y507775D01*
G01X61333Y509517D02*
X58833D01*
Y510558D01*
X58958Y510892D01*
X59125Y511100D01*
X59458Y511183D01*
X59791Y511100D01*
X60000Y510850D01*
X60125Y510558D01*
Y509517D01*
G01Y510558D02*
X61333Y511183D01*
G01Y513450D02*
X58833D01*
X59333Y512950D01*
G01X61333D02*
Y513950D01*
G01Y517050D02*
X58833D01*
X60625Y515508D01*
Y517592D01*
G01X61333Y520150D02*
X58833D01*
X60625Y518608D01*
Y520692D01*
G01X61334Y497017D02*
X58834D01*
Y498058D01*
X58959Y498392D01*
X59126Y498600D01*
X59459Y498683D01*
X59792Y498600D01*
X60001Y498350D01*
X60126Y498058D01*
Y497017D01*
G01Y498058D02*
X61334Y498683D01*
G01X59251Y500158D02*
X59001Y500408D01*
X58876Y500700D01*
X58834Y501033D01*
X58917Y501450D01*
X59126Y501742D01*
X59376Y501825D01*
X59626Y501783D01*
X59834Y501617D01*
X60251Y500783D01*
X60542Y500408D01*
X60959Y500158D01*
X61334Y500075D01*
Y501825D01*
G01Y504050D02*
X58834D01*
X59334Y503550D01*
G01X61334D02*
Y504550D01*
G01X60834Y506233D02*
X61126Y506483D01*
X61292Y506817D01*
X61334Y507192D01*
X61292Y507525D01*
X61084Y507858D01*
X60834Y508067D01*
X60584Y508108D01*
X60292Y508025D01*
X60084Y507733D01*
X60001Y507442D01*
Y507067D01*
G01Y507442D02*
X59876Y507692D01*
X59667Y507900D01*
X59417Y507983D01*
X59167Y507900D01*
X58959Y507692D01*
X58834Y507317D01*
X58876Y506942D01*
X59042Y506567D01*
G01X65333Y509517D02*
X62833D01*
Y510558D01*
X62958Y510892D01*
X63125Y511100D01*
X63458Y511183D01*
X63791Y511100D01*
X64000Y510850D01*
X64125Y510558D01*
Y509517D01*
G01Y510558D02*
X65333Y511183D01*
G01X63250Y512658D02*
X63000Y512908D01*
X62875Y513200D01*
X62833Y513533D01*
X62916Y513950D01*
X63125Y514242D01*
X63375Y514325D01*
X63625Y514283D01*
X63833Y514117D01*
X64250Y513283D01*
X64541Y512908D01*
X64958Y512658D01*
X65333Y512575D01*
Y514325D01*
G01Y516550D02*
X62833D01*
X63333Y516050D01*
G01X65333D02*
Y517050D01*
G01Y520150D02*
X62833D01*
X64625Y518608D01*
Y520692D01*
G01X53334Y497017D02*
X50834D01*
Y498058D01*
X50959Y498392D01*
X51126Y498600D01*
X51459Y498683D01*
X51792Y498600D01*
X52001Y498350D01*
X52126Y498058D01*
Y497017D01*
G01Y498058D02*
X53334Y498683D01*
G01X51251Y500158D02*
X51001Y500408D01*
X50876Y500700D01*
X50834Y501033D01*
X50917Y501450D01*
X51126Y501742D01*
X51376Y501825D01*
X51626Y501783D01*
X51834Y501617D01*
X52251Y500783D01*
X52542Y500408D01*
X52959Y500158D01*
X53334Y500075D01*
Y501825D01*
G01Y504050D02*
X50834D01*
X51334Y503550D01*
G01X53334D02*
Y504550D01*
G01X52959Y506233D02*
X53167Y506483D01*
X53292Y506775D01*
X53334Y507150D01*
X53251Y507525D01*
X53084Y507817D01*
X52792Y508025D01*
X52459Y508067D01*
X52126Y507983D01*
X51917Y507775D01*
X51751Y507483D01*
X51709Y507192D01*
X51751Y506900D01*
X51917Y506525D01*
X50834Y506650D01*
Y507775D01*
G01X73373Y504479D02*
X77373D01*
Y511879D01*
G01X53334Y509517D02*
X50834D01*
Y510558D01*
X50959Y510892D01*
X51126Y511100D01*
X51459Y511183D01*
X51792Y511100D01*
X52001Y510850D01*
X52126Y510558D01*
Y509517D01*
G01Y510558D02*
X53334Y511183D01*
G01X51251Y512658D02*
X51001Y512908D01*
X50876Y513200D01*
X50834Y513533D01*
X50917Y513950D01*
X51126Y514242D01*
X51376Y514325D01*
X51626Y514283D01*
X51834Y514117D01*
X52251Y513283D01*
X52542Y512908D01*
X52959Y512658D01*
X53334Y512575D01*
Y514325D01*
G01Y516550D02*
X50834D01*
X51334Y516050D01*
G01X53334D02*
Y517050D01*
G01X52292Y518858D02*
X52001Y519150D01*
X51834Y519400D01*
X51751Y519733D01*
X51834Y520025D01*
X52001Y520233D01*
X52251Y520400D01*
X52542Y520442D01*
X52792Y520400D01*
X53042Y520233D01*
X53251Y519983D01*
X53334Y519692D01*
X53251Y519358D01*
X53001Y519067D01*
X52626Y518900D01*
X52209Y518858D01*
X51667Y518942D01*
X51376Y519067D01*
X51084Y519275D01*
X50876Y519567D01*
X50834Y519858D01*
X50917Y520150D01*
X51126Y520358D01*
G01X73405Y512077D02*
X77405D01*
Y519477D01*
G01X49334Y497017D02*
X46834D01*
Y498058D01*
X46959Y498392D01*
X47126Y498600D01*
X47459Y498683D01*
X47792Y498600D01*
X48001Y498350D01*
X48126Y498058D01*
Y497017D01*
G01Y498058D02*
X49334Y498683D01*
G01X47251Y500158D02*
X47001Y500408D01*
X46876Y500700D01*
X46834Y501033D01*
X46917Y501450D01*
X47126Y501742D01*
X47376Y501825D01*
X47626Y501783D01*
X47834Y501617D01*
X48251Y500783D01*
X48542Y500408D01*
X48959Y500158D01*
X49334Y500075D01*
Y501825D01*
G01X47251Y503258D02*
X47001Y503508D01*
X46876Y503800D01*
X46834Y504133D01*
X46917Y504550D01*
X47126Y504842D01*
X47376Y504925D01*
X47626Y504883D01*
X47834Y504717D01*
X48251Y503883D01*
X48542Y503508D01*
X48959Y503258D01*
X49334Y503175D01*
Y504925D01*
G01X46834Y507150D02*
X46917Y506817D01*
X47126Y506567D01*
X47376Y506400D01*
X47709Y506275D01*
X48084Y506233D01*
X48459Y506275D01*
X48792Y506400D01*
X49042Y506567D01*
X49251Y506817D01*
X49334Y507150D01*
X49251Y507483D01*
X49042Y507733D01*
X48792Y507900D01*
X48459Y508025D01*
X48084Y508067D01*
X47709Y508025D01*
X47376Y507900D01*
X47126Y507733D01*
X46917Y507483D01*
X46834Y507150D01*
G01X67900Y504600D02*
X71900D01*
Y512000D01*
G01X49334Y509517D02*
X46834D01*
Y510558D01*
X46959Y510892D01*
X47126Y511100D01*
X47459Y511183D01*
X47792Y511100D01*
X48001Y510850D01*
X48126Y510558D01*
Y509517D01*
G01Y510558D02*
X49334Y511183D01*
G01X47251Y512658D02*
X47001Y512908D01*
X46876Y513200D01*
X46834Y513533D01*
X46917Y513950D01*
X47126Y514242D01*
X47376Y514325D01*
X47626Y514283D01*
X47834Y514117D01*
X48251Y513283D01*
X48542Y512908D01*
X48959Y512658D01*
X49334Y512575D01*
Y514325D01*
G01X47251Y515758D02*
X47001Y516008D01*
X46876Y516300D01*
X46834Y516633D01*
X46917Y517050D01*
X47126Y517342D01*
X47376Y517425D01*
X47626Y517383D01*
X47834Y517217D01*
X48251Y516383D01*
X48542Y516008D01*
X48959Y515758D01*
X49334Y515675D01*
Y517425D01*
G01Y519650D02*
X46834D01*
X47334Y519150D01*
G01X49334D02*
Y520150D01*
G01X67778Y512077D02*
X71778D01*
Y519477D01*
G01X75617Y501800D02*
Y499300D01*
X77283D01*
G01X80383D02*
X78717D01*
Y501800D01*
X80383D01*
G01X79717Y500592D02*
X78717D01*
G01X81733Y499300D02*
Y501800D01*
X82567D01*
X82900Y501675D01*
X83150Y501508D01*
X83358Y501258D01*
X83525Y500967D01*
X83567Y500550D01*
X83525Y500133D01*
X83358Y499842D01*
X83150Y499592D01*
X82900Y499425D01*
X82567Y499300D01*
X81733D01*
G01X84958Y500342D02*
X85250Y500633D01*
X85500Y500800D01*
X85833Y500883D01*
X86125Y500800D01*
X86333Y500633D01*
X86500Y500383D01*
X86542Y500092D01*
X86500Y499842D01*
X86333Y499592D01*
X86083Y499383D01*
X85792Y499300D01*
X85458Y499383D01*
X85167Y499633D01*
X85000Y500008D01*
X84958Y500425D01*
X85042Y500967D01*
X85167Y501258D01*
X85375Y501550D01*
X85667Y501758D01*
X85958Y501800D01*
X86250Y501717D01*
X86458Y501508D01*
G01X61159Y533707D02*
X96593D01*
Y588825D01*
X61159D01*
Y533707D01*
G01X37973Y572676D02*
Y575176D01*
X39014D01*
X39348Y575051D01*
X39556Y574884D01*
X39639Y574551D01*
X39556Y574218D01*
X39306Y574009D01*
X39014Y573884D01*
X37973D01*
G01X39014D02*
X39639Y572676D01*
G01X41114Y574759D02*
X41364Y575009D01*
X41656Y575134D01*
X41989Y575176D01*
X42406Y575093D01*
X42698Y574884D01*
X42781Y574634D01*
X42739Y574384D01*
X42573Y574176D01*
X41739Y573759D01*
X41364Y573468D01*
X41114Y573051D01*
X41031Y572676D01*
X42781D01*
G01X44089Y573176D02*
X44339Y572884D01*
X44673Y572718D01*
X45048Y572676D01*
X45381Y572718D01*
X45714Y572926D01*
X45923Y573176D01*
X45964Y573426D01*
X45881Y573718D01*
X45589Y573926D01*
X45298Y574009D01*
X44923D01*
G01X45298D02*
X45548Y574134D01*
X45756Y574343D01*
X45839Y574593D01*
X45756Y574843D01*
X45548Y575051D01*
X45173Y575176D01*
X44798Y575134D01*
X44423Y574968D01*
G01X48106Y575176D02*
X47773Y575093D01*
X47523Y574884D01*
X47356Y574634D01*
X47231Y574301D01*
X47189Y573926D01*
X47231Y573551D01*
X47356Y573218D01*
X47523Y572968D01*
X47773Y572759D01*
X48106Y572676D01*
X48439Y572759D01*
X48689Y572968D01*
X48856Y573218D01*
X48981Y573551D01*
X49023Y573926D01*
X48981Y574301D01*
X48856Y574634D01*
X48689Y574884D01*
X48439Y575093D01*
X48106Y575176D01*
G01X38806Y545876D02*
Y541876D01*
X46206D01*
G01X23125Y572581D02*
Y575081D01*
X24166D01*
X24500Y574956D01*
X24708Y574789D01*
X24791Y574456D01*
X24708Y574123D01*
X24458Y573914D01*
X24166Y573789D01*
X23125D01*
G01X24166D02*
X24791Y572581D01*
G01X26266Y574664D02*
X26516Y574914D01*
X26808Y575039D01*
X27141Y575081D01*
X27558Y574998D01*
X27850Y574789D01*
X27933Y574539D01*
X27891Y574289D01*
X27725Y574081D01*
X26891Y573664D01*
X26516Y573373D01*
X26266Y572956D01*
X26183Y572581D01*
X27933D01*
G01X29366Y574664D02*
X29616Y574914D01*
X29908Y575039D01*
X30241Y575081D01*
X30658Y574998D01*
X30950Y574789D01*
X31033Y574539D01*
X30991Y574289D01*
X30825Y574081D01*
X29991Y573664D01*
X29616Y573373D01*
X29366Y572956D01*
X29283Y572581D01*
X31033D01*
G01X32550Y572873D02*
X32841Y572664D01*
X33175Y572581D01*
X33508Y572664D01*
X33800Y572914D01*
X34008Y573289D01*
X34091Y573664D01*
Y574123D01*
X34008Y574498D01*
X33800Y574831D01*
X33550Y574998D01*
X33258Y575081D01*
X32925Y574998D01*
X32675Y574831D01*
X32508Y574581D01*
X32425Y574248D01*
X32508Y573956D01*
X32716Y573664D01*
X32966Y573498D01*
X33258Y573456D01*
X33591Y573539D01*
X33841Y573748D01*
X34091Y574123D01*
G01X31358Y545881D02*
Y541881D01*
X38758D01*
G01X37954Y583953D02*
Y586453D01*
X38995D01*
X39329Y586328D01*
X39537Y586161D01*
X39620Y585828D01*
X39537Y585495D01*
X39287Y585286D01*
X38995Y585161D01*
X37954D01*
G01X38995D02*
X39620Y583953D01*
G01X41095Y586036D02*
X41345Y586286D01*
X41637Y586411D01*
X41970Y586453D01*
X42387Y586370D01*
X42679Y586161D01*
X42762Y585911D01*
X42720Y585661D01*
X42554Y585453D01*
X41720Y585036D01*
X41345Y584745D01*
X41095Y584328D01*
X41012Y583953D01*
X42762D01*
G01X44195Y586036D02*
X44445Y586286D01*
X44737Y586411D01*
X45070Y586453D01*
X45487Y586370D01*
X45779Y586161D01*
X45862Y585911D01*
X45820Y585661D01*
X45654Y585453D01*
X44820Y585036D01*
X44445Y584745D01*
X44195Y584328D01*
X44112Y583953D01*
X45862D01*
G01X48087D02*
X48379Y583995D01*
X48712Y584120D01*
X48920Y584328D01*
X49004Y584620D01*
X48920Y584911D01*
X48670Y585161D01*
X48295Y585286D01*
X47879D01*
X47629Y585370D01*
X47420Y585578D01*
X47337Y585870D01*
X47462Y586161D01*
X47754Y586370D01*
X48087Y586453D01*
X48420Y586370D01*
X48712Y586161D01*
X48837Y585870D01*
X48754Y585578D01*
X48545Y585370D01*
X48295Y585286D01*
X47879D01*
X47504Y585161D01*
X47254Y584911D01*
X47170Y584620D01*
X47254Y584328D01*
X47462Y584120D01*
X47795Y583995D01*
X48087Y583953D01*
G01X38787Y557153D02*
Y553153D01*
X46187D01*
G01X23054Y583853D02*
Y586353D01*
X24095D01*
X24429Y586228D01*
X24637Y586061D01*
X24720Y585728D01*
X24637Y585395D01*
X24387Y585186D01*
X24095Y585061D01*
X23054D01*
G01X24095D02*
X24720Y583853D01*
G01X26195Y585936D02*
X26445Y586186D01*
X26737Y586311D01*
X27070Y586353D01*
X27487Y586270D01*
X27779Y586061D01*
X27862Y585811D01*
X27820Y585561D01*
X27654Y585353D01*
X26820Y584936D01*
X26445Y584645D01*
X26195Y584228D01*
X26112Y583853D01*
X27862D01*
G01X29295Y585936D02*
X29545Y586186D01*
X29837Y586311D01*
X30170Y586353D01*
X30587Y586270D01*
X30879Y586061D01*
X30962Y585811D01*
X30920Y585561D01*
X30754Y585353D01*
X29920Y584936D01*
X29545Y584645D01*
X29295Y584228D01*
X29212Y583853D01*
X30962D01*
G01X33104D02*
X33187Y584395D01*
X33312Y584853D01*
X33479Y585270D01*
X33687Y585728D01*
X34020Y586353D01*
X32354D01*
G01X31287Y557153D02*
Y553153D01*
X38687D01*
G01X37767Y578300D02*
Y580800D01*
X38808D01*
X39142Y580675D01*
X39350Y580508D01*
X39433Y580175D01*
X39350Y579842D01*
X39100Y579633D01*
X38808Y579508D01*
X37767D01*
G01X38808D02*
X39433Y578300D01*
G01X40908Y580383D02*
X41158Y580633D01*
X41450Y580758D01*
X41783Y580800D01*
X42200Y580717D01*
X42492Y580508D01*
X42575Y580258D01*
X42533Y580008D01*
X42367Y579800D01*
X41533Y579383D01*
X41158Y579092D01*
X40908Y578675D01*
X40825Y578300D01*
X42575D01*
G01X44800D02*
Y580800D01*
X44300Y580300D01*
G01Y578300D02*
X45300D01*
G01X47900D02*
X48192Y578342D01*
X48525Y578467D01*
X48733Y578675D01*
X48817Y578967D01*
X48733Y579258D01*
X48483Y579508D01*
X48108Y579633D01*
X47692D01*
X47442Y579717D01*
X47233Y579925D01*
X47150Y580217D01*
X47275Y580508D01*
X47567Y580717D01*
X47900Y580800D01*
X48233Y580717D01*
X48525Y580508D01*
X48650Y580217D01*
X48567Y579925D01*
X48358Y579717D01*
X48108Y579633D01*
X47692D01*
X47317Y579508D01*
X47067Y579258D01*
X46983Y578967D01*
X47067Y578675D01*
X47275Y578467D01*
X47608Y578342D01*
X47900Y578300D01*
G01X38600Y551500D02*
Y547500D01*
X46000D01*
G01X22867Y578200D02*
Y580700D01*
X23908D01*
X24242Y580575D01*
X24450Y580408D01*
X24533Y580075D01*
X24450Y579742D01*
X24200Y579533D01*
X23908Y579408D01*
X22867D01*
G01X23908D02*
X24533Y578200D01*
G01X26008Y580283D02*
X26258Y580533D01*
X26550Y580658D01*
X26883Y580700D01*
X27300Y580617D01*
X27592Y580408D01*
X27675Y580158D01*
X27633Y579908D01*
X27467Y579700D01*
X26633Y579283D01*
X26258Y578992D01*
X26008Y578575D01*
X25925Y578200D01*
X27675D01*
G01X29900D02*
Y580700D01*
X29400Y580200D01*
G01Y578200D02*
X30400D01*
G01X32917D02*
X33000Y578742D01*
X33125Y579200D01*
X33292Y579617D01*
X33500Y580075D01*
X33833Y580700D01*
X32167D01*
G01X31100Y551500D02*
Y547500D01*
X38500D01*
G01X37973Y567049D02*
Y569549D01*
X39014D01*
X39348Y569424D01*
X39556Y569257D01*
X39639Y568924D01*
X39556Y568591D01*
X39306Y568382D01*
X39014Y568257D01*
X37973D01*
G01X39014D02*
X39639Y567049D01*
G01X41114Y569132D02*
X41364Y569382D01*
X41656Y569507D01*
X41989Y569549D01*
X42406Y569466D01*
X42698Y569257D01*
X42781Y569007D01*
X42739Y568757D01*
X42573Y568549D01*
X41739Y568132D01*
X41364Y567841D01*
X41114Y567424D01*
X41031Y567049D01*
X42781D01*
G01X45006Y569549D02*
X44673Y569466D01*
X44423Y569257D01*
X44256Y569007D01*
X44131Y568674D01*
X44089Y568299D01*
X44131Y567924D01*
X44256Y567591D01*
X44423Y567341D01*
X44673Y567132D01*
X45006Y567049D01*
X45339Y567132D01*
X45589Y567341D01*
X45756Y567591D01*
X45881Y567924D01*
X45923Y568299D01*
X45881Y568674D01*
X45756Y569007D01*
X45589Y569257D01*
X45339Y569466D01*
X45006Y569549D01*
G01X48106Y567049D02*
X48398Y567091D01*
X48731Y567216D01*
X48939Y567424D01*
X49023Y567716D01*
X48939Y568007D01*
X48689Y568257D01*
X48314Y568382D01*
X47898D01*
X47648Y568466D01*
X47439Y568674D01*
X47356Y568966D01*
X47481Y569257D01*
X47773Y569466D01*
X48106Y569549D01*
X48439Y569466D01*
X48731Y569257D01*
X48856Y568966D01*
X48773Y568674D01*
X48564Y568466D01*
X48314Y568382D01*
X47898D01*
X47523Y568257D01*
X47273Y568007D01*
X47189Y567716D01*
X47273Y567424D01*
X47481Y567216D01*
X47814Y567091D01*
X48106Y567049D01*
G01X38806Y540249D02*
Y536249D01*
X46206D01*
G01X23025Y566954D02*
Y569454D01*
X24066D01*
X24400Y569329D01*
X24608Y569162D01*
X24691Y568829D01*
X24608Y568496D01*
X24358Y568287D01*
X24066Y568162D01*
X23025D01*
G01X24066D02*
X24691Y566954D01*
G01X26166Y569037D02*
X26416Y569287D01*
X26708Y569412D01*
X27041Y569454D01*
X27458Y569371D01*
X27750Y569162D01*
X27833Y568912D01*
X27791Y568662D01*
X27625Y568454D01*
X26791Y568037D01*
X26416Y567746D01*
X26166Y567329D01*
X26083Y566954D01*
X27833D01*
G01X30058Y569454D02*
X29725Y569371D01*
X29475Y569162D01*
X29308Y568912D01*
X29183Y568579D01*
X29141Y568204D01*
X29183Y567829D01*
X29308Y567496D01*
X29475Y567246D01*
X29725Y567037D01*
X30058Y566954D01*
X30391Y567037D01*
X30641Y567246D01*
X30808Y567496D01*
X30933Y567829D01*
X30975Y568204D01*
X30933Y568579D01*
X30808Y568912D01*
X30641Y569162D01*
X30391Y569371D01*
X30058Y569454D01*
G01X33075Y566954D02*
X33158Y567496D01*
X33283Y567954D01*
X33450Y568371D01*
X33658Y568829D01*
X33991Y569454D01*
X32325D01*
G01X31258Y540254D02*
Y536254D01*
X38658D01*
G01X37873Y561422D02*
Y563922D01*
X38914D01*
X39248Y563797D01*
X39456Y563630D01*
X39539Y563297D01*
X39456Y562964D01*
X39206Y562755D01*
X38914Y562630D01*
X37873D01*
G01X38914D02*
X39539Y561422D01*
G01X41014Y563505D02*
X41264Y563755D01*
X41556Y563880D01*
X41889Y563922D01*
X42306Y563839D01*
X42598Y563630D01*
X42681Y563380D01*
X42639Y563130D01*
X42473Y562922D01*
X41639Y562505D01*
X41264Y562214D01*
X41014Y561797D01*
X40931Y561422D01*
X42681D01*
G01X44114Y563505D02*
X44364Y563755D01*
X44656Y563880D01*
X44989Y563922D01*
X45406Y563839D01*
X45698Y563630D01*
X45781Y563380D01*
X45739Y563130D01*
X45573Y562922D01*
X44739Y562505D01*
X44364Y562214D01*
X44114Y561797D01*
X44031Y561422D01*
X45781D01*
G01X48506D02*
Y563922D01*
X46964Y562130D01*
X49048D01*
G01X38706Y534622D02*
Y530622D01*
X46106D01*
G01X23032Y561338D02*
Y563838D01*
X24073D01*
X24407Y563713D01*
X24615Y563546D01*
X24698Y563213D01*
X24615Y562880D01*
X24365Y562671D01*
X24073Y562546D01*
X23032D01*
G01X24073D02*
X24698Y561338D01*
G01X26173Y563421D02*
X26423Y563671D01*
X26715Y563796D01*
X27048Y563838D01*
X27465Y563755D01*
X27757Y563546D01*
X27840Y563296D01*
X27798Y563046D01*
X27632Y562838D01*
X26798Y562421D01*
X26423Y562130D01*
X26173Y561713D01*
X26090Y561338D01*
X27840D01*
G01X29148Y561838D02*
X29398Y561546D01*
X29732Y561380D01*
X30107Y561338D01*
X30440Y561380D01*
X30773Y561588D01*
X30982Y561838D01*
X31023Y562088D01*
X30940Y562380D01*
X30648Y562588D01*
X30357Y562671D01*
X29982D01*
G01X30357D02*
X30607Y562796D01*
X30815Y563005D01*
X30898Y563255D01*
X30815Y563505D01*
X30607Y563713D01*
X30232Y563838D01*
X29857Y563796D01*
X29482Y563630D01*
G01X32457Y561630D02*
X32748Y561421D01*
X33082Y561338D01*
X33415Y561421D01*
X33707Y561671D01*
X33915Y562046D01*
X33998Y562421D01*
Y562880D01*
X33915Y563255D01*
X33707Y563588D01*
X33457Y563755D01*
X33165Y563838D01*
X32832Y563755D01*
X32582Y563588D01*
X32415Y563338D01*
X32332Y563005D01*
X32415Y562713D01*
X32623Y562421D01*
X32873Y562255D01*
X33165Y562213D01*
X33498Y562296D01*
X33748Y562505D01*
X33998Y562880D01*
G01X38665Y530638D02*
Y534638D01*
X31265D01*
G01X51983Y572167D02*
Y570375D01*
X52150Y570000D01*
X52483Y569750D01*
X52900Y569667D01*
X53317Y569750D01*
X53650Y570000D01*
X53817Y570375D01*
Y572167D01*
G01X55208Y571750D02*
X55458Y572000D01*
X55750Y572125D01*
X56083Y572167D01*
X56500Y572084D01*
X56792Y571875D01*
X56875Y571625D01*
X56833Y571375D01*
X56667Y571167D01*
X55833Y570750D01*
X55458Y570459D01*
X55208Y570042D01*
X55125Y569667D01*
X56875D01*
G01X59100D02*
X59392Y569709D01*
X59725Y569834D01*
X59933Y570042D01*
X60017Y570334D01*
X59933Y570625D01*
X59683Y570875D01*
X59308Y571000D01*
X58892D01*
X58642Y571084D01*
X58433Y571292D01*
X58350Y571584D01*
X58475Y571875D01*
X58767Y572084D01*
X59100Y572167D01*
X59433Y572084D01*
X59725Y571875D01*
X59850Y571584D01*
X59767Y571292D01*
X59558Y571084D01*
X59308Y571000D01*
X58892D01*
X58517Y570875D01*
X58267Y570625D01*
X58183Y570334D01*
X58267Y570042D01*
X58475Y569834D01*
X58808Y569709D01*
X59100Y569667D01*
G01X64112Y535675D02*
X93640D01*
Y586857D01*
X64112D01*
Y535675D01*
G01X47967Y640959D02*
X47717Y641084D01*
X47425Y641167D01*
X47092D01*
X46717Y641042D01*
X46425Y640834D01*
X46217Y640584D01*
X46050Y640167D01*
X46008Y639792D01*
X46092Y639417D01*
X46217Y639167D01*
X46467Y638917D01*
X46758Y638750D01*
X47050Y638667D01*
X47342D01*
X47633Y638750D01*
X47883Y638875D01*
X48092Y639042D01*
G01X49358Y640750D02*
X49608Y641000D01*
X49900Y641125D01*
X50233Y641167D01*
X50650Y641084D01*
X50942Y640875D01*
X51025Y640625D01*
X50983Y640375D01*
X50817Y640167D01*
X49983Y639750D01*
X49608Y639459D01*
X49358Y639042D01*
X49275Y638667D01*
X51025D01*
G01X52458Y640750D02*
X52708Y641000D01*
X53000Y641125D01*
X53333Y641167D01*
X53750Y641084D01*
X54042Y640875D01*
X54125Y640625D01*
X54083Y640375D01*
X53917Y640167D01*
X53083Y639750D01*
X52708Y639459D01*
X52458Y639042D01*
X52375Y638667D01*
X54125D01*
G01X55558Y640750D02*
X55808Y641000D01*
X56100Y641125D01*
X56433Y641167D01*
X56850Y641084D01*
X57142Y640875D01*
X57225Y640625D01*
X57183Y640375D01*
X57017Y640167D01*
X56183Y639750D01*
X55808Y639459D01*
X55558Y639042D01*
X55475Y638667D01*
X57225D01*
G01X69587Y625809D02*
X69462Y625559D01*
X69379Y625267D01*
Y624934D01*
X69504Y624559D01*
X69712Y624267D01*
X69962Y624059D01*
X70379Y623892D01*
X70754Y623850D01*
X71129Y623934D01*
X71379Y624059D01*
X71629Y624309D01*
X71796Y624600D01*
X71879Y624892D01*
Y625184D01*
X71796Y625475D01*
X71671Y625725D01*
X71504Y625934D01*
G01X69796Y627200D02*
X69546Y627450D01*
X69421Y627742D01*
X69379Y628075D01*
X69462Y628492D01*
X69671Y628784D01*
X69921Y628867D01*
X70171Y628825D01*
X70379Y628659D01*
X70796Y627825D01*
X71087Y627450D01*
X71504Y627200D01*
X71879Y627117D01*
Y628867D01*
G01X69796Y630300D02*
X69546Y630550D01*
X69421Y630842D01*
X69379Y631175D01*
X69462Y631592D01*
X69671Y631884D01*
X69921Y631967D01*
X70171Y631925D01*
X70379Y631759D01*
X70796Y630925D01*
X71087Y630550D01*
X71504Y630300D01*
X71879Y630217D01*
Y631967D01*
G01Y634109D02*
X71337Y634192D01*
X70879Y634317D01*
X70462Y634484D01*
X70004Y634692D01*
X69379Y635025D01*
Y633359D01*
G01X46717Y634667D02*
Y637167D01*
X47758D01*
X48092Y637042D01*
X48300Y636875D01*
X48383Y636542D01*
X48300Y636209D01*
X48050Y636000D01*
X47758Y635875D01*
X46717D01*
G01X47758D02*
X48383Y634667D01*
G01X49733Y635042D02*
X49983Y634834D01*
X50275Y634709D01*
X50650Y634667D01*
X51025Y634750D01*
X51317Y634917D01*
X51525Y635209D01*
X51567Y635542D01*
X51483Y635875D01*
X51275Y636084D01*
X50983Y636250D01*
X50692Y636292D01*
X50400Y636250D01*
X50025Y636084D01*
X50150Y637167D01*
X51275D01*
G01X52833Y635167D02*
X53083Y634875D01*
X53417Y634709D01*
X53792Y634667D01*
X54125Y634709D01*
X54458Y634917D01*
X54667Y635167D01*
X54708Y635417D01*
X54625Y635709D01*
X54333Y635917D01*
X54042Y636000D01*
X53667D01*
G01X54042D02*
X54292Y636125D01*
X54500Y636334D01*
X54583Y636584D01*
X54500Y636834D01*
X54292Y637042D01*
X53917Y637167D01*
X53542Y637125D01*
X53167Y636959D01*
G01X56850Y637167D02*
X56517Y637084D01*
X56267Y636875D01*
X56100Y636625D01*
X55975Y636292D01*
X55933Y635917D01*
X55975Y635542D01*
X56100Y635209D01*
X56267Y634959D01*
X56517Y634750D01*
X56850Y634667D01*
X57183Y634750D01*
X57433Y634959D01*
X57600Y635209D01*
X57725Y635542D01*
X57767Y635917D01*
X57725Y636292D01*
X57600Y636625D01*
X57433Y636875D01*
X57183Y637084D01*
X56850Y637167D01*
G01X66854Y637950D02*
Y641950D01*
X59454D01*
G01X46117Y646767D02*
Y649267D01*
X47158D01*
X47492Y649142D01*
X47700Y648975D01*
X47783Y648642D01*
X47700Y648309D01*
X47450Y648100D01*
X47158Y647975D01*
X46117D01*
G01X47158D02*
X47783Y646767D01*
G01X49133Y647142D02*
X49383Y646934D01*
X49675Y646809D01*
X50050Y646767D01*
X50425Y646850D01*
X50717Y647017D01*
X50925Y647309D01*
X50967Y647642D01*
X50883Y647975D01*
X50675Y648184D01*
X50383Y648350D01*
X50092Y648392D01*
X49800Y648350D01*
X49425Y648184D01*
X49550Y649267D01*
X50675D01*
G01X52233Y647267D02*
X52483Y646975D01*
X52817Y646809D01*
X53192Y646767D01*
X53525Y646809D01*
X53858Y647017D01*
X54067Y647267D01*
X54108Y647517D01*
X54025Y647809D01*
X53733Y648017D01*
X53442Y648100D01*
X53067D01*
G01X53442D02*
X53692Y648225D01*
X53900Y648434D01*
X53983Y648684D01*
X53900Y648934D01*
X53692Y649142D01*
X53317Y649267D01*
X52942Y649225D01*
X52567Y649059D01*
G01X56250Y646767D02*
Y649267D01*
X55750Y648767D01*
G01Y646767D02*
X56750D01*
G01X59346Y649850D02*
Y645850D01*
X66746D01*
G01X67716Y624017D02*
X65216D01*
Y625058D01*
X65341Y625392D01*
X65508Y625600D01*
X65841Y625683D01*
X66174Y625600D01*
X66383Y625350D01*
X66508Y625058D01*
Y624017D01*
G01Y625058D02*
X67716Y625683D01*
G01X67341Y627033D02*
X67549Y627283D01*
X67674Y627575D01*
X67716Y627950D01*
X67633Y628325D01*
X67466Y628617D01*
X67174Y628825D01*
X66841Y628867D01*
X66508Y628783D01*
X66299Y628575D01*
X66133Y628283D01*
X66091Y627992D01*
X66133Y627700D01*
X66299Y627325D01*
X65216Y627450D01*
Y628575D01*
G01X65633Y630258D02*
X65383Y630508D01*
X65258Y630800D01*
X65216Y631133D01*
X65299Y631550D01*
X65508Y631842D01*
X65758Y631925D01*
X66008Y631883D01*
X66216Y631717D01*
X66633Y630883D01*
X66924Y630508D01*
X67341Y630258D01*
X67716Y630175D01*
Y631925D01*
G01X67424Y633442D02*
X67633Y633733D01*
X67716Y634067D01*
X67633Y634400D01*
X67383Y634692D01*
X67008Y634900D01*
X66633Y634983D01*
X66174D01*
X65799Y634900D01*
X65466Y634692D01*
X65299Y634442D01*
X65216Y634150D01*
X65299Y633817D01*
X65466Y633567D01*
X65716Y633400D01*
X66049Y633317D01*
X66341Y633400D01*
X66633Y633608D01*
X66799Y633858D01*
X66841Y634150D01*
X66758Y634483D01*
X66549Y634733D01*
X66174Y634983D01*
G01X74266Y627046D02*
Y632246D01*
G01Y627046D02*
X81266D01*
G01X74266Y640446D02*
Y631746D01*
G01X81266Y640446D02*
X74266D01*
G01X31017Y650500D02*
Y653000D01*
X32017D01*
X32350Y652875D01*
X32600Y652583D01*
X32683Y652250D01*
X32600Y651917D01*
X32392Y651667D01*
X32017Y651542D01*
X31017D01*
G01X34033Y653000D02*
Y651208D01*
X34200Y650833D01*
X34533Y650583D01*
X34950Y650500D01*
X35367Y650583D01*
X35700Y650833D01*
X35867Y651208D01*
Y653000D01*
G01X38050Y650500D02*
Y653000D01*
X37550Y652500D01*
G01Y650500D02*
X38550D01*
G01X41150Y653000D02*
X40817Y652917D01*
X40567Y652708D01*
X40400Y652458D01*
X40275Y652125D01*
X40233Y651750D01*
X40275Y651375D01*
X40400Y651042D01*
X40567Y650792D01*
X40817Y650583D01*
X41150Y650500D01*
X41483Y650583D01*
X41733Y650792D01*
X41900Y651042D01*
X42025Y651375D01*
X42067Y651750D01*
X42025Y652125D01*
X41900Y652458D01*
X41733Y652708D01*
X41483Y652917D01*
X41150Y653000D01*
G01X51864Y657000D02*
Y652000D01*
X56864D01*
G01X70832Y653407D02*
Y650407D01*
G01X28067Y661959D02*
X27817Y662084D01*
X27525Y662167D01*
X27192D01*
X26817Y662042D01*
X26525Y661834D01*
X26317Y661584D01*
X26150Y661167D01*
X26108Y660792D01*
X26192Y660417D01*
X26317Y660167D01*
X26567Y659917D01*
X26858Y659750D01*
X27150Y659667D01*
X27442D01*
X27733Y659750D01*
X27983Y659875D01*
X28192Y660042D01*
G01X29458Y661750D02*
X29708Y662000D01*
X30000Y662125D01*
X30333Y662167D01*
X30750Y662084D01*
X31042Y661875D01*
X31125Y661625D01*
X31083Y661375D01*
X30917Y661167D01*
X30083Y660750D01*
X29708Y660459D01*
X29458Y660042D01*
X29375Y659667D01*
X31125D01*
G01X32558Y661750D02*
X32808Y662000D01*
X33100Y662125D01*
X33433Y662167D01*
X33850Y662084D01*
X34142Y661875D01*
X34225Y661625D01*
X34183Y661375D01*
X34017Y661167D01*
X33183Y660750D01*
X32808Y660459D01*
X32558Y660042D01*
X32475Y659667D01*
X34225D01*
G01X36450D02*
X36742Y659709D01*
X37075Y659834D01*
X37283Y660042D01*
X37367Y660334D01*
X37283Y660625D01*
X37033Y660875D01*
X36658Y661000D01*
X36242D01*
X35992Y661084D01*
X35783Y661292D01*
X35700Y661584D01*
X35825Y661875D01*
X36117Y662084D01*
X36450Y662167D01*
X36783Y662084D01*
X37075Y661875D01*
X37200Y661584D01*
X37117Y661292D01*
X36908Y661084D01*
X36658Y661000D01*
X36242D01*
X35867Y660875D01*
X35617Y660625D01*
X35533Y660334D01*
X35617Y660042D01*
X35825Y659834D01*
X36158Y659709D01*
X36450Y659667D01*
G01X39708Y665767D02*
X39583Y665517D01*
X39500Y665225D01*
Y664892D01*
X39625Y664517D01*
X39833Y664225D01*
X40083Y664017D01*
X40500Y663850D01*
X40875Y663808D01*
X41250Y663892D01*
X41500Y664017D01*
X41750Y664267D01*
X41917Y664558D01*
X42000Y664850D01*
Y665142D01*
X41917Y665433D01*
X41792Y665683D01*
X41625Y665892D01*
G01X39917Y667158D02*
X39667Y667408D01*
X39542Y667700D01*
X39500Y668033D01*
X39583Y668450D01*
X39792Y668742D01*
X40042Y668825D01*
X40292Y668783D01*
X40500Y668617D01*
X40917Y667783D01*
X41208Y667408D01*
X41625Y667158D01*
X42000Y667075D01*
Y668825D01*
G01X41500Y670133D02*
X41792Y670383D01*
X41958Y670717D01*
X42000Y671092D01*
X41958Y671425D01*
X41750Y671758D01*
X41500Y671967D01*
X41250Y672008D01*
X40958Y671925D01*
X40750Y671633D01*
X40667Y671342D01*
Y670967D01*
G01Y671342D02*
X40542Y671592D01*
X40333Y671800D01*
X40083Y671883D01*
X39833Y671800D01*
X39625Y671592D01*
X39500Y671217D01*
X39542Y670842D01*
X39708Y670467D01*
G01X41500Y673233D02*
X41792Y673483D01*
X41958Y673817D01*
X42000Y674192D01*
X41958Y674525D01*
X41750Y674858D01*
X41500Y675067D01*
X41250Y675108D01*
X40958Y675025D01*
X40750Y674733D01*
X40667Y674442D01*
Y674067D01*
G01Y674442D02*
X40542Y674692D01*
X40333Y674900D01*
X40083Y674983D01*
X39833Y674900D01*
X39625Y674692D01*
X39500Y674317D01*
X39542Y673942D01*
X39708Y673567D01*
G01X64042Y707767D02*
X63917Y707517D01*
X63834Y707225D01*
Y706892D01*
X63959Y706517D01*
X64167Y706225D01*
X64417Y706017D01*
X64834Y705850D01*
X65209Y705808D01*
X65584Y705892D01*
X65834Y706017D01*
X66084Y706267D01*
X66251Y706558D01*
X66334Y706850D01*
Y707142D01*
X66251Y707433D01*
X66126Y707683D01*
X65959Y707892D01*
G01X66334Y709950D02*
X63834D01*
X64334Y709450D01*
G01X66334D02*
Y710450D01*
G01Y712967D02*
X65792Y713050D01*
X65334Y713175D01*
X64917Y713342D01*
X64459Y713550D01*
X63834Y713883D01*
Y712217D01*
G01Y716150D02*
X63917Y715817D01*
X64126Y715567D01*
X64376Y715400D01*
X64709Y715275D01*
X65084Y715233D01*
X65459Y715275D01*
X65792Y715400D01*
X66042Y715567D01*
X66251Y715817D01*
X66334Y716150D01*
X66251Y716483D01*
X66042Y716733D01*
X65792Y716900D01*
X65459Y717025D01*
X65084Y717067D01*
X64709Y717025D01*
X64376Y716900D01*
X64126Y716733D01*
X63917Y716483D01*
X63834Y716150D01*
G01X59728Y707758D02*
X59603Y707508D01*
X59520Y707216D01*
Y706883D01*
X59645Y706508D01*
X59853Y706216D01*
X60103Y706008D01*
X60520Y705841D01*
X60895Y705799D01*
X61270Y705883D01*
X61520Y706008D01*
X61770Y706258D01*
X61937Y706549D01*
X62020Y706841D01*
Y707133D01*
X61937Y707424D01*
X61812Y707674D01*
X61645Y707883D01*
G01X62020Y709941D02*
X59520D01*
X60020Y709441D01*
G01X62020D02*
Y710441D01*
G01Y712958D02*
X61478Y713041D01*
X61020Y713166D01*
X60603Y713333D01*
X60145Y713541D01*
X59520Y713874D01*
Y712208D01*
G01X62020Y716141D02*
X59520D01*
X60020Y715641D01*
G01X62020D02*
Y716641D01*
G01X77042Y707767D02*
X76917Y707517D01*
X76834Y707225D01*
Y706892D01*
X76959Y706517D01*
X77167Y706225D01*
X77417Y706017D01*
X77834Y705850D01*
X78209Y705808D01*
X78584Y705892D01*
X78834Y706017D01*
X79084Y706267D01*
X79251Y706558D01*
X79334Y706850D01*
Y707142D01*
X79251Y707433D01*
X79126Y707683D01*
X78959Y707892D01*
G01X79334Y709950D02*
X76834D01*
X77334Y709450D01*
G01X79334D02*
Y710450D01*
G01Y712967D02*
X78792Y713050D01*
X78334Y713175D01*
X77917Y713342D01*
X77459Y713550D01*
X76834Y713883D01*
Y712217D01*
G01X78834Y715233D02*
X79126Y715483D01*
X79292Y715817D01*
X79334Y716192D01*
X79292Y716525D01*
X79084Y716858D01*
X78834Y717067D01*
X78584Y717108D01*
X78292Y717025D01*
X78084Y716733D01*
X78001Y716442D01*
Y716067D01*
G01Y716442D02*
X77876Y716692D01*
X77667Y716900D01*
X77417Y716983D01*
X77167Y716900D01*
X76959Y716692D01*
X76834Y716317D01*
X76876Y715942D01*
X77042Y715567D01*
G01X68542Y707767D02*
X68417Y707517D01*
X68334Y707225D01*
Y706892D01*
X68459Y706517D01*
X68667Y706225D01*
X68917Y706017D01*
X69334Y705850D01*
X69709Y705808D01*
X70084Y705892D01*
X70334Y706017D01*
X70584Y706267D01*
X70751Y706558D01*
X70834Y706850D01*
Y707142D01*
X70751Y707433D01*
X70626Y707683D01*
X70459Y707892D01*
G01X70834Y709950D02*
X68334D01*
X68834Y709450D01*
G01X70834D02*
Y710450D01*
G01Y712967D02*
X70292Y713050D01*
X69834Y713175D01*
X69417Y713342D01*
X68959Y713550D01*
X68334Y713883D01*
Y712217D01*
G01X69792Y715358D02*
X69501Y715650D01*
X69334Y715900D01*
X69251Y716233D01*
X69334Y716525D01*
X69501Y716733D01*
X69751Y716900D01*
X70042Y716942D01*
X70292Y716900D01*
X70542Y716733D01*
X70751Y716483D01*
X70834Y716192D01*
X70751Y715858D01*
X70501Y715567D01*
X70126Y715400D01*
X69709Y715358D01*
X69167Y715442D01*
X68876Y715567D01*
X68584Y715775D01*
X68376Y716067D01*
X68334Y716358D01*
X68417Y716650D01*
X68626Y716858D01*
G01X73042Y707767D02*
X72917Y707517D01*
X72834Y707225D01*
Y706892D01*
X72959Y706517D01*
X73167Y706225D01*
X73417Y706017D01*
X73834Y705850D01*
X74209Y705808D01*
X74584Y705892D01*
X74834Y706017D01*
X75084Y706267D01*
X75251Y706558D01*
X75334Y706850D01*
Y707142D01*
X75251Y707433D01*
X75126Y707683D01*
X74959Y707892D01*
G01X75334Y709950D02*
X72834D01*
X73334Y709450D01*
G01X75334D02*
Y710450D01*
G01Y712967D02*
X74792Y713050D01*
X74334Y713175D01*
X73917Y713342D01*
X73459Y713550D01*
X72834Y713883D01*
Y712217D01*
G01X75334Y716067D02*
X74792Y716150D01*
X74334Y716275D01*
X73917Y716442D01*
X73459Y716650D01*
X72834Y716983D01*
Y715317D01*
G01X67700Y685117D02*
X65200D01*
Y686158D01*
X65325Y686492D01*
X65492Y686700D01*
X65825Y686783D01*
X66158Y686700D01*
X66367Y686450D01*
X66492Y686158D01*
Y685117D01*
G01Y686158D02*
X67700Y686783D01*
G01X67325Y688133D02*
X67533Y688383D01*
X67658Y688675D01*
X67700Y689050D01*
X67617Y689425D01*
X67450Y689717D01*
X67158Y689925D01*
X66825Y689967D01*
X66492Y689883D01*
X66283Y689675D01*
X66117Y689383D01*
X66075Y689092D01*
X66117Y688800D01*
X66283Y688425D01*
X65200Y688550D01*
Y689675D01*
G01X67200Y691233D02*
X67492Y691483D01*
X67658Y691817D01*
X67700Y692192D01*
X67658Y692525D01*
X67450Y692858D01*
X67200Y693067D01*
X66950Y693108D01*
X66658Y693025D01*
X66450Y692733D01*
X66367Y692442D01*
Y692067D01*
G01Y692442D02*
X66242Y692692D01*
X66033Y692900D01*
X65783Y692983D01*
X65533Y692900D01*
X65325Y692692D01*
X65200Y692317D01*
X65242Y691942D01*
X65408Y691567D01*
G01X65617Y694458D02*
X65367Y694708D01*
X65242Y695000D01*
X65200Y695333D01*
X65283Y695750D01*
X65492Y696042D01*
X65742Y696125D01*
X65992Y696083D01*
X66200Y695917D01*
X66617Y695083D01*
X66908Y694708D01*
X67325Y694458D01*
X67700Y694375D01*
Y696125D01*
G01X63000Y690117D02*
X60500D01*
Y691158D01*
X60625Y691492D01*
X60792Y691700D01*
X61125Y691783D01*
X61458Y691700D01*
X61667Y691450D01*
X61792Y691158D01*
Y690117D01*
G01Y691158D02*
X63000Y691783D01*
G01X62625Y693133D02*
X62833Y693383D01*
X62958Y693675D01*
X63000Y694050D01*
X62917Y694425D01*
X62750Y694717D01*
X62458Y694925D01*
X62125Y694967D01*
X61792Y694883D01*
X61583Y694675D01*
X61417Y694383D01*
X61375Y694092D01*
X61417Y693800D01*
X61583Y693425D01*
X60500Y693550D01*
Y694675D01*
G01X62500Y696233D02*
X62792Y696483D01*
X62958Y696817D01*
X63000Y697192D01*
X62958Y697525D01*
X62750Y697858D01*
X62500Y698067D01*
X62250Y698108D01*
X61958Y698025D01*
X61750Y697733D01*
X61667Y697442D01*
Y697067D01*
G01Y697442D02*
X61542Y697692D01*
X61333Y697900D01*
X61083Y697983D01*
X60833Y697900D01*
X60625Y697692D01*
X60500Y697317D01*
X60542Y696942D01*
X60708Y696567D01*
G01X62500Y699333D02*
X62792Y699583D01*
X62958Y699917D01*
X63000Y700292D01*
X62958Y700625D01*
X62750Y700958D01*
X62500Y701167D01*
X62250Y701208D01*
X61958Y701125D01*
X61750Y700833D01*
X61667Y700542D01*
Y700167D01*
G01Y700542D02*
X61542Y700792D01*
X61333Y701000D01*
X61083Y701083D01*
X60833Y701000D01*
X60625Y700792D01*
X60500Y700417D01*
X60542Y700042D01*
X60708Y699667D01*
G01X78100Y695700D02*
X74100D01*
Y688300D01*
G01X37000Y664017D02*
X34500D01*
Y665058D01*
X34625Y665392D01*
X34792Y665600D01*
X35125Y665683D01*
X35458Y665600D01*
X35667Y665350D01*
X35792Y665058D01*
Y664017D01*
G01Y665058D02*
X37000Y665683D01*
G01X36625Y667033D02*
X36833Y667283D01*
X36958Y667575D01*
X37000Y667950D01*
X36917Y668325D01*
X36750Y668617D01*
X36458Y668825D01*
X36125Y668867D01*
X35792Y668783D01*
X35583Y668575D01*
X35417Y668283D01*
X35375Y667992D01*
X35417Y667700D01*
X35583Y667325D01*
X34500Y667450D01*
Y668575D01*
G01X36500Y670133D02*
X36792Y670383D01*
X36958Y670717D01*
X37000Y671092D01*
X36958Y671425D01*
X36750Y671758D01*
X36500Y671967D01*
X36250Y672008D01*
X35958Y671925D01*
X35750Y671633D01*
X35667Y671342D01*
Y670967D01*
G01Y671342D02*
X35542Y671592D01*
X35333Y671800D01*
X35083Y671883D01*
X34833Y671800D01*
X34625Y671592D01*
X34500Y671217D01*
X34542Y670842D01*
X34708Y670467D01*
G01X37000Y674650D02*
X34500D01*
X36292Y673108D01*
Y675192D01*
G01X44100Y669584D02*
X48100D01*
Y676984D01*
G01X20217Y678267D02*
Y680767D01*
X21258D01*
X21592Y680642D01*
X21800Y680475D01*
X21883Y680142D01*
X21800Y679809D01*
X21550Y679600D01*
X21258Y679475D01*
X20217D01*
G01X21258D02*
X21883Y678267D01*
G01X23233Y678642D02*
X23483Y678434D01*
X23775Y678309D01*
X24150Y678267D01*
X24525Y678350D01*
X24817Y678517D01*
X25025Y678809D01*
X25067Y679142D01*
X24983Y679475D01*
X24775Y679684D01*
X24483Y679850D01*
X24192Y679892D01*
X23900Y679850D01*
X23525Y679684D01*
X23650Y680767D01*
X24775D01*
G01X26333Y678767D02*
X26583Y678475D01*
X26917Y678309D01*
X27292Y678267D01*
X27625Y678309D01*
X27958Y678517D01*
X28167Y678767D01*
X28208Y679017D01*
X28125Y679309D01*
X27833Y679517D01*
X27542Y679600D01*
X27167D01*
G01X27542D02*
X27792Y679725D01*
X28000Y679934D01*
X28083Y680184D01*
X28000Y680434D01*
X27792Y680642D01*
X27417Y680767D01*
X27042Y680725D01*
X26667Y680559D01*
G01X29433Y678642D02*
X29683Y678434D01*
X29975Y678309D01*
X30350Y678267D01*
X30725Y678350D01*
X31017Y678517D01*
X31225Y678809D01*
X31267Y679142D01*
X31183Y679475D01*
X30975Y679684D01*
X30683Y679850D01*
X30392Y679892D01*
X30100Y679850D01*
X29725Y679684D01*
X29850Y680767D01*
X30975D01*
G01X44133Y677946D02*
Y681946D01*
X36733D01*
G01X55541Y688867D02*
X55416Y688617D01*
X55333Y688325D01*
Y687992D01*
X55458Y687617D01*
X55666Y687325D01*
X55916Y687117D01*
X56333Y686950D01*
X56708Y686908D01*
X57083Y686992D01*
X57333Y687117D01*
X57583Y687367D01*
X57750Y687658D01*
X57833Y687950D01*
Y688242D01*
X57750Y688533D01*
X57625Y688783D01*
X57458Y688992D01*
G01X55750Y690258D02*
X55500Y690508D01*
X55375Y690800D01*
X55333Y691133D01*
X55416Y691550D01*
X55625Y691842D01*
X55875Y691925D01*
X56125Y691883D01*
X56333Y691717D01*
X56750Y690883D01*
X57041Y690508D01*
X57458Y690258D01*
X57833Y690175D01*
Y691925D01*
G01X55750Y693358D02*
X55500Y693608D01*
X55375Y693900D01*
X55333Y694233D01*
X55416Y694650D01*
X55625Y694942D01*
X55875Y695025D01*
X56125Y694983D01*
X56333Y694817D01*
X56750Y693983D01*
X57041Y693608D01*
X57458Y693358D01*
X57833Y693275D01*
Y695025D01*
G01X57541Y696542D02*
X57750Y696833D01*
X57833Y697167D01*
X57750Y697500D01*
X57500Y697792D01*
X57125Y698000D01*
X56750Y698083D01*
X56291D01*
X55916Y698000D01*
X55583Y697792D01*
X55416Y697542D01*
X55333Y697250D01*
X55416Y696917D01*
X55583Y696667D01*
X55833Y696500D01*
X56166Y696417D01*
X56458Y696500D01*
X56750Y696708D01*
X56916Y696958D01*
X56958Y697250D01*
X56875Y697583D01*
X56666Y697833D01*
X56291Y698083D01*
G01X56864Y679700D02*
X51864D01*
Y674700D01*
G01X79564D02*
Y679700D01*
X74564D01*
G01X60596Y678293D02*
Y681293D01*
G01X53271Y660732D02*
X51271D01*
G01X107834Y53517D02*
X105334D01*
Y54517D01*
X105459Y54850D01*
X105751Y55100D01*
X106084Y55183D01*
X106417Y55100D01*
X106667Y54892D01*
X106792Y54517D01*
Y53517D01*
G01X105334Y56200D02*
X107834Y56783D01*
X105334Y57450D01*
X107834Y58117D01*
X105334Y58700D01*
G01X107834Y59717D02*
X105334D01*
Y60758D01*
X105459Y61092D01*
X105626Y61300D01*
X105959Y61383D01*
X106292Y61300D01*
X106501Y61050D01*
X106626Y60758D01*
Y59717D01*
G01Y60758D02*
X107834Y61383D01*
G01Y63650D02*
X105334D01*
X105834Y63150D01*
G01X107834D02*
Y64150D01*
G01X88434Y65867D02*
X85934D01*
Y66908D01*
X86059Y67242D01*
X86226Y67450D01*
X86559Y67533D01*
X86892Y67450D01*
X87101Y67200D01*
X87226Y66908D01*
Y65867D01*
G01Y66908D02*
X88434Y67533D01*
G01Y70300D02*
X85934D01*
X87726Y68758D01*
Y70842D01*
G01X88434Y72900D02*
X88392Y73192D01*
X88267Y73525D01*
X88059Y73733D01*
X87767Y73817D01*
X87476Y73733D01*
X87226Y73483D01*
X87101Y73108D01*
Y72692D01*
X87017Y72442D01*
X86809Y72233D01*
X86517Y72150D01*
X86226Y72275D01*
X86017Y72567D01*
X85934Y72900D01*
X86017Y73233D01*
X86226Y73525D01*
X86517Y73650D01*
X86809Y73567D01*
X87017Y73358D01*
X87101Y73108D01*
Y72692D01*
X87226Y72317D01*
X87476Y72067D01*
X87767Y71983D01*
X88059Y72067D01*
X88267Y72275D01*
X88392Y72608D01*
X88434Y72900D01*
G01X91034Y61335D02*
X87034D01*
Y53935D01*
G01X80952Y66997D02*
X80827Y66747D01*
X80744Y66455D01*
Y66122D01*
X80869Y65747D01*
X81077Y65455D01*
X81327Y65247D01*
X81744Y65080D01*
X82119Y65038D01*
X82494Y65122D01*
X82744Y65247D01*
X82994Y65497D01*
X83161Y65788D01*
X83244Y66080D01*
Y66372D01*
X83161Y66663D01*
X83036Y66913D01*
X82869Y67122D01*
G01X81161Y68388D02*
X80911Y68638D01*
X80786Y68930D01*
X80744Y69263D01*
X80827Y69680D01*
X81036Y69972D01*
X81286Y70055D01*
X81536Y70013D01*
X81744Y69847D01*
X82161Y69013D01*
X82452Y68638D01*
X82869Y68388D01*
X83244Y68305D01*
Y70055D01*
G01X82202Y71488D02*
X81911Y71780D01*
X81744Y72030D01*
X81661Y72363D01*
X81744Y72655D01*
X81911Y72863D01*
X82161Y73030D01*
X82452Y73072D01*
X82702Y73030D01*
X82952Y72863D01*
X83161Y72613D01*
X83244Y72322D01*
X83161Y71988D01*
X82911Y71697D01*
X82536Y71530D01*
X82119Y71488D01*
X81577Y71572D01*
X81286Y71697D01*
X80994Y71905D01*
X80786Y72197D01*
X80744Y72488D01*
X80827Y72780D01*
X81036Y72988D01*
G01X91173Y68527D02*
Y71027D01*
X92007D01*
X92340Y70902D01*
X92590Y70735D01*
X92798Y70485D01*
X92965Y70194D01*
X93007Y69777D01*
X92965Y69360D01*
X92798Y69069D01*
X92590Y68819D01*
X92340Y68652D01*
X92007Y68527D01*
X91173D01*
G01X94398Y70610D02*
X94648Y70860D01*
X94940Y70985D01*
X95273Y71027D01*
X95690Y70944D01*
X95982Y70735D01*
X96065Y70485D01*
X96023Y70235D01*
X95857Y70027D01*
X95023Y69610D01*
X94648Y69319D01*
X94398Y68902D01*
X94315Y68527D01*
X96065D01*
G01X95740Y51860D02*
X91540D01*
G01X95740Y63560D02*
Y51860D01*
G01X91540Y63560D02*
X95740D01*
G01X91540Y51860D02*
Y63560D01*
G01X87108Y444567D02*
X86983Y444317D01*
X86900Y444025D01*
Y443692D01*
X87025Y443317D01*
X87233Y443025D01*
X87483Y442817D01*
X87900Y442650D01*
X88275Y442608D01*
X88650Y442692D01*
X88900Y442817D01*
X89150Y443067D01*
X89317Y443358D01*
X89400Y443650D01*
Y443942D01*
X89317Y444233D01*
X89192Y444483D01*
X89025Y444692D01*
G01X89400Y446750D02*
X86900D01*
X87400Y446250D01*
G01X89400D02*
Y447250D01*
G01X87317Y449058D02*
X87067Y449308D01*
X86942Y449600D01*
X86900Y449933D01*
X86983Y450350D01*
X87192Y450642D01*
X87442Y450725D01*
X87692Y450683D01*
X87900Y450517D01*
X88317Y449683D01*
X88608Y449308D01*
X89025Y449058D01*
X89400Y448975D01*
Y450725D01*
G01X86900Y452950D02*
X86983Y452617D01*
X87192Y452367D01*
X87442Y452200D01*
X87775Y452075D01*
X88150Y452033D01*
X88525Y452075D01*
X88858Y452200D01*
X89108Y452367D01*
X89317Y452617D01*
X89400Y452950D01*
X89317Y453283D01*
X89108Y453533D01*
X88858Y453700D01*
X88525Y453825D01*
X88150Y453867D01*
X87775Y453825D01*
X87442Y453700D01*
X87192Y453533D01*
X86983Y453283D01*
X86900Y452950D01*
G01X89817Y434967D02*
Y437467D01*
X90858D01*
X91192Y437342D01*
X91400Y437175D01*
X91483Y436842D01*
X91400Y436509D01*
X91150Y436300D01*
X90858Y436175D01*
X89817D01*
G01X90858D02*
X91483Y434967D01*
G01X92833Y435467D02*
X93083Y435175D01*
X93417Y435009D01*
X93792Y434967D01*
X94125Y435009D01*
X94458Y435217D01*
X94667Y435467D01*
X94708Y435717D01*
X94625Y436009D01*
X94333Y436217D01*
X94042Y436300D01*
X93667D01*
G01X94042D02*
X94292Y436425D01*
X94500Y436634D01*
X94583Y436884D01*
X94500Y437134D01*
X94292Y437342D01*
X93917Y437467D01*
X93542Y437425D01*
X93167Y437259D01*
G01X96142Y435259D02*
X96433Y435050D01*
X96767Y434967D01*
X97100Y435050D01*
X97392Y435300D01*
X97600Y435675D01*
X97683Y436050D01*
Y436509D01*
X97600Y436884D01*
X97392Y437217D01*
X97142Y437384D01*
X96850Y437467D01*
X96517Y437384D01*
X96267Y437217D01*
X96100Y436967D01*
X96017Y436634D01*
X96100Y436342D01*
X96308Y436050D01*
X96558Y435884D01*
X96850Y435842D01*
X97183Y435925D01*
X97433Y436134D01*
X97683Y436509D01*
G01X99158Y437050D02*
X99408Y437300D01*
X99700Y437425D01*
X100033Y437467D01*
X100450Y437384D01*
X100742Y437175D01*
X100825Y436925D01*
X100783Y436675D01*
X100617Y436467D01*
X99783Y436050D01*
X99408Y435759D01*
X99158Y435342D01*
X99075Y434967D01*
X100825D01*
G01X84800Y422917D02*
X82300D01*
Y423958D01*
X82425Y424292D01*
X82592Y424500D01*
X82925Y424583D01*
X83258Y424500D01*
X83467Y424250D01*
X83592Y423958D01*
Y422917D01*
G01Y423958D02*
X84800Y424583D01*
G01X84300Y425933D02*
X84592Y426183D01*
X84758Y426517D01*
X84800Y426892D01*
X84758Y427225D01*
X84550Y427558D01*
X84300Y427767D01*
X84050Y427808D01*
X83758Y427725D01*
X83550Y427433D01*
X83467Y427142D01*
Y426767D01*
G01Y427142D02*
X83342Y427392D01*
X83133Y427600D01*
X82883Y427683D01*
X82633Y427600D01*
X82425Y427392D01*
X82300Y427017D01*
X82342Y426642D01*
X82508Y426267D01*
G01X84508Y429242D02*
X84717Y429533D01*
X84800Y429867D01*
X84717Y430200D01*
X84467Y430492D01*
X84092Y430700D01*
X83717Y430783D01*
X83258D01*
X82883Y430700D01*
X82550Y430492D01*
X82383Y430242D01*
X82300Y429950D01*
X82383Y429617D01*
X82550Y429367D01*
X82800Y429200D01*
X83133Y429117D01*
X83425Y429200D01*
X83717Y429408D01*
X83883Y429658D01*
X83925Y429950D01*
X83842Y430283D01*
X83633Y430533D01*
X83258Y430783D01*
G01X82300Y433050D02*
X82383Y432717D01*
X82592Y432467D01*
X82842Y432300D01*
X83175Y432175D01*
X83550Y432133D01*
X83925Y432175D01*
X84258Y432300D01*
X84508Y432467D01*
X84717Y432717D01*
X84800Y433050D01*
X84717Y433383D01*
X84508Y433633D01*
X84258Y433800D01*
X83925Y433925D01*
X83550Y433967D01*
X83175Y433925D01*
X82842Y433800D01*
X82592Y433633D01*
X82383Y433383D01*
X82300Y433050D01*
G01X89733Y422917D02*
X87233D01*
Y423958D01*
X87358Y424292D01*
X87525Y424500D01*
X87858Y424583D01*
X88191Y424500D01*
X88400Y424250D01*
X88525Y423958D01*
Y422917D01*
G01Y423958D02*
X89733Y424583D01*
G01X89233Y425933D02*
X89525Y426183D01*
X89691Y426517D01*
X89733Y426892D01*
X89691Y427225D01*
X89483Y427558D01*
X89233Y427767D01*
X88983Y427808D01*
X88691Y427725D01*
X88483Y427433D01*
X88400Y427142D01*
Y426767D01*
G01Y427142D02*
X88275Y427392D01*
X88066Y427600D01*
X87816Y427683D01*
X87566Y427600D01*
X87358Y427392D01*
X87233Y427017D01*
X87275Y426642D01*
X87441Y426267D01*
G01X89441Y429242D02*
X89650Y429533D01*
X89733Y429867D01*
X89650Y430200D01*
X89400Y430492D01*
X89025Y430700D01*
X88650Y430783D01*
X88191D01*
X87816Y430700D01*
X87483Y430492D01*
X87316Y430242D01*
X87233Y429950D01*
X87316Y429617D01*
X87483Y429367D01*
X87733Y429200D01*
X88066Y429117D01*
X88358Y429200D01*
X88650Y429408D01*
X88816Y429658D01*
X88858Y429950D01*
X88775Y430283D01*
X88566Y430533D01*
X88191Y430783D01*
G01X89733Y433050D02*
X87233D01*
X87733Y432550D01*
G01X89733D02*
Y433550D01*
G01X80800Y422917D02*
X78300D01*
Y423958D01*
X78425Y424292D01*
X78592Y424500D01*
X78925Y424583D01*
X79258Y424500D01*
X79467Y424250D01*
X79592Y423958D01*
Y422917D01*
G01Y423958D02*
X80800Y424583D01*
G01X80300Y425933D02*
X80592Y426183D01*
X80758Y426517D01*
X80800Y426892D01*
X80758Y427225D01*
X80550Y427558D01*
X80300Y427767D01*
X80050Y427808D01*
X79758Y427725D01*
X79550Y427433D01*
X79467Y427142D01*
Y426767D01*
G01Y427142D02*
X79342Y427392D01*
X79133Y427600D01*
X78883Y427683D01*
X78633Y427600D01*
X78425Y427392D01*
X78300Y427017D01*
X78342Y426642D01*
X78508Y426267D01*
G01X80508Y429242D02*
X80717Y429533D01*
X80800Y429867D01*
X80717Y430200D01*
X80467Y430492D01*
X80092Y430700D01*
X79717Y430783D01*
X79258D01*
X78883Y430700D01*
X78550Y430492D01*
X78383Y430242D01*
X78300Y429950D01*
X78383Y429617D01*
X78550Y429367D01*
X78800Y429200D01*
X79133Y429117D01*
X79425Y429200D01*
X79717Y429408D01*
X79883Y429658D01*
X79925Y429950D01*
X79842Y430283D01*
X79633Y430533D01*
X79258Y430783D01*
G01X80425Y432133D02*
X80633Y432383D01*
X80758Y432675D01*
X80800Y433050D01*
X80717Y433425D01*
X80550Y433717D01*
X80258Y433925D01*
X79925Y433967D01*
X79592Y433883D01*
X79383Y433675D01*
X79217Y433383D01*
X79175Y433092D01*
X79217Y432800D01*
X79383Y432425D01*
X78300Y432550D01*
Y433675D01*
G01X90017Y438767D02*
Y441267D01*
X91058D01*
X91392Y441142D01*
X91600Y440975D01*
X91683Y440642D01*
X91600Y440309D01*
X91350Y440100D01*
X91058Y439975D01*
X90017D01*
G01X91058D02*
X91683Y438767D01*
G01X94450D02*
Y441267D01*
X92908Y439475D01*
X94992D01*
G01X97050Y441267D02*
X96717Y441184D01*
X96467Y440975D01*
X96300Y440725D01*
X96175Y440392D01*
X96133Y440017D01*
X96175Y439642D01*
X96300Y439309D01*
X96467Y439059D01*
X96717Y438850D01*
X97050Y438767D01*
X97383Y438850D01*
X97633Y439059D01*
X97800Y439309D01*
X97925Y439642D01*
X97967Y440017D01*
X97925Y440392D01*
X97800Y440725D01*
X97633Y440975D01*
X97383Y441184D01*
X97050Y441267D01*
G01X100067Y438767D02*
X100150Y439309D01*
X100275Y439767D01*
X100442Y440184D01*
X100650Y440642D01*
X100983Y441267D01*
X99317D01*
G01X85300Y438717D02*
X82800D01*
Y439758D01*
X82925Y440092D01*
X83092Y440300D01*
X83425Y440383D01*
X83758Y440300D01*
X83967Y440050D01*
X84092Y439758D01*
Y438717D01*
G01Y439758D02*
X85300Y440383D01*
G01Y443150D02*
X82800D01*
X84592Y441608D01*
Y443692D01*
G01X82800Y445750D02*
X82883Y445417D01*
X83092Y445167D01*
X83342Y445000D01*
X83675Y444875D01*
X84050Y444833D01*
X84425Y444875D01*
X84758Y445000D01*
X85008Y445167D01*
X85217Y445417D01*
X85300Y445750D01*
X85217Y446083D01*
X85008Y446333D01*
X84758Y446500D01*
X84425Y446625D01*
X84050Y446667D01*
X83675Y446625D01*
X83342Y446500D01*
X83092Y446333D01*
X82883Y446083D01*
X82800Y445750D01*
G01X83217Y448058D02*
X82967Y448308D01*
X82842Y448600D01*
X82800Y448933D01*
X82883Y449350D01*
X83092Y449642D01*
X83342Y449725D01*
X83592Y449683D01*
X83800Y449517D01*
X84217Y448683D01*
X84508Y448308D01*
X84925Y448058D01*
X85300Y447975D01*
Y449725D01*
G01X80734Y438017D02*
X78234D01*
Y439058D01*
X78359Y439392D01*
X78526Y439600D01*
X78859Y439683D01*
X79192Y439600D01*
X79401Y439350D01*
X79526Y439058D01*
Y438017D01*
G01Y439058D02*
X80734Y439683D01*
G01Y442450D02*
X78234D01*
X80026Y440908D01*
Y442992D01*
G01X78234Y445050D02*
X78317Y444717D01*
X78526Y444467D01*
X78776Y444300D01*
X79109Y444175D01*
X79484Y444133D01*
X79859Y444175D01*
X80192Y444300D01*
X80442Y444467D01*
X80651Y444717D01*
X80734Y445050D01*
X80651Y445383D01*
X80442Y445633D01*
X80192Y445800D01*
X79859Y445925D01*
X79484Y445967D01*
X79109Y445925D01*
X78776Y445800D01*
X78526Y445633D01*
X78317Y445383D01*
X78234Y445050D01*
G01X80359Y447233D02*
X80567Y447483D01*
X80692Y447775D01*
X80734Y448150D01*
X80651Y448525D01*
X80484Y448817D01*
X80192Y449025D01*
X79859Y449067D01*
X79526Y448983D01*
X79317Y448775D01*
X79151Y448483D01*
X79109Y448192D01*
X79151Y447900D01*
X79317Y447525D01*
X78234Y447650D01*
Y448775D01*
G01X93200Y442817D02*
X90700D01*
Y443858D01*
X90825Y444192D01*
X90992Y444400D01*
X91325Y444483D01*
X91658Y444400D01*
X91867Y444150D01*
X91992Y443858D01*
Y442817D01*
G01Y443858D02*
X93200Y444483D01*
G01Y447250D02*
X90700D01*
X92492Y445708D01*
Y447792D01*
G01X93200Y449850D02*
X90700D01*
X91200Y449350D01*
G01X93200D02*
Y450350D01*
G01X90700Y452950D02*
X90783Y452617D01*
X90992Y452367D01*
X91242Y452200D01*
X91575Y452075D01*
X91950Y452033D01*
X92325Y452075D01*
X92658Y452200D01*
X92908Y452367D01*
X93117Y452617D01*
X93200Y452950D01*
X93117Y453283D01*
X92908Y453533D01*
X92658Y453700D01*
X92325Y453825D01*
X91950Y453867D01*
X91575Y453825D01*
X91242Y453700D01*
X90992Y453533D01*
X90783Y453283D01*
X90700Y452950D01*
G01X119560Y508899D02*
Y446699D01*
X169960D01*
Y508899D01*
X119560D01*
G01X149060Y446749D02*
X144460Y451349D01*
X139810Y446699D01*
G01X142790Y455799D02*
X144760Y457769D01*
G01X132060Y455799D02*
Y496499D01*
G01X157460Y455799D02*
X132060D01*
G01X139400Y511000D02*
Y526500D01*
X144900D01*
Y529900D01*
X228500D01*
G01X112142Y516217D02*
X112017Y515967D01*
X111934Y515675D01*
Y515342D01*
X112059Y514967D01*
X112267Y514675D01*
X112517Y514467D01*
X112934Y514300D01*
X113309Y514258D01*
X113684Y514342D01*
X113934Y514467D01*
X114184Y514717D01*
X114351Y515008D01*
X114434Y515300D01*
Y515592D01*
X114351Y515883D01*
X114226Y516133D01*
X114059Y516342D01*
G01X114434Y518317D02*
X113892Y518400D01*
X113434Y518525D01*
X113017Y518692D01*
X112559Y518900D01*
X111934Y519233D01*
Y517567D01*
G01X114142Y520792D02*
X114351Y521083D01*
X114434Y521417D01*
X114351Y521750D01*
X114101Y522042D01*
X113726Y522250D01*
X113351Y522333D01*
X112892D01*
X112517Y522250D01*
X112184Y522042D01*
X112017Y521792D01*
X111934Y521500D01*
X112017Y521167D01*
X112184Y520917D01*
X112434Y520750D01*
X112767Y520667D01*
X113059Y520750D01*
X113351Y520958D01*
X113517Y521208D01*
X113559Y521500D01*
X113476Y521833D01*
X113267Y522083D01*
X112892Y522333D01*
G01X79032Y512077D02*
X83032D01*
Y519477D01*
G01X79068Y504466D02*
X83068D01*
Y511866D01*
G01X97900Y467767D02*
X95400D01*
Y468808D01*
X95525Y469142D01*
X95692Y469350D01*
X96025Y469433D01*
X96358Y469350D01*
X96567Y469100D01*
X96692Y468808D01*
Y467767D01*
G01Y468808D02*
X97900Y469433D01*
G01Y471700D02*
X97858Y471992D01*
X97733Y472325D01*
X97525Y472533D01*
X97233Y472617D01*
X96942Y472533D01*
X96692Y472283D01*
X96567Y471908D01*
Y471492D01*
X96483Y471242D01*
X96275Y471033D01*
X95983Y470950D01*
X95692Y471075D01*
X95483Y471367D01*
X95400Y471700D01*
X95483Y472033D01*
X95692Y472325D01*
X95983Y472450D01*
X96275Y472367D01*
X96483Y472158D01*
X96567Y471908D01*
Y471492D01*
X96692Y471117D01*
X96942Y470867D01*
X97233Y470783D01*
X97525Y470867D01*
X97733Y471075D01*
X97858Y471408D01*
X97900Y471700D01*
G01Y475300D02*
X95400D01*
X97192Y473758D01*
Y475842D01*
G01X103920Y479998D02*
X107920D01*
Y487398D01*
G01X101600Y467767D02*
X99100D01*
Y468808D01*
X99225Y469142D01*
X99392Y469350D01*
X99725Y469433D01*
X100058Y469350D01*
X100267Y469100D01*
X100392Y468808D01*
Y467767D01*
G01Y468808D02*
X101600Y469433D01*
G01Y471700D02*
X101558Y471992D01*
X101433Y472325D01*
X101225Y472533D01*
X100933Y472617D01*
X100642Y472533D01*
X100392Y472283D01*
X100267Y471908D01*
Y471492D01*
X100183Y471242D01*
X99975Y471033D01*
X99683Y470950D01*
X99392Y471075D01*
X99183Y471367D01*
X99100Y471700D01*
X99183Y472033D01*
X99392Y472325D01*
X99683Y472450D01*
X99975Y472367D01*
X100183Y472158D01*
X100267Y471908D01*
Y471492D01*
X100392Y471117D01*
X100642Y470867D01*
X100933Y470783D01*
X101225Y470867D01*
X101433Y471075D01*
X101558Y471408D01*
X101600Y471700D01*
G01X101225Y473883D02*
X101433Y474133D01*
X101558Y474425D01*
X101600Y474800D01*
X101517Y475175D01*
X101350Y475467D01*
X101058Y475675D01*
X100725Y475717D01*
X100392Y475633D01*
X100183Y475425D01*
X100017Y475133D01*
X99975Y474842D01*
X100017Y474550D01*
X100183Y474175D01*
X99100Y474300D01*
Y475425D01*
G01X112220Y487398D02*
X108220D01*
Y479998D01*
G01X84659Y512077D02*
X88659D01*
Y519477D01*
G01X84673Y504600D02*
X88673D01*
Y512000D01*
G01X90000D02*
X94000D01*
Y519400D01*
G01X107234Y513617D02*
X104734D01*
Y514658D01*
X104859Y514992D01*
X105026Y515200D01*
X105359Y515283D01*
X105692Y515200D01*
X105901Y514950D01*
X106026Y514658D01*
Y513617D01*
G01Y514658D02*
X107234Y515283D01*
G01X105151Y516758D02*
X104901Y517008D01*
X104776Y517300D01*
X104734Y517633D01*
X104817Y518050D01*
X105026Y518342D01*
X105276Y518425D01*
X105526Y518383D01*
X105734Y518217D01*
X106151Y517383D01*
X106442Y517008D01*
X106859Y516758D01*
X107234Y516675D01*
Y518425D01*
G01X106734Y519733D02*
X107026Y519983D01*
X107192Y520317D01*
X107234Y520692D01*
X107192Y521025D01*
X106984Y521358D01*
X106734Y521567D01*
X106484Y521608D01*
X106192Y521525D01*
X105984Y521233D01*
X105901Y520942D01*
Y520567D01*
G01Y520942D02*
X105776Y521192D01*
X105567Y521400D01*
X105317Y521483D01*
X105067Y521400D01*
X104859Y521192D01*
X104734Y520817D01*
X104776Y520442D01*
X104942Y520067D01*
G01X107234Y523750D02*
X104734D01*
X105234Y523250D01*
G01X107234D02*
Y524250D01*
G01X99100Y509900D02*
X103100D01*
Y517300D01*
G01X107234Y525617D02*
X104734D01*
Y526658D01*
X104859Y526992D01*
X105026Y527200D01*
X105359Y527283D01*
X105692Y527200D01*
X105901Y526950D01*
X106026Y526658D01*
Y525617D01*
G01Y526658D02*
X107234Y527283D01*
G01X105151Y528758D02*
X104901Y529008D01*
X104776Y529300D01*
X104734Y529633D01*
X104817Y530050D01*
X105026Y530342D01*
X105276Y530425D01*
X105526Y530383D01*
X105734Y530217D01*
X106151Y529383D01*
X106442Y529008D01*
X106859Y528758D01*
X107234Y528675D01*
Y530425D01*
G01X106734Y531733D02*
X107026Y531983D01*
X107192Y532317D01*
X107234Y532692D01*
X107192Y533025D01*
X106984Y533358D01*
X106734Y533567D01*
X106484Y533608D01*
X106192Y533525D01*
X105984Y533233D01*
X105901Y532942D01*
Y532567D01*
G01Y532942D02*
X105776Y533192D01*
X105567Y533400D01*
X105317Y533483D01*
X105067Y533400D01*
X104859Y533192D01*
X104734Y532817D01*
X104776Y532442D01*
X104942Y532067D01*
G01X105151Y534958D02*
X104901Y535208D01*
X104776Y535500D01*
X104734Y535833D01*
X104817Y536250D01*
X105026Y536542D01*
X105276Y536625D01*
X105526Y536583D01*
X105734Y536417D01*
X106151Y535583D01*
X106442Y535208D01*
X106859Y534958D01*
X107234Y534875D01*
Y536625D01*
G01X99113Y517377D02*
X103113D01*
Y524777D01*
G01X140000Y510100D02*
X144000D01*
Y517500D01*
G01X78917Y493900D02*
Y496400D01*
X79958D01*
X80292Y496275D01*
X80500Y496108D01*
X80583Y495775D01*
X80500Y495442D01*
X80250Y495233D01*
X79958Y495108D01*
X78917D01*
G01X79958D02*
X80583Y493900D01*
G01X81933Y494400D02*
X82183Y494108D01*
X82517Y493942D01*
X82892Y493900D01*
X83225Y493942D01*
X83558Y494150D01*
X83767Y494400D01*
X83808Y494650D01*
X83725Y494942D01*
X83433Y495150D01*
X83142Y495233D01*
X82767D01*
G01X83142D02*
X83392Y495358D01*
X83600Y495567D01*
X83683Y495817D01*
X83600Y496067D01*
X83392Y496275D01*
X83017Y496400D01*
X82642Y496358D01*
X82267Y496192D01*
G01X86450Y493900D02*
Y496400D01*
X84908Y494608D01*
X86992D01*
G01X88258Y494942D02*
X88550Y495233D01*
X88800Y495400D01*
X89133Y495483D01*
X89425Y495400D01*
X89633Y495233D01*
X89800Y494983D01*
X89842Y494692D01*
X89800Y494442D01*
X89633Y494192D01*
X89383Y493983D01*
X89092Y493900D01*
X88758Y493983D01*
X88467Y494233D01*
X88300Y494608D01*
X88258Y495025D01*
X88342Y495567D01*
X88467Y495858D01*
X88675Y496150D01*
X88967Y496358D01*
X89258Y496400D01*
X89550Y496317D01*
X89758Y496108D01*
G01X91531Y490941D02*
X95531D01*
Y498341D01*
G01X144100Y525300D02*
X140100D01*
Y517900D01*
G01X98000Y477817D02*
X95500D01*
Y478858D01*
X95625Y479192D01*
X95792Y479400D01*
X96125Y479483D01*
X96458Y479400D01*
X96667Y479150D01*
X96792Y478858D01*
Y477817D01*
G01Y478858D02*
X98000Y479483D01*
G01Y481667D02*
X97458Y481750D01*
X97000Y481875D01*
X96583Y482042D01*
X96125Y482250D01*
X95500Y482583D01*
Y480917D01*
G01X98000Y484850D02*
X97958Y485142D01*
X97833Y485475D01*
X97625Y485683D01*
X97333Y485767D01*
X97042Y485683D01*
X96792Y485433D01*
X96667Y485058D01*
Y484642D01*
X96583Y484392D01*
X96375Y484183D01*
X96083Y484100D01*
X95792Y484225D01*
X95583Y484517D01*
X95500Y484850D01*
X95583Y485183D01*
X95792Y485475D01*
X96083Y485600D01*
X96375Y485517D01*
X96583Y485308D01*
X96667Y485058D01*
Y484642D01*
X96792Y484267D01*
X97042Y484017D01*
X97333Y483933D01*
X97625Y484017D01*
X97833Y484225D01*
X97958Y484558D01*
X98000Y484850D01*
G01X97708Y487242D02*
X97917Y487533D01*
X98000Y487867D01*
X97917Y488200D01*
X97667Y488492D01*
X97292Y488700D01*
X96917Y488783D01*
X96458D01*
X96083Y488700D01*
X95750Y488492D01*
X95583Y488242D01*
X95500Y487950D01*
X95583Y487617D01*
X95750Y487367D01*
X96000Y487200D01*
X96333Y487117D01*
X96625Y487200D01*
X96917Y487408D01*
X97083Y487658D01*
X97125Y487950D01*
X97042Y488283D01*
X96833Y488533D01*
X96458Y488783D01*
G01X107920Y495118D02*
X103920D01*
Y487718D01*
G01X101700Y477817D02*
X99200D01*
Y478858D01*
X99325Y479192D01*
X99492Y479400D01*
X99825Y479483D01*
X100158Y479400D01*
X100367Y479150D01*
X100492Y478858D01*
Y477817D01*
G01Y478858D02*
X101700Y479483D01*
G01Y481667D02*
X101158Y481750D01*
X100700Y481875D01*
X100283Y482042D01*
X99825Y482250D01*
X99200Y482583D01*
Y480917D01*
G01X101700Y484850D02*
X101658Y485142D01*
X101533Y485475D01*
X101325Y485683D01*
X101033Y485767D01*
X100742Y485683D01*
X100492Y485433D01*
X100367Y485058D01*
Y484642D01*
X100283Y484392D01*
X100075Y484183D01*
X99783Y484100D01*
X99492Y484225D01*
X99283Y484517D01*
X99200Y484850D01*
X99283Y485183D01*
X99492Y485475D01*
X99783Y485600D01*
X100075Y485517D01*
X100283Y485308D01*
X100367Y485058D01*
Y484642D01*
X100492Y484267D01*
X100742Y484017D01*
X101033Y483933D01*
X101325Y484017D01*
X101533Y484225D01*
X101658Y484558D01*
X101700Y484850D01*
G01Y487950D02*
X101658Y488242D01*
X101533Y488575D01*
X101325Y488783D01*
X101033Y488867D01*
X100742Y488783D01*
X100492Y488533D01*
X100367Y488158D01*
Y487742D01*
X100283Y487492D01*
X100075Y487283D01*
X99783Y487200D01*
X99492Y487325D01*
X99283Y487617D01*
X99200Y487950D01*
X99283Y488283D01*
X99492Y488575D01*
X99783Y488700D01*
X100075Y488617D01*
X100283Y488408D01*
X100367Y488158D01*
Y487742D01*
X100492Y487367D01*
X100742Y487117D01*
X101033Y487033D01*
X101325Y487117D01*
X101533Y487325D01*
X101658Y487658D01*
X101700Y487950D01*
G01X112220Y495078D02*
X108220D01*
Y487678D01*
G01X106055Y505545D02*
X106388Y505337D01*
X106763Y505212D01*
X107097D01*
X107430Y505337D01*
X107680Y505545D01*
X107805Y505837D01*
X107722Y506129D01*
X107513Y506379D01*
X107138Y506545D01*
X106638Y506629D01*
X106347Y506795D01*
X106222Y507087D01*
X106305Y507379D01*
X106513Y507587D01*
X106805Y507712D01*
X107097D01*
X107388Y507629D01*
X107638Y507420D01*
G01X109113Y505212D02*
Y507712D01*
G01X110697D02*
X109113Y506170D01*
G01X110947Y505212D02*
X109822Y506879D01*
G01X113130Y507712D02*
Y505212D01*
G01X112172Y507712D02*
X114088D01*
G01X116230Y505212D02*
Y507712D01*
X115730Y507212D01*
G01Y505212D02*
X116730D01*
G01X107363Y502812D02*
Y501020D01*
X107530Y500645D01*
X107863Y500395D01*
X108280Y500312D01*
X108697Y500395D01*
X109030Y500645D01*
X109197Y501020D01*
Y502812D01*
G01X111380Y500312D02*
Y502812D01*
X110880Y502312D01*
G01Y500312D02*
X111880D01*
G01X114480D02*
Y502812D01*
X113980Y502312D01*
G01Y500312D02*
X114980D01*
G01X132060Y496499D02*
X157460D01*
G01X118350Y524666D02*
X118017Y524708D01*
X117725Y524874D01*
X117475Y525124D01*
X117308Y525416D01*
X117225Y525749D01*
Y526083D01*
X117308Y526416D01*
X117475Y526708D01*
X117725Y526958D01*
X118017Y527124D01*
X118350Y527166D01*
X118683Y527124D01*
X118975Y526958D01*
X119225Y526708D01*
X119392Y526416D01*
X119475Y526083D01*
Y525749D01*
X119392Y525416D01*
X119225Y525124D01*
X118975Y524874D01*
X118683Y524708D01*
X118350Y524666D01*
G01X120575Y524999D02*
X120908Y524791D01*
X121283Y524666D01*
X121617D01*
X121950Y524791D01*
X122200Y524999D01*
X122325Y525291D01*
X122242Y525583D01*
X122033Y525833D01*
X121658Y525999D01*
X121158Y526083D01*
X120867Y526249D01*
X120742Y526541D01*
X120825Y526833D01*
X121033Y527041D01*
X121325Y527166D01*
X121617D01*
X121908Y527083D01*
X122158Y526874D01*
G01X125467Y526958D02*
X125217Y527083D01*
X124925Y527166D01*
X124592D01*
X124217Y527041D01*
X123925Y526833D01*
X123717Y526583D01*
X123550Y526166D01*
X123508Y525791D01*
X123592Y525416D01*
X123717Y525166D01*
X123967Y524916D01*
X124258Y524749D01*
X124550Y524666D01*
X124842D01*
X125133Y524749D01*
X125383Y524874D01*
X125592Y525041D01*
G01X127650Y524666D02*
Y527166D01*
X127150Y526666D01*
G01Y524666D02*
X128150D01*
G01X122050Y523850D02*
X138750D01*
Y511750D01*
X122050D01*
Y523850D01*
G01X96214Y509752D02*
Y498952D01*
X91014D01*
Y509752D01*
X96214D01*
G01X110717Y533400D02*
Y535900D01*
X111758D01*
X112092Y535775D01*
X112300Y535608D01*
X112383Y535275D01*
X112300Y534942D01*
X112050Y534733D01*
X111758Y534608D01*
X110717D01*
G01X111758D02*
X112383Y533400D01*
G01X113858Y535483D02*
X114108Y535733D01*
X114400Y535858D01*
X114733Y535900D01*
X115150Y535817D01*
X115442Y535608D01*
X115525Y535358D01*
X115483Y535108D01*
X115317Y534900D01*
X114483Y534483D01*
X114108Y534192D01*
X113858Y533775D01*
X113775Y533400D01*
X115525D01*
G01X117750D02*
X118042Y533442D01*
X118375Y533567D01*
X118583Y533775D01*
X118667Y534067D01*
X118583Y534358D01*
X118333Y534608D01*
X117958Y534733D01*
X117542D01*
X117292Y534817D01*
X117083Y535025D01*
X117000Y535317D01*
X117125Y535608D01*
X117417Y535817D01*
X117750Y535900D01*
X118083Y535817D01*
X118375Y535608D01*
X118500Y535317D01*
X118417Y535025D01*
X118208Y534817D01*
X117958Y534733D01*
X117542D01*
X117167Y534608D01*
X116917Y534358D01*
X116833Y534067D01*
X116917Y533775D01*
X117125Y533567D01*
X117458Y533442D01*
X117750Y533400D01*
G01X119933Y533900D02*
X120183Y533608D01*
X120517Y533442D01*
X120892Y533400D01*
X121225Y533442D01*
X121558Y533650D01*
X121767Y533900D01*
X121808Y534150D01*
X121725Y534442D01*
X121433Y534650D01*
X121142Y534733D01*
X120767D01*
G01X121142D02*
X121392Y534858D01*
X121600Y535067D01*
X121683Y535317D01*
X121600Y535567D01*
X121392Y535775D01*
X121017Y535900D01*
X120642Y535858D01*
X120267Y535692D01*
G01X125000Y536600D02*
Y532600D01*
X132400D01*
G01X130017Y587167D02*
Y589667D01*
X131058D01*
X131392Y589542D01*
X131600Y589375D01*
X131683Y589042D01*
X131600Y588709D01*
X131350Y588500D01*
X131058Y588375D01*
X130017D01*
G01X131058D02*
X131683Y587167D01*
G01X133033Y587667D02*
X133283Y587375D01*
X133617Y587209D01*
X133992Y587167D01*
X134325Y587209D01*
X134658Y587417D01*
X134867Y587667D01*
X134908Y587917D01*
X134825Y588209D01*
X134533Y588417D01*
X134242Y588500D01*
X133867D01*
G01X134242D02*
X134492Y588625D01*
X134700Y588834D01*
X134783Y589084D01*
X134700Y589334D01*
X134492Y589542D01*
X134117Y589667D01*
X133742Y589625D01*
X133367Y589459D01*
G01X137050Y587167D02*
Y589667D01*
X136550Y589167D01*
G01Y587167D02*
X137550D01*
G01X139442Y587459D02*
X139733Y587250D01*
X140067Y587167D01*
X140400Y587250D01*
X140692Y587500D01*
X140900Y587875D01*
X140983Y588250D01*
Y588709D01*
X140900Y589084D01*
X140692Y589417D01*
X140442Y589584D01*
X140150Y589667D01*
X139817Y589584D01*
X139567Y589417D01*
X139400Y589167D01*
X139317Y588834D01*
X139400Y588542D01*
X139608Y588250D01*
X139858Y588084D01*
X140150Y588042D01*
X140483Y588125D01*
X140733Y588334D01*
X140983Y588709D01*
G01X129917Y583117D02*
Y585617D01*
X130958D01*
X131292Y585492D01*
X131500Y585325D01*
X131583Y584992D01*
X131500Y584659D01*
X131250Y584450D01*
X130958Y584325D01*
X129917D01*
G01X130958D02*
X131583Y583117D01*
G01X132933Y583617D02*
X133183Y583325D01*
X133517Y583159D01*
X133892Y583117D01*
X134225Y583159D01*
X134558Y583367D01*
X134767Y583617D01*
X134808Y583867D01*
X134725Y584159D01*
X134433Y584367D01*
X134142Y584450D01*
X133767D01*
G01X134142D02*
X134392Y584575D01*
X134600Y584784D01*
X134683Y585034D01*
X134600Y585284D01*
X134392Y585492D01*
X134017Y585617D01*
X133642Y585575D01*
X133267Y585409D01*
G01X136033Y583617D02*
X136283Y583325D01*
X136617Y583159D01*
X136992Y583117D01*
X137325Y583159D01*
X137658Y583367D01*
X137867Y583617D01*
X137908Y583867D01*
X137825Y584159D01*
X137533Y584367D01*
X137242Y584450D01*
X136867D01*
G01X137242D02*
X137492Y584575D01*
X137700Y584784D01*
X137783Y585034D01*
X137700Y585284D01*
X137492Y585492D01*
X137117Y585617D01*
X136742Y585575D01*
X136367Y585409D01*
G01X139133Y583617D02*
X139383Y583325D01*
X139717Y583159D01*
X140092Y583117D01*
X140425Y583159D01*
X140758Y583367D01*
X140967Y583617D01*
X141008Y583867D01*
X140925Y584159D01*
X140633Y584367D01*
X140342Y584450D01*
X139967D01*
G01X140342D02*
X140592Y584575D01*
X140800Y584784D01*
X140883Y585034D01*
X140800Y585284D01*
X140592Y585492D01*
X140217Y585617D01*
X139842Y585575D01*
X139467Y585409D01*
G01X105234Y573617D02*
X102734D01*
Y574658D01*
X102859Y574992D01*
X103026Y575200D01*
X103359Y575283D01*
X103692Y575200D01*
X103901Y574950D01*
X104026Y574658D01*
Y573617D01*
G01Y574658D02*
X105234Y575283D01*
G01X103151Y576758D02*
X102901Y577008D01*
X102776Y577300D01*
X102734Y577633D01*
X102817Y578050D01*
X103026Y578342D01*
X103276Y578425D01*
X103526Y578383D01*
X103734Y578217D01*
X104151Y577383D01*
X104442Y577008D01*
X104859Y576758D01*
X105234Y576675D01*
Y578425D01*
G01Y580650D02*
X102734D01*
X103234Y580150D01*
G01X105234D02*
Y581150D01*
G01X104942Y583042D02*
X105151Y583333D01*
X105234Y583667D01*
X105151Y584000D01*
X104901Y584292D01*
X104526Y584500D01*
X104151Y584583D01*
X103692D01*
X103317Y584500D01*
X102984Y584292D01*
X102817Y584042D01*
X102734Y583750D01*
X102817Y583417D01*
X102984Y583167D01*
X103234Y583000D01*
X103567Y582917D01*
X103859Y583000D01*
X104151Y583208D01*
X104317Y583458D01*
X104359Y583750D01*
X104276Y584083D01*
X104067Y584333D01*
X103692Y584583D01*
G01X110600Y575950D02*
X106600D01*
Y568550D01*
G01X130017Y541667D02*
Y544167D01*
X131058D01*
X131392Y544042D01*
X131600Y543875D01*
X131683Y543542D01*
X131600Y543209D01*
X131350Y543000D01*
X131058Y542875D01*
X130017D01*
G01X131058D02*
X131683Y541667D01*
G01X133158Y543750D02*
X133408Y544000D01*
X133700Y544125D01*
X134033Y544167D01*
X134450Y544084D01*
X134742Y543875D01*
X134825Y543625D01*
X134783Y543375D01*
X134617Y543167D01*
X133783Y542750D01*
X133408Y542459D01*
X133158Y542042D01*
X133075Y541667D01*
X134825D01*
G01X137050D02*
X137342Y541709D01*
X137675Y541834D01*
X137883Y542042D01*
X137967Y542334D01*
X137883Y542625D01*
X137633Y542875D01*
X137258Y543000D01*
X136842D01*
X136592Y543084D01*
X136383Y543292D01*
X136300Y543584D01*
X136425Y543875D01*
X136717Y544084D01*
X137050Y544167D01*
X137383Y544084D01*
X137675Y543875D01*
X137800Y543584D01*
X137717Y543292D01*
X137508Y543084D01*
X137258Y543000D01*
X136842D01*
X136467Y542875D01*
X136217Y542625D01*
X136133Y542334D01*
X136217Y542042D01*
X136425Y541834D01*
X136758Y541709D01*
X137050Y541667D01*
G01X140150Y544167D02*
X139817Y544084D01*
X139567Y543875D01*
X139400Y543625D01*
X139275Y543292D01*
X139233Y542917D01*
X139275Y542542D01*
X139400Y542209D01*
X139567Y541959D01*
X139817Y541750D01*
X140150Y541667D01*
X140483Y541750D01*
X140733Y541959D01*
X140900Y542209D01*
X141025Y542542D01*
X141067Y542917D01*
X141025Y543292D01*
X140900Y543625D01*
X140733Y543875D01*
X140483Y544084D01*
X140150Y544167D01*
G01X134900Y531700D02*
Y527700D01*
X142300D01*
G01X130593Y591184D02*
Y593684D01*
X131634D01*
X131968Y593559D01*
X132176Y593392D01*
X132259Y593059D01*
X132176Y592726D01*
X131926Y592517D01*
X131634Y592392D01*
X130593D01*
G01X131634D02*
X132259Y591184D01*
G01X133609Y591684D02*
X133859Y591392D01*
X134193Y591226D01*
X134568Y591184D01*
X134901Y591226D01*
X135234Y591434D01*
X135443Y591684D01*
X135484Y591934D01*
X135401Y592226D01*
X135109Y592434D01*
X134818Y592517D01*
X134443D01*
G01X134818D02*
X135068Y592642D01*
X135276Y592851D01*
X135359Y593101D01*
X135276Y593351D01*
X135068Y593559D01*
X134693Y593684D01*
X134318Y593642D01*
X133943Y593476D01*
G01X136834Y593267D02*
X137084Y593517D01*
X137376Y593642D01*
X137709Y593684D01*
X138126Y593601D01*
X138418Y593392D01*
X138501Y593142D01*
X138459Y592892D01*
X138293Y592684D01*
X137459Y592267D01*
X137084Y591976D01*
X136834Y591559D01*
X136751Y591184D01*
X138501D01*
G01X139934Y593267D02*
X140184Y593517D01*
X140476Y593642D01*
X140809Y593684D01*
X141226Y593601D01*
X141518Y593392D01*
X141601Y593142D01*
X141559Y592892D01*
X141393Y592684D01*
X140559Y592267D01*
X140184Y591976D01*
X139934Y591559D01*
X139851Y591184D01*
X141601D01*
G01X117017Y589167D02*
Y591667D01*
X118058D01*
X118392Y591542D01*
X118600Y591375D01*
X118683Y591042D01*
X118600Y590709D01*
X118350Y590500D01*
X118058Y590375D01*
X117017D01*
G01X118058D02*
X118683Y589167D01*
G01X120033Y589667D02*
X120283Y589375D01*
X120617Y589209D01*
X120992Y589167D01*
X121325Y589209D01*
X121658Y589417D01*
X121867Y589667D01*
X121908Y589917D01*
X121825Y590209D01*
X121533Y590417D01*
X121242Y590500D01*
X120867D01*
G01X121242D02*
X121492Y590625D01*
X121700Y590834D01*
X121783Y591084D01*
X121700Y591334D01*
X121492Y591542D01*
X121117Y591667D01*
X120742Y591625D01*
X120367Y591459D01*
G01X123133Y589667D02*
X123383Y589375D01*
X123717Y589209D01*
X124092Y589167D01*
X124425Y589209D01*
X124758Y589417D01*
X124967Y589667D01*
X125008Y589917D01*
X124925Y590209D01*
X124633Y590417D01*
X124342Y590500D01*
X123967D01*
G01X124342D02*
X124592Y590625D01*
X124800Y590834D01*
X124883Y591084D01*
X124800Y591334D01*
X124592Y591542D01*
X124217Y591667D01*
X123842Y591625D01*
X123467Y591459D01*
G01X127150Y589167D02*
Y591667D01*
X126650Y591167D01*
G01Y589167D02*
X127650D01*
G01X130017Y545667D02*
Y548167D01*
X131058D01*
X131392Y548042D01*
X131600Y547875D01*
X131683Y547542D01*
X131600Y547209D01*
X131350Y547000D01*
X131058Y546875D01*
X130017D01*
G01X131058D02*
X131683Y545667D01*
G01X133033Y546167D02*
X133283Y545875D01*
X133617Y545709D01*
X133992Y545667D01*
X134325Y545709D01*
X134658Y545917D01*
X134867Y546167D01*
X134908Y546417D01*
X134825Y546709D01*
X134533Y546917D01*
X134242Y547000D01*
X133867D01*
G01X134242D02*
X134492Y547125D01*
X134700Y547334D01*
X134783Y547584D01*
X134700Y547834D01*
X134492Y548042D01*
X134117Y548167D01*
X133742Y548125D01*
X133367Y547959D01*
G01X136133Y546042D02*
X136383Y545834D01*
X136675Y545709D01*
X137050Y545667D01*
X137425Y545750D01*
X137717Y545917D01*
X137925Y546209D01*
X137967Y546542D01*
X137883Y546875D01*
X137675Y547084D01*
X137383Y547250D01*
X137092Y547292D01*
X136800Y547250D01*
X136425Y547084D01*
X136550Y548167D01*
X137675D01*
G01X140150Y545667D02*
Y548167D01*
X139650Y547667D01*
G01Y545667D02*
X140650D01*
G01X135024Y540335D02*
Y536335D01*
X142424D01*
G01X110717Y529100D02*
Y531600D01*
X111758D01*
X112092Y531475D01*
X112300Y531308D01*
X112383Y530975D01*
X112300Y530642D01*
X112050Y530433D01*
X111758Y530308D01*
X110717D01*
G01X111758D02*
X112383Y529100D01*
G01X113733Y529600D02*
X113983Y529308D01*
X114317Y529142D01*
X114692Y529100D01*
X115025Y529142D01*
X115358Y529350D01*
X115567Y529600D01*
X115608Y529850D01*
X115525Y530142D01*
X115233Y530350D01*
X114942Y530433D01*
X114567D01*
G01X114942D02*
X115192Y530558D01*
X115400Y530767D01*
X115483Y531017D01*
X115400Y531267D01*
X115192Y531475D01*
X114817Y531600D01*
X114442Y531558D01*
X114067Y531392D01*
G01X116958Y530142D02*
X117250Y530433D01*
X117500Y530600D01*
X117833Y530683D01*
X118125Y530600D01*
X118333Y530433D01*
X118500Y530183D01*
X118542Y529892D01*
X118500Y529642D01*
X118333Y529392D01*
X118083Y529183D01*
X117792Y529100D01*
X117458Y529183D01*
X117167Y529433D01*
X117000Y529808D01*
X116958Y530225D01*
X117042Y530767D01*
X117167Y531058D01*
X117375Y531350D01*
X117667Y531558D01*
X117958Y531600D01*
X118250Y531517D01*
X118458Y531308D01*
G01X120142Y529392D02*
X120433Y529183D01*
X120767Y529100D01*
X121100Y529183D01*
X121392Y529433D01*
X121600Y529808D01*
X121683Y530183D01*
Y530642D01*
X121600Y531017D01*
X121392Y531350D01*
X121142Y531517D01*
X120850Y531600D01*
X120517Y531517D01*
X120267Y531350D01*
X120100Y531100D01*
X120017Y530767D01*
X120100Y530475D01*
X120308Y530183D01*
X120558Y530017D01*
X120850Y529975D01*
X121183Y530058D01*
X121433Y530267D01*
X121683Y530642D01*
G01X125000Y532300D02*
Y528300D01*
X132400D01*
G01X116594Y585190D02*
Y587690D01*
X117635D01*
X117969Y587565D01*
X118177Y587398D01*
X118260Y587065D01*
X118177Y586732D01*
X117927Y586523D01*
X117635Y586398D01*
X116594D01*
G01X117635D02*
X118260Y585190D01*
G01X120444D02*
X120527Y585732D01*
X120652Y586190D01*
X120819Y586607D01*
X121027Y587065D01*
X121360Y587690D01*
X119694D01*
G01X123627D02*
X123294Y587607D01*
X123044Y587398D01*
X122877Y587148D01*
X122752Y586815D01*
X122710Y586440D01*
X122752Y586065D01*
X122877Y585732D01*
X123044Y585482D01*
X123294Y585273D01*
X123627Y585190D01*
X123960Y585273D01*
X124210Y585482D01*
X124377Y585732D01*
X124502Y586065D01*
X124544Y586440D01*
X124502Y586815D01*
X124377Y587148D01*
X124210Y587398D01*
X123960Y587607D01*
X123627Y587690D01*
G01X126727Y585190D02*
Y587690D01*
X126227Y587190D01*
G01Y585190D02*
X127227D01*
G01X88517Y592167D02*
Y594667D01*
X89558D01*
X89892Y594542D01*
X90100Y594375D01*
X90183Y594042D01*
X90100Y593709D01*
X89850Y593500D01*
X89558Y593375D01*
X88517D01*
G01X89558D02*
X90183Y592167D01*
G01X92367D02*
X92450Y592709D01*
X92575Y593167D01*
X92742Y593584D01*
X92950Y594042D01*
X93283Y594667D01*
X91617D01*
G01X94758Y593209D02*
X95050Y593500D01*
X95300Y593667D01*
X95633Y593750D01*
X95925Y593667D01*
X96133Y593500D01*
X96300Y593250D01*
X96342Y592959D01*
X96300Y592709D01*
X96133Y592459D01*
X95883Y592250D01*
X95592Y592167D01*
X95258Y592250D01*
X94967Y592500D01*
X94800Y592875D01*
X94758Y593292D01*
X94842Y593834D01*
X94967Y594125D01*
X95175Y594417D01*
X95467Y594625D01*
X95758Y594667D01*
X96050Y594584D01*
X96258Y594375D01*
G01X98650Y592167D02*
X98942Y592209D01*
X99275Y592334D01*
X99483Y592542D01*
X99567Y592834D01*
X99483Y593125D01*
X99233Y593375D01*
X98858Y593500D01*
X98442D01*
X98192Y593584D01*
X97983Y593792D01*
X97900Y594084D01*
X98025Y594375D01*
X98317Y594584D01*
X98650Y594667D01*
X98983Y594584D01*
X99275Y594375D01*
X99400Y594084D01*
X99317Y593792D01*
X99108Y593584D01*
X98858Y593500D01*
X98442D01*
X98067Y593375D01*
X97817Y593125D01*
X97733Y592834D01*
X97817Y592542D01*
X98025Y592334D01*
X98358Y592209D01*
X98650Y592167D01*
G01X137233Y572367D02*
Y570575D01*
X137400Y570200D01*
X137733Y569950D01*
X138150Y569867D01*
X138567Y569950D01*
X138900Y570200D01*
X139067Y570575D01*
Y572367D01*
G01X140458Y571950D02*
X140708Y572200D01*
X141000Y572325D01*
X141333Y572367D01*
X141750Y572284D01*
X142042Y572075D01*
X142125Y571825D01*
X142083Y571575D01*
X141917Y571367D01*
X141083Y570950D01*
X140708Y570659D01*
X140458Y570242D01*
X140375Y569867D01*
X142125D01*
G01X143500Y620000D02*
X167000D01*
Y611500D01*
X228500D01*
G01X142000Y626500D02*
Y640900D01*
X157000D01*
G01X99542Y654767D02*
X99417Y654517D01*
X99334Y654225D01*
Y653892D01*
X99459Y653517D01*
X99667Y653225D01*
X99917Y653017D01*
X100334Y652850D01*
X100709Y652808D01*
X101084Y652892D01*
X101334Y653017D01*
X101584Y653267D01*
X101751Y653558D01*
X101834Y653850D01*
Y654142D01*
X101751Y654433D01*
X101626Y654683D01*
X101459Y654892D01*
G01X99751Y656158D02*
X99501Y656408D01*
X99376Y656700D01*
X99334Y657033D01*
X99417Y657450D01*
X99626Y657742D01*
X99876Y657825D01*
X100126Y657783D01*
X100334Y657617D01*
X100751Y656783D01*
X101042Y656408D01*
X101459Y656158D01*
X101834Y656075D01*
Y657825D01*
G01X99751Y659258D02*
X99501Y659508D01*
X99376Y659800D01*
X99334Y660133D01*
X99417Y660550D01*
X99626Y660842D01*
X99876Y660925D01*
X100126Y660883D01*
X100334Y660717D01*
X100751Y659883D01*
X101042Y659508D01*
X101459Y659258D01*
X101834Y659175D01*
Y660925D01*
G01X101334Y662233D02*
X101626Y662483D01*
X101792Y662817D01*
X101834Y663192D01*
X101792Y663525D01*
X101584Y663858D01*
X101334Y664067D01*
X101084Y664108D01*
X100792Y664025D01*
X100584Y663733D01*
X100501Y663442D01*
Y663067D01*
G01Y663442D02*
X100376Y663692D01*
X100167Y663900D01*
X99917Y663983D01*
X99667Y663900D01*
X99459Y663692D01*
X99334Y663317D01*
X99376Y662942D01*
X99542Y662567D01*
G01X103342Y655067D02*
X103217Y654817D01*
X103134Y654525D01*
Y654192D01*
X103259Y653817D01*
X103467Y653525D01*
X103717Y653317D01*
X104134Y653150D01*
X104509Y653108D01*
X104884Y653192D01*
X105134Y653317D01*
X105384Y653567D01*
X105551Y653858D01*
X105634Y654150D01*
Y654442D01*
X105551Y654733D01*
X105426Y654983D01*
X105259Y655192D01*
G01X103551Y656458D02*
X103301Y656708D01*
X103176Y657000D01*
X103134Y657333D01*
X103217Y657750D01*
X103426Y658042D01*
X103676Y658125D01*
X103926Y658083D01*
X104134Y657917D01*
X104551Y657083D01*
X104842Y656708D01*
X105259Y656458D01*
X105634Y656375D01*
Y658125D01*
G01X103551Y659558D02*
X103301Y659808D01*
X103176Y660100D01*
X103134Y660433D01*
X103217Y660850D01*
X103426Y661142D01*
X103676Y661225D01*
X103926Y661183D01*
X104134Y661017D01*
X104551Y660183D01*
X104842Y659808D01*
X105259Y659558D01*
X105634Y659475D01*
Y661225D01*
G01Y663950D02*
X103134D01*
X104926Y662408D01*
Y664492D01*
G01X90767Y627792D02*
X90517Y627917D01*
X90225Y628000D01*
X89892D01*
X89517Y627875D01*
X89225Y627667D01*
X89017Y627417D01*
X88850Y627000D01*
X88808Y626625D01*
X88892Y626250D01*
X89017Y626000D01*
X89267Y625750D01*
X89558Y625583D01*
X89850Y625500D01*
X90142D01*
X90433Y625583D01*
X90683Y625708D01*
X90892Y625875D01*
G01X92158Y627583D02*
X92408Y627833D01*
X92700Y627958D01*
X93033Y628000D01*
X93450Y627917D01*
X93742Y627708D01*
X93825Y627458D01*
X93783Y627208D01*
X93617Y627000D01*
X92783Y626583D01*
X92408Y626292D01*
X92158Y625875D01*
X92075Y625500D01*
X93825D01*
G01X95258Y627583D02*
X95508Y627833D01*
X95800Y627958D01*
X96133Y628000D01*
X96550Y627917D01*
X96842Y627708D01*
X96925Y627458D01*
X96883Y627208D01*
X96717Y627000D01*
X95883Y626583D01*
X95508Y626292D01*
X95258Y625875D01*
X95175Y625500D01*
X96925D01*
G01X98233Y625875D02*
X98483Y625667D01*
X98775Y625542D01*
X99150Y625500D01*
X99525Y625583D01*
X99817Y625750D01*
X100025Y626042D01*
X100067Y626375D01*
X99983Y626708D01*
X99775Y626917D01*
X99483Y627083D01*
X99192Y627125D01*
X98900Y627083D01*
X98525Y626917D01*
X98650Y628000D01*
X99775D01*
G01X90767Y631492D02*
X90517Y631617D01*
X90225Y631700D01*
X89892D01*
X89517Y631575D01*
X89225Y631367D01*
X89017Y631117D01*
X88850Y630700D01*
X88808Y630325D01*
X88892Y629950D01*
X89017Y629700D01*
X89267Y629450D01*
X89558Y629283D01*
X89850Y629200D01*
X90142D01*
X90433Y629283D01*
X90683Y629408D01*
X90892Y629575D01*
G01X92158Y631283D02*
X92408Y631533D01*
X92700Y631658D01*
X93033Y631700D01*
X93450Y631617D01*
X93742Y631408D01*
X93825Y631158D01*
X93783Y630908D01*
X93617Y630700D01*
X92783Y630283D01*
X92408Y629992D01*
X92158Y629575D01*
X92075Y629200D01*
X93825D01*
G01X95258Y631283D02*
X95508Y631533D01*
X95800Y631658D01*
X96133Y631700D01*
X96550Y631617D01*
X96842Y631408D01*
X96925Y631158D01*
X96883Y630908D01*
X96717Y630700D01*
X95883Y630283D01*
X95508Y629992D01*
X95258Y629575D01*
X95175Y629200D01*
X96925D01*
G01X98358Y630242D02*
X98650Y630533D01*
X98900Y630700D01*
X99233Y630783D01*
X99525Y630700D01*
X99733Y630533D01*
X99900Y630283D01*
X99942Y629992D01*
X99900Y629742D01*
X99733Y629492D01*
X99483Y629283D01*
X99192Y629200D01*
X98858Y629283D01*
X98567Y629533D01*
X98400Y629908D01*
X98358Y630325D01*
X98442Y630867D01*
X98567Y631158D01*
X98775Y631450D01*
X99067Y631658D01*
X99358Y631700D01*
X99650Y631617D01*
X99858Y631408D01*
G01X136662Y601311D02*
Y605311D01*
X129262D01*
G01X122040Y622823D02*
Y625323D01*
X123081D01*
X123415Y625198D01*
X123623Y625031D01*
X123706Y624698D01*
X123623Y624365D01*
X123373Y624156D01*
X123081Y624031D01*
X122040D01*
G01X123081D02*
X123706Y622823D01*
G01X125056Y623323D02*
X125306Y623031D01*
X125640Y622865D01*
X126015Y622823D01*
X126348Y622865D01*
X126681Y623073D01*
X126890Y623323D01*
X126931Y623573D01*
X126848Y623865D01*
X126556Y624073D01*
X126265Y624156D01*
X125890D01*
G01X126265D02*
X126515Y624281D01*
X126723Y624490D01*
X126806Y624740D01*
X126723Y624990D01*
X126515Y625198D01*
X126140Y625323D01*
X125765Y625281D01*
X125390Y625115D01*
G01X128281Y624906D02*
X128531Y625156D01*
X128823Y625281D01*
X129156Y625323D01*
X129573Y625240D01*
X129865Y625031D01*
X129948Y624781D01*
X129906Y624531D01*
X129740Y624323D01*
X128906Y623906D01*
X128531Y623615D01*
X128281Y623198D01*
X128198Y622823D01*
X129948D01*
G01X132173Y625323D02*
X131840Y625240D01*
X131590Y625031D01*
X131423Y624781D01*
X131298Y624448D01*
X131256Y624073D01*
X131298Y623698D01*
X131423Y623365D01*
X131590Y623115D01*
X131840Y622906D01*
X132173Y622823D01*
X132506Y622906D01*
X132756Y623115D01*
X132923Y623365D01*
X133048Y623698D01*
X133090Y624073D01*
X133048Y624448D01*
X132923Y624781D01*
X132756Y625031D01*
X132506Y625240D01*
X132173Y625323D01*
G01X137418Y615677D02*
Y619677D01*
X130018D01*
G01X136650Y597250D02*
Y601250D01*
X129250D01*
G01X138153Y607777D02*
Y611777D01*
X130753D01*
G01X118003Y611818D02*
Y607818D01*
X125403D01*
G01X147300Y628200D02*
X143300D01*
Y620800D01*
G01X120997Y603923D02*
Y599923D01*
X128397D01*
G01X114700Y595000D02*
Y599000D01*
X107300D01*
G01X88517Y596667D02*
Y599167D01*
X89558D01*
X89892Y599042D01*
X90100Y598875D01*
X90183Y598542D01*
X90100Y598209D01*
X89850Y598000D01*
X89558Y597875D01*
X88517D01*
G01X89558D02*
X90183Y596667D01*
G01X92367D02*
X92450Y597209D01*
X92575Y597667D01*
X92742Y598084D01*
X92950Y598542D01*
X93283Y599167D01*
X91617D01*
G01X94758Y597709D02*
X95050Y598000D01*
X95300Y598167D01*
X95633Y598250D01*
X95925Y598167D01*
X96133Y598000D01*
X96300Y597750D01*
X96342Y597459D01*
X96300Y597209D01*
X96133Y596959D01*
X95883Y596750D01*
X95592Y596667D01*
X95258Y596750D01*
X94967Y597000D01*
X94800Y597375D01*
X94758Y597792D01*
X94842Y598334D01*
X94967Y598625D01*
X95175Y598917D01*
X95467Y599125D01*
X95758Y599167D01*
X96050Y599084D01*
X96258Y598875D01*
G01X97942Y596959D02*
X98233Y596750D01*
X98567Y596667D01*
X98900Y596750D01*
X99192Y597000D01*
X99400Y597375D01*
X99483Y597750D01*
Y598209D01*
X99400Y598584D01*
X99192Y598917D01*
X98942Y599084D01*
X98650Y599167D01*
X98317Y599084D01*
X98067Y598917D01*
X97900Y598667D01*
X97817Y598334D01*
X97900Y598042D01*
X98108Y597750D01*
X98358Y597584D01*
X98650Y597542D01*
X98983Y597625D01*
X99233Y597834D01*
X99483Y598209D01*
G01X114700Y599000D02*
Y603000D01*
X107300D01*
G01X90517Y604667D02*
Y607167D01*
X91558D01*
X91892Y607042D01*
X92100Y606875D01*
X92183Y606542D01*
X92100Y606209D01*
X91850Y606000D01*
X91558Y605875D01*
X90517D01*
G01X91558D02*
X92183Y604667D01*
G01X94367D02*
X94450Y605209D01*
X94575Y605667D01*
X94742Y606084D01*
X94950Y606542D01*
X95283Y607167D01*
X93617D01*
G01X97467Y604667D02*
X97550Y605209D01*
X97675Y605667D01*
X97842Y606084D01*
X98050Y606542D01*
X98383Y607167D01*
X96717D01*
G01X100650D02*
X100317Y607084D01*
X100067Y606875D01*
X99900Y606625D01*
X99775Y606292D01*
X99733Y605917D01*
X99775Y605542D01*
X99900Y605209D01*
X100067Y604959D01*
X100317Y604750D01*
X100650Y604667D01*
X100983Y604750D01*
X101233Y604959D01*
X101400Y605209D01*
X101525Y605542D01*
X101567Y605917D01*
X101525Y606292D01*
X101400Y606625D01*
X101233Y606875D01*
X100983Y607084D01*
X100650Y607167D01*
G01X114700Y607000D02*
Y611000D01*
X107300D01*
G01X90517Y600667D02*
Y603167D01*
X91558D01*
X91892Y603042D01*
X92100Y602875D01*
X92183Y602542D01*
X92100Y602209D01*
X91850Y602000D01*
X91558Y601875D01*
X90517D01*
G01X91558D02*
X92183Y600667D01*
G01X94367D02*
X94450Y601209D01*
X94575Y601667D01*
X94742Y602084D01*
X94950Y602542D01*
X95283Y603167D01*
X93617D01*
G01X97467Y600667D02*
X97550Y601209D01*
X97675Y601667D01*
X97842Y602084D01*
X98050Y602542D01*
X98383Y603167D01*
X96717D01*
G01X100650Y600667D02*
Y603167D01*
X100150Y602667D01*
G01Y600667D02*
X101150D01*
G01X114700Y603000D02*
Y607000D01*
X107300D01*
G01X90517Y609167D02*
Y611667D01*
X91558D01*
X91892Y611542D01*
X92100Y611375D01*
X92183Y611042D01*
X92100Y610709D01*
X91850Y610500D01*
X91558Y610375D01*
X90517D01*
G01X91558D02*
X92183Y609167D01*
G01X94367D02*
X94450Y609709D01*
X94575Y610167D01*
X94742Y610584D01*
X94950Y611042D01*
X95283Y611667D01*
X93617D01*
G01X97467Y609167D02*
X97550Y609709D01*
X97675Y610167D01*
X97842Y610584D01*
X98050Y611042D01*
X98383Y611667D01*
X96717D01*
G01X99858Y611250D02*
X100108Y611500D01*
X100400Y611625D01*
X100733Y611667D01*
X101150Y611584D01*
X101442Y611375D01*
X101525Y611125D01*
X101483Y610875D01*
X101317Y610667D01*
X100483Y610250D01*
X100108Y609959D01*
X99858Y609542D01*
X99775Y609167D01*
X101525D01*
G01X114700Y611000D02*
Y615000D01*
X107300D01*
G01X90517Y618167D02*
Y620667D01*
X91558D01*
X91892Y620542D01*
X92100Y620375D01*
X92183Y620042D01*
X92100Y619709D01*
X91850Y619500D01*
X91558Y619375D01*
X90517D01*
G01X91558D02*
X92183Y618167D01*
G01X94367D02*
X94450Y618709D01*
X94575Y619167D01*
X94742Y619584D01*
X94950Y620042D01*
X95283Y620667D01*
X93617D01*
G01X97467Y618167D02*
X97550Y618709D01*
X97675Y619167D01*
X97842Y619584D01*
X98050Y620042D01*
X98383Y620667D01*
X96717D01*
G01X99733Y618667D02*
X99983Y618375D01*
X100317Y618209D01*
X100692Y618167D01*
X101025Y618209D01*
X101358Y618417D01*
X101567Y618667D01*
X101608Y618917D01*
X101525Y619209D01*
X101233Y619417D01*
X100942Y619500D01*
X100567D01*
G01X100942D02*
X101192Y619625D01*
X101400Y619834D01*
X101483Y620084D01*
X101400Y620334D01*
X101192Y620542D01*
X100817Y620667D01*
X100442Y620625D01*
X100067Y620459D01*
G01X115200Y619000D02*
Y623000D01*
X107800D01*
G01X90517Y613667D02*
Y616167D01*
X91558D01*
X91892Y616042D01*
X92100Y615875D01*
X92183Y615542D01*
X92100Y615209D01*
X91850Y615000D01*
X91558Y614875D01*
X90517D01*
G01X91558D02*
X92183Y613667D01*
G01X94367D02*
X94450Y614209D01*
X94575Y614667D01*
X94742Y615084D01*
X94950Y615542D01*
X95283Y616167D01*
X93617D01*
G01X97550Y613667D02*
X97842Y613709D01*
X98175Y613834D01*
X98383Y614042D01*
X98467Y614334D01*
X98383Y614625D01*
X98133Y614875D01*
X97758Y615000D01*
X97342D01*
X97092Y615084D01*
X96883Y615292D01*
X96800Y615584D01*
X96925Y615875D01*
X97217Y616084D01*
X97550Y616167D01*
X97883Y616084D01*
X98175Y615875D01*
X98300Y615584D01*
X98217Y615292D01*
X98008Y615084D01*
X97758Y615000D01*
X97342D01*
X96967Y614875D01*
X96717Y614625D01*
X96633Y614334D01*
X96717Y614042D01*
X96925Y613834D01*
X97258Y613709D01*
X97550Y613667D01*
G01X99858Y614709D02*
X100150Y615000D01*
X100400Y615167D01*
X100733Y615250D01*
X101025Y615167D01*
X101233Y615000D01*
X101400Y614750D01*
X101442Y614459D01*
X101400Y614209D01*
X101233Y613959D01*
X100983Y613750D01*
X100692Y613667D01*
X100358Y613750D01*
X100067Y614000D01*
X99900Y614375D01*
X99858Y614792D01*
X99942Y615334D01*
X100067Y615625D01*
X100275Y615917D01*
X100567Y616125D01*
X100858Y616167D01*
X101150Y616084D01*
X101358Y615875D01*
G01X114700Y615000D02*
Y619000D01*
X107300D01*
G01X106717Y630200D02*
Y632700D01*
X107758D01*
X108092Y632575D01*
X108300Y632408D01*
X108383Y632075D01*
X108300Y631742D01*
X108050Y631533D01*
X107758Y631408D01*
X106717D01*
G01X107758D02*
X108383Y630200D01*
G01X110567D02*
X110650Y630742D01*
X110775Y631200D01*
X110942Y631617D01*
X111150Y632075D01*
X111483Y632700D01*
X109817D01*
G01X113750D02*
X113417Y632617D01*
X113167Y632408D01*
X113000Y632158D01*
X112875Y631825D01*
X112833Y631450D01*
X112875Y631075D01*
X113000Y630742D01*
X113167Y630492D01*
X113417Y630283D01*
X113750Y630200D01*
X114083Y630283D01*
X114333Y630492D01*
X114500Y630742D01*
X114625Y631075D01*
X114667Y631450D01*
X114625Y631825D01*
X114500Y632158D01*
X114333Y632408D01*
X114083Y632617D01*
X113750Y632700D01*
G01X116058Y631242D02*
X116350Y631533D01*
X116600Y631700D01*
X116933Y631783D01*
X117225Y631700D01*
X117433Y631533D01*
X117600Y631283D01*
X117642Y630992D01*
X117600Y630742D01*
X117433Y630492D01*
X117183Y630283D01*
X116892Y630200D01*
X116558Y630283D01*
X116267Y630533D01*
X116100Y630908D01*
X116058Y631325D01*
X116142Y631867D01*
X116267Y632158D01*
X116475Y632450D01*
X116767Y632658D01*
X117058Y632700D01*
X117350Y632617D01*
X117558Y632408D01*
G01X120700Y634300D02*
Y630300D01*
X128100D01*
G01X120500Y647617D02*
X118000D01*
Y648658D01*
X118125Y648992D01*
X118292Y649200D01*
X118625Y649283D01*
X118958Y649200D01*
X119167Y648950D01*
X119292Y648658D01*
Y647617D01*
G01Y648658D02*
X120500Y649283D01*
G01Y651467D02*
X119958Y651550D01*
X119500Y651675D01*
X119083Y651842D01*
X118625Y652050D01*
X118000Y652383D01*
Y650717D01*
G01Y654650D02*
X118083Y654317D01*
X118292Y654067D01*
X118542Y653900D01*
X118875Y653775D01*
X119250Y653733D01*
X119625Y653775D01*
X119958Y653900D01*
X120208Y654067D01*
X120417Y654317D01*
X120500Y654650D01*
X120417Y654983D01*
X120208Y655233D01*
X119958Y655400D01*
X119625Y655525D01*
X119250Y655567D01*
X118875Y655525D01*
X118542Y655400D01*
X118292Y655233D01*
X118083Y654983D01*
X118000Y654650D01*
G01X120125Y656833D02*
X120333Y657083D01*
X120458Y657375D01*
X120500Y657750D01*
X120417Y658125D01*
X120250Y658417D01*
X119958Y658625D01*
X119625Y658667D01*
X119292Y658583D01*
X119083Y658375D01*
X118917Y658083D01*
X118875Y657792D01*
X118917Y657500D01*
X119083Y657125D01*
X118000Y657250D01*
Y658375D01*
G01X130100Y646000D02*
X134100D01*
Y653400D01*
G01X112300Y647617D02*
X109800D01*
Y648658D01*
X109925Y648992D01*
X110092Y649200D01*
X110425Y649283D01*
X110758Y649200D01*
X110967Y648950D01*
X111092Y648658D01*
Y647617D01*
G01Y648658D02*
X112300Y649283D01*
G01Y651467D02*
X111758Y651550D01*
X111300Y651675D01*
X110883Y651842D01*
X110425Y652050D01*
X109800Y652383D01*
Y650717D01*
G01Y654650D02*
X109883Y654317D01*
X110092Y654067D01*
X110342Y653900D01*
X110675Y653775D01*
X111050Y653733D01*
X111425Y653775D01*
X111758Y653900D01*
X112008Y654067D01*
X112217Y654317D01*
X112300Y654650D01*
X112217Y654983D01*
X112008Y655233D01*
X111758Y655400D01*
X111425Y655525D01*
X111050Y655567D01*
X110675Y655525D01*
X110342Y655400D01*
X110092Y655233D01*
X109883Y654983D01*
X109800Y654650D01*
G01X111800Y656833D02*
X112092Y657083D01*
X112258Y657417D01*
X112300Y657792D01*
X112258Y658125D01*
X112050Y658458D01*
X111800Y658667D01*
X111550Y658708D01*
X111258Y658625D01*
X111050Y658333D01*
X110967Y658042D01*
Y657667D01*
G01Y658042D02*
X110842Y658292D01*
X110633Y658500D01*
X110383Y658583D01*
X110133Y658500D01*
X109925Y658292D01*
X109800Y657917D01*
X109842Y657542D01*
X110008Y657167D01*
G01X125900Y653400D02*
X121900D01*
Y646000D01*
G01X106717Y634300D02*
Y636800D01*
X107758D01*
X108092Y636675D01*
X108300Y636508D01*
X108383Y636175D01*
X108300Y635842D01*
X108050Y635633D01*
X107758Y635508D01*
X106717D01*
G01X107758D02*
X108383Y634300D01*
G01X110567D02*
X110650Y634842D01*
X110775Y635300D01*
X110942Y635717D01*
X111150Y636175D01*
X111483Y636800D01*
X109817D01*
G01X113750D02*
X113417Y636717D01*
X113167Y636508D01*
X113000Y636258D01*
X112875Y635925D01*
X112833Y635550D01*
X112875Y635175D01*
X113000Y634842D01*
X113167Y634592D01*
X113417Y634383D01*
X113750Y634300D01*
X114083Y634383D01*
X114333Y634592D01*
X114500Y634842D01*
X114625Y635175D01*
X114667Y635550D01*
X114625Y635925D01*
X114500Y636258D01*
X114333Y636508D01*
X114083Y636717D01*
X113750Y636800D01*
G01X116850D02*
X116517Y636717D01*
X116267Y636508D01*
X116100Y636258D01*
X115975Y635925D01*
X115933Y635550D01*
X115975Y635175D01*
X116100Y634842D01*
X116267Y634592D01*
X116517Y634383D01*
X116850Y634300D01*
X117183Y634383D01*
X117433Y634592D01*
X117600Y634842D01*
X117725Y635175D01*
X117767Y635550D01*
X117725Y635925D01*
X117600Y636258D01*
X117433Y636508D01*
X117183Y636717D01*
X116850Y636800D01*
G01X120700Y638400D02*
Y634400D01*
X128100D01*
G01X134100Y646000D02*
X138100D01*
Y653400D01*
G01X116300Y647617D02*
X113800D01*
Y648658D01*
X113925Y648992D01*
X114092Y649200D01*
X114425Y649283D01*
X114758Y649200D01*
X114967Y648950D01*
X115092Y648658D01*
Y647617D01*
G01Y648658D02*
X116300Y649283D01*
G01X115258Y650758D02*
X114967Y651050D01*
X114800Y651300D01*
X114717Y651633D01*
X114800Y651925D01*
X114967Y652133D01*
X115217Y652300D01*
X115508Y652342D01*
X115758Y652300D01*
X116008Y652133D01*
X116217Y651883D01*
X116300Y651592D01*
X116217Y651258D01*
X115967Y650967D01*
X115592Y650800D01*
X115175Y650758D01*
X114633Y650842D01*
X114342Y650967D01*
X114050Y651175D01*
X113842Y651467D01*
X113800Y651758D01*
X113883Y652050D01*
X114092Y652258D01*
G01X116008Y653942D02*
X116217Y654233D01*
X116300Y654567D01*
X116217Y654900D01*
X115967Y655192D01*
X115592Y655400D01*
X115217Y655483D01*
X114758D01*
X114383Y655400D01*
X114050Y655192D01*
X113883Y654942D01*
X113800Y654650D01*
X113883Y654317D01*
X114050Y654067D01*
X114300Y653900D01*
X114633Y653817D01*
X114925Y653900D01*
X115217Y654108D01*
X115383Y654358D01*
X115425Y654650D01*
X115342Y654983D01*
X115133Y655233D01*
X114758Y655483D01*
G01X116300Y657750D02*
X116258Y658042D01*
X116133Y658375D01*
X115925Y658583D01*
X115633Y658667D01*
X115342Y658583D01*
X115092Y658333D01*
X114967Y657958D01*
Y657542D01*
X114883Y657292D01*
X114675Y657083D01*
X114383Y657000D01*
X114092Y657125D01*
X113883Y657417D01*
X113800Y657750D01*
X113883Y658083D01*
X114092Y658375D01*
X114383Y658500D01*
X114675Y658417D01*
X114883Y658208D01*
X114967Y657958D01*
Y657542D01*
X115092Y657167D01*
X115342Y656917D01*
X115633Y656833D01*
X115925Y656917D01*
X116133Y657125D01*
X116258Y657458D01*
X116300Y657750D01*
G01X129900Y653400D02*
X125900D01*
Y646000D01*
G01X146800Y655500D02*
X142800D01*
Y648100D01*
G01X142700Y655500D02*
X138700D01*
Y648100D01*
G01X81266Y627046D02*
Y634846D01*
G01Y634046D02*
Y640446D01*
G01X101708Y667767D02*
X101583Y667517D01*
X101500Y667225D01*
Y666892D01*
X101625Y666517D01*
X101833Y666225D01*
X102083Y666017D01*
X102500Y665850D01*
X102875Y665808D01*
X103250Y665892D01*
X103500Y666017D01*
X103750Y666267D01*
X103917Y666558D01*
X104000Y666850D01*
Y667142D01*
X103917Y667433D01*
X103792Y667683D01*
X103625Y667892D01*
G01X101917Y669158D02*
X101667Y669408D01*
X101542Y669700D01*
X101500Y670033D01*
X101583Y670450D01*
X101792Y670742D01*
X102042Y670825D01*
X102292Y670783D01*
X102500Y670617D01*
X102917Y669783D01*
X103208Y669408D01*
X103625Y669158D01*
X104000Y669075D01*
Y670825D01*
G01X103500Y672133D02*
X103792Y672383D01*
X103958Y672717D01*
X104000Y673092D01*
X103958Y673425D01*
X103750Y673758D01*
X103500Y673967D01*
X103250Y674008D01*
X102958Y673925D01*
X102750Y673633D01*
X102667Y673342D01*
Y672967D01*
G01Y673342D02*
X102542Y673592D01*
X102333Y673800D01*
X102083Y673883D01*
X101833Y673800D01*
X101625Y673592D01*
X101500Y673217D01*
X101542Y672842D01*
X101708Y672467D01*
G01X101500Y676150D02*
X101583Y675817D01*
X101792Y675567D01*
X102042Y675400D01*
X102375Y675275D01*
X102750Y675233D01*
X103125Y675275D01*
X103458Y675400D01*
X103708Y675567D01*
X103917Y675817D01*
X104000Y676150D01*
X103917Y676483D01*
X103708Y676733D01*
X103458Y676900D01*
X103125Y677025D01*
X102750Y677067D01*
X102375Y677025D01*
X102042Y676900D01*
X101792Y676733D01*
X101583Y676483D01*
X101500Y676150D01*
G01X107767Y674292D02*
X107517Y674417D01*
X107225Y674500D01*
X106892D01*
X106517Y674375D01*
X106225Y674167D01*
X106017Y673917D01*
X105850Y673500D01*
X105808Y673125D01*
X105892Y672750D01*
X106017Y672500D01*
X106267Y672250D01*
X106558Y672083D01*
X106850Y672000D01*
X107142D01*
X107433Y672083D01*
X107683Y672208D01*
X107892Y672375D01*
G01X109158Y674083D02*
X109408Y674333D01*
X109700Y674458D01*
X110033Y674500D01*
X110450Y674417D01*
X110742Y674208D01*
X110825Y673958D01*
X110783Y673708D01*
X110617Y673500D01*
X109783Y673083D01*
X109408Y672792D01*
X109158Y672375D01*
X109075Y672000D01*
X110825D01*
G01X112133Y672500D02*
X112383Y672208D01*
X112717Y672042D01*
X113092Y672000D01*
X113425Y672042D01*
X113758Y672250D01*
X113967Y672500D01*
X114008Y672750D01*
X113925Y673042D01*
X113633Y673250D01*
X113342Y673333D01*
X112967D01*
G01X113342D02*
X113592Y673458D01*
X113800Y673667D01*
X113883Y673917D01*
X113800Y674167D01*
X113592Y674375D01*
X113217Y674500D01*
X112842Y674458D01*
X112467Y674292D01*
G01X116150Y672000D02*
Y674500D01*
X115650Y674000D01*
G01Y672000D02*
X116650D01*
G01X107767Y669792D02*
X107517Y669917D01*
X107225Y670000D01*
X106892D01*
X106517Y669875D01*
X106225Y669667D01*
X106017Y669417D01*
X105850Y669000D01*
X105808Y668625D01*
X105892Y668250D01*
X106017Y668000D01*
X106267Y667750D01*
X106558Y667583D01*
X106850Y667500D01*
X107142D01*
X107433Y667583D01*
X107683Y667708D01*
X107892Y667875D01*
G01X109158Y669583D02*
X109408Y669833D01*
X109700Y669958D01*
X110033Y670000D01*
X110450Y669917D01*
X110742Y669708D01*
X110825Y669458D01*
X110783Y669208D01*
X110617Y669000D01*
X109783Y668583D01*
X109408Y668292D01*
X109158Y667875D01*
X109075Y667500D01*
X110825D01*
G01X112133Y668000D02*
X112383Y667708D01*
X112717Y667542D01*
X113092Y667500D01*
X113425Y667542D01*
X113758Y667750D01*
X113967Y668000D01*
X114008Y668250D01*
X113925Y668542D01*
X113633Y668750D01*
X113342Y668833D01*
X112967D01*
G01X113342D02*
X113592Y668958D01*
X113800Y669167D01*
X113883Y669417D01*
X113800Y669667D01*
X113592Y669875D01*
X113217Y670000D01*
X112842Y669958D01*
X112467Y669792D01*
G01X115358Y669583D02*
X115608Y669833D01*
X115900Y669958D01*
X116233Y670000D01*
X116650Y669917D01*
X116942Y669708D01*
X117025Y669458D01*
X116983Y669208D01*
X116817Y669000D01*
X115983Y668583D01*
X115608Y668292D01*
X115358Y667875D01*
X115275Y667500D01*
X117025D01*
G01X94017Y702667D02*
Y705167D01*
X95058D01*
X95392Y705042D01*
X95600Y704875D01*
X95683Y704542D01*
X95600Y704209D01*
X95350Y704000D01*
X95058Y703875D01*
X94017D01*
G01X95058D02*
X95683Y702667D01*
G01X98450D02*
Y705167D01*
X96908Y703375D01*
X98992D01*
G01X100342Y702959D02*
X100633Y702750D01*
X100967Y702667D01*
X101300Y702750D01*
X101592Y703000D01*
X101800Y703375D01*
X101883Y703750D01*
Y704209D01*
X101800Y704584D01*
X101592Y704917D01*
X101342Y705084D01*
X101050Y705167D01*
X100717Y705084D01*
X100467Y704917D01*
X100300Y704667D01*
X100217Y704334D01*
X100300Y704042D01*
X100508Y703750D01*
X100758Y703584D01*
X101050Y703542D01*
X101383Y703625D01*
X101633Y703834D01*
X101883Y704209D01*
G01X103358Y704750D02*
X103608Y705000D01*
X103900Y705125D01*
X104233Y705167D01*
X104650Y705084D01*
X104942Y704875D01*
X105025Y704625D01*
X104983Y704375D01*
X104817Y704167D01*
X103983Y703750D01*
X103608Y703459D01*
X103358Y703042D01*
X103275Y702667D01*
X105025D01*
G01X115299Y699465D02*
Y703465D01*
X107899D01*
G01X98334Y689517D02*
X95834D01*
Y690558D01*
X95959Y690892D01*
X96126Y691100D01*
X96459Y691183D01*
X96792Y691100D01*
X97001Y690850D01*
X97126Y690558D01*
Y689517D01*
G01Y690558D02*
X98334Y691183D01*
G01Y693950D02*
X95834D01*
X97626Y692408D01*
Y694492D01*
G01X98042Y695842D02*
X98251Y696133D01*
X98334Y696467D01*
X98251Y696800D01*
X98001Y697092D01*
X97626Y697300D01*
X97251Y697383D01*
X96792D01*
X96417Y697300D01*
X96084Y697092D01*
X95917Y696842D01*
X95834Y696550D01*
X95917Y696217D01*
X96084Y695967D01*
X96334Y695800D01*
X96667Y695717D01*
X96959Y695800D01*
X97251Y696008D01*
X97417Y696258D01*
X97459Y696550D01*
X97376Y696883D01*
X97167Y697133D01*
X96792Y697383D01*
G01X97834Y698733D02*
X98126Y698983D01*
X98292Y699317D01*
X98334Y699692D01*
X98292Y700025D01*
X98084Y700358D01*
X97834Y700567D01*
X97584Y700608D01*
X97292Y700525D01*
X97084Y700233D01*
X97001Y699942D01*
Y699567D01*
G01Y699942D02*
X96876Y700192D01*
X96667Y700400D01*
X96417Y700483D01*
X96167Y700400D01*
X95959Y700192D01*
X95834Y699817D01*
X95876Y699442D01*
X96042Y699067D01*
G01X111349Y691647D02*
X115349D01*
Y699047D01*
G01X102334Y689517D02*
X99834D01*
Y690558D01*
X99959Y690892D01*
X100126Y691100D01*
X100459Y691183D01*
X100792Y691100D01*
X101001Y690850D01*
X101126Y690558D01*
Y689517D01*
G01Y690558D02*
X102334Y691183D01*
G01Y693950D02*
X99834D01*
X101626Y692408D01*
Y694492D01*
G01X102042Y695842D02*
X102251Y696133D01*
X102334Y696467D01*
X102251Y696800D01*
X102001Y697092D01*
X101626Y697300D01*
X101251Y697383D01*
X100792D01*
X100417Y697300D01*
X100084Y697092D01*
X99917Y696842D01*
X99834Y696550D01*
X99917Y696217D01*
X100084Y695967D01*
X100334Y695800D01*
X100667Y695717D01*
X100959Y695800D01*
X101251Y696008D01*
X101417Y696258D01*
X101459Y696550D01*
X101376Y696883D01*
X101167Y697133D01*
X100792Y697383D01*
G01X102334Y700150D02*
X99834D01*
X101626Y698608D01*
Y700692D01*
G01X115449Y691647D02*
X119449D01*
Y699047D01*
G01X100834Y707017D02*
X98334D01*
Y708058D01*
X98459Y708392D01*
X98626Y708600D01*
X98959Y708683D01*
X99292Y708600D01*
X99501Y708350D01*
X99626Y708058D01*
Y707017D01*
G01Y708058D02*
X100834Y708683D01*
G01Y711450D02*
X98334D01*
X100126Y709908D01*
Y711992D01*
G01X100542Y713342D02*
X100751Y713633D01*
X100834Y713967D01*
X100751Y714300D01*
X100501Y714592D01*
X100126Y714800D01*
X99751Y714883D01*
X99292D01*
X98917Y714800D01*
X98584Y714592D01*
X98417Y714342D01*
X98334Y714050D01*
X98417Y713717D01*
X98584Y713467D01*
X98834Y713300D01*
X99167Y713217D01*
X99459Y713300D01*
X99751Y713508D01*
X99917Y713758D01*
X99959Y714050D01*
X99876Y714383D01*
X99667Y714633D01*
X99292Y714883D01*
G01X100459Y716233D02*
X100667Y716483D01*
X100792Y716775D01*
X100834Y717150D01*
X100751Y717525D01*
X100584Y717817D01*
X100292Y718025D01*
X99959Y718067D01*
X99626Y717983D01*
X99417Y717775D01*
X99251Y717483D01*
X99209Y717192D01*
X99251Y716900D01*
X99417Y716525D01*
X98334Y716650D01*
Y717775D01*
G01X113200Y715300D02*
X109200D01*
Y707900D01*
G01X138017Y676667D02*
Y679167D01*
X139058D01*
X139392Y679042D01*
X139600Y678875D01*
X139683Y678542D01*
X139600Y678209D01*
X139350Y678000D01*
X139058Y677875D01*
X138017D01*
G01X139058D02*
X139683Y676667D01*
G01X142450D02*
Y679167D01*
X140908Y677375D01*
X142992D01*
G01X144342Y676959D02*
X144633Y676750D01*
X144967Y676667D01*
X145300Y676750D01*
X145592Y677000D01*
X145800Y677375D01*
X145883Y677750D01*
Y678209D01*
X145800Y678584D01*
X145592Y678917D01*
X145342Y679084D01*
X145050Y679167D01*
X144717Y679084D01*
X144467Y678917D01*
X144300Y678667D01*
X144217Y678334D01*
X144300Y678042D01*
X144508Y677750D01*
X144758Y677584D01*
X145050Y677542D01*
X145383Y677625D01*
X145633Y677834D01*
X145883Y678209D01*
G01X147358Y677709D02*
X147650Y678000D01*
X147900Y678167D01*
X148233Y678250D01*
X148525Y678167D01*
X148733Y678000D01*
X148900Y677750D01*
X148942Y677459D01*
X148900Y677209D01*
X148733Y676959D01*
X148483Y676750D01*
X148192Y676667D01*
X147858Y676750D01*
X147567Y677000D01*
X147400Y677375D01*
X147358Y677792D01*
X147442Y678334D01*
X147567Y678625D01*
X147775Y678917D01*
X148067Y679125D01*
X148358Y679167D01*
X148650Y679084D01*
X148858Y678875D01*
G01X143149Y685715D02*
Y681715D01*
X150549D01*
G01X109334Y687017D02*
X106834D01*
Y688058D01*
X106959Y688392D01*
X107126Y688600D01*
X107459Y688683D01*
X107792Y688600D01*
X108001Y688350D01*
X108126Y688058D01*
Y687017D01*
G01Y688058D02*
X109334Y688683D01*
G01Y691450D02*
X106834D01*
X108626Y689908D01*
Y691992D01*
G01X109042Y693342D02*
X109251Y693633D01*
X109334Y693967D01*
X109251Y694300D01*
X109001Y694592D01*
X108626Y694800D01*
X108251Y694883D01*
X107792D01*
X107417Y694800D01*
X107084Y694592D01*
X106917Y694342D01*
X106834Y694050D01*
X106917Y693717D01*
X107084Y693467D01*
X107334Y693300D01*
X107667Y693217D01*
X107959Y693300D01*
X108251Y693508D01*
X108417Y693758D01*
X108459Y694050D01*
X108376Y694383D01*
X108167Y694633D01*
X107792Y694883D01*
G01X109334Y697067D02*
X108792Y697150D01*
X108334Y697275D01*
X107917Y697442D01*
X107459Y697650D01*
X106834Y697983D01*
Y696317D01*
G01X119549Y689347D02*
X123549D01*
Y696747D01*
G01X124017Y684267D02*
Y686767D01*
X125058D01*
X125392Y686642D01*
X125600Y686475D01*
X125683Y686142D01*
X125600Y685809D01*
X125350Y685600D01*
X125058Y685475D01*
X124017D01*
G01X125058D02*
X125683Y684267D01*
G01X128450D02*
Y686767D01*
X126908Y684975D01*
X128992D01*
G01X130342Y684559D02*
X130633Y684350D01*
X130967Y684267D01*
X131300Y684350D01*
X131592Y684600D01*
X131800Y684975D01*
X131883Y685350D01*
Y685809D01*
X131800Y686184D01*
X131592Y686517D01*
X131342Y686684D01*
X131050Y686767D01*
X130717Y686684D01*
X130467Y686517D01*
X130300Y686267D01*
X130217Y685934D01*
X130300Y685642D01*
X130508Y685350D01*
X130758Y685184D01*
X131050Y685142D01*
X131383Y685225D01*
X131633Y685434D01*
X131883Y685809D01*
G01X133442Y684559D02*
X133733Y684350D01*
X134067Y684267D01*
X134400Y684350D01*
X134692Y684600D01*
X134900Y684975D01*
X134983Y685350D01*
Y685809D01*
X134900Y686184D01*
X134692Y686517D01*
X134442Y686684D01*
X134150Y686767D01*
X133817Y686684D01*
X133567Y686517D01*
X133400Y686267D01*
X133317Y685934D01*
X133400Y685642D01*
X133608Y685350D01*
X133858Y685184D01*
X134150Y685142D01*
X134483Y685225D01*
X134733Y685434D01*
X134983Y685809D01*
G01X143049Y685715D02*
Y689715D01*
X135649D01*
G01X82600Y690900D02*
X78600D01*
Y683500D01*
G01X138934Y663817D02*
X136434D01*
Y664858D01*
X136559Y665192D01*
X136726Y665400D01*
X137059Y665483D01*
X137392Y665400D01*
X137601Y665150D01*
X137726Y664858D01*
Y663817D01*
G01Y664858D02*
X138934Y665483D01*
G01X138434Y666833D02*
X138726Y667083D01*
X138892Y667417D01*
X138934Y667792D01*
X138892Y668125D01*
X138684Y668458D01*
X138434Y668667D01*
X138184Y668708D01*
X137892Y668625D01*
X137684Y668333D01*
X137601Y668042D01*
Y667667D01*
G01Y668042D02*
X137476Y668292D01*
X137267Y668500D01*
X137017Y668583D01*
X136767Y668500D01*
X136559Y668292D01*
X136434Y667917D01*
X136476Y667542D01*
X136642Y667167D01*
G01X138434Y669933D02*
X138726Y670183D01*
X138892Y670517D01*
X138934Y670892D01*
X138892Y671225D01*
X138684Y671558D01*
X138434Y671767D01*
X138184Y671808D01*
X137892Y671725D01*
X137684Y671433D01*
X137601Y671142D01*
Y670767D01*
G01Y671142D02*
X137476Y671392D01*
X137267Y671600D01*
X137017Y671683D01*
X136767Y671600D01*
X136559Y671392D01*
X136434Y671017D01*
X136476Y670642D01*
X136642Y670267D01*
G01X136434Y673950D02*
X136517Y673617D01*
X136726Y673367D01*
X136976Y673200D01*
X137309Y673075D01*
X137684Y673033D01*
X138059Y673075D01*
X138392Y673200D01*
X138642Y673367D01*
X138851Y673617D01*
X138934Y673950D01*
X138851Y674283D01*
X138642Y674533D01*
X138392Y674700D01*
X138059Y674825D01*
X137684Y674867D01*
X137309Y674825D01*
X136976Y674700D01*
X136726Y674533D01*
X136517Y674283D01*
X136434Y673950D01*
G01X125317Y677067D02*
Y679567D01*
X126358D01*
X126692Y679442D01*
X126900Y679275D01*
X126983Y678942D01*
X126900Y678609D01*
X126650Y678400D01*
X126358Y678275D01*
X125317D01*
G01X126358D02*
X126983Y677067D01*
G01X128333Y677567D02*
X128583Y677275D01*
X128917Y677109D01*
X129292Y677067D01*
X129625Y677109D01*
X129958Y677317D01*
X130167Y677567D01*
X130208Y677817D01*
X130125Y678109D01*
X129833Y678317D01*
X129542Y678400D01*
X129167D01*
G01X129542D02*
X129792Y678525D01*
X130000Y678734D01*
X130083Y678984D01*
X130000Y679234D01*
X129792Y679442D01*
X129417Y679567D01*
X129042Y679525D01*
X128667Y679359D01*
G01X132350Y679567D02*
X132017Y679484D01*
X131767Y679275D01*
X131600Y679025D01*
X131475Y678692D01*
X131433Y678317D01*
X131475Y677942D01*
X131600Y677609D01*
X131767Y677359D01*
X132017Y677150D01*
X132350Y677067D01*
X132683Y677150D01*
X132933Y677359D01*
X133100Y677609D01*
X133225Y677942D01*
X133267Y678317D01*
X133225Y678692D01*
X133100Y679025D01*
X132933Y679275D01*
X132683Y679484D01*
X132350Y679567D01*
G01X134658Y679150D02*
X134908Y679400D01*
X135200Y679525D01*
X135533Y679567D01*
X135950Y679484D01*
X136242Y679275D01*
X136325Y679025D01*
X136283Y678775D01*
X136117Y678567D01*
X135283Y678150D01*
X134908Y677859D01*
X134658Y677442D01*
X134575Y677067D01*
X136325D01*
G01X142800Y663217D02*
X140300D01*
Y664258D01*
X140425Y664592D01*
X140592Y664800D01*
X140925Y664883D01*
X141258Y664800D01*
X141467Y664550D01*
X141592Y664258D01*
Y663217D01*
G01Y664258D02*
X142800Y664883D01*
G01X142300Y666233D02*
X142592Y666483D01*
X142758Y666817D01*
X142800Y667192D01*
X142758Y667525D01*
X142550Y667858D01*
X142300Y668067D01*
X142050Y668108D01*
X141758Y668025D01*
X141550Y667733D01*
X141467Y667442D01*
Y667067D01*
G01Y667442D02*
X141342Y667692D01*
X141133Y667900D01*
X140883Y667983D01*
X140633Y667900D01*
X140425Y667692D01*
X140300Y667317D01*
X140342Y666942D01*
X140508Y666567D01*
G01X140300Y670250D02*
X140383Y669917D01*
X140592Y669667D01*
X140842Y669500D01*
X141175Y669375D01*
X141550Y669333D01*
X141925Y669375D01*
X142258Y669500D01*
X142508Y669667D01*
X142717Y669917D01*
X142800Y670250D01*
X142717Y670583D01*
X142508Y670833D01*
X142258Y671000D01*
X141925Y671125D01*
X141550Y671167D01*
X141175Y671125D01*
X140842Y671000D01*
X140592Y670833D01*
X140383Y670583D01*
X140300Y670250D01*
G01X142800Y673350D02*
X140300D01*
X140800Y672850D01*
G01X142800D02*
Y673850D01*
G01X127600Y663917D02*
X125100D01*
Y664958D01*
X125225Y665292D01*
X125392Y665500D01*
X125725Y665583D01*
X126058Y665500D01*
X126267Y665250D01*
X126392Y664958D01*
Y663917D01*
G01Y664958D02*
X127600Y665583D01*
G01X126558Y667058D02*
X126267Y667350D01*
X126100Y667600D01*
X126017Y667933D01*
X126100Y668225D01*
X126267Y668433D01*
X126517Y668600D01*
X126808Y668642D01*
X127058Y668600D01*
X127308Y668433D01*
X127517Y668183D01*
X127600Y667892D01*
X127517Y667558D01*
X127267Y667267D01*
X126892Y667100D01*
X126475Y667058D01*
X125933Y667142D01*
X125642Y667267D01*
X125350Y667475D01*
X125142Y667767D01*
X125100Y668058D01*
X125183Y668350D01*
X125392Y668558D01*
G01X127308Y670242D02*
X127517Y670533D01*
X127600Y670867D01*
X127517Y671200D01*
X127267Y671492D01*
X126892Y671700D01*
X126517Y671783D01*
X126058D01*
X125683Y671700D01*
X125350Y671492D01*
X125183Y671242D01*
X125100Y670950D01*
X125183Y670617D01*
X125350Y670367D01*
X125600Y670200D01*
X125933Y670117D01*
X126225Y670200D01*
X126517Y670408D01*
X126683Y670658D01*
X126725Y670950D01*
X126642Y671283D01*
X126433Y671533D01*
X126058Y671783D01*
G01X127308Y673342D02*
X127517Y673633D01*
X127600Y673967D01*
X127517Y674300D01*
X127267Y674592D01*
X126892Y674800D01*
X126517Y674883D01*
X126058D01*
X125683Y674800D01*
X125350Y674592D01*
X125183Y674342D01*
X125100Y674050D01*
X125183Y673717D01*
X125350Y673467D01*
X125600Y673300D01*
X125933Y673217D01*
X126225Y673300D01*
X126517Y673508D01*
X126683Y673758D01*
X126725Y674050D01*
X126642Y674383D01*
X126433Y674633D01*
X126058Y674883D01*
G01X135000Y663717D02*
X132500D01*
Y664758D01*
X132625Y665092D01*
X132792Y665300D01*
X133125Y665383D01*
X133458Y665300D01*
X133667Y665050D01*
X133792Y664758D01*
Y663717D01*
G01Y664758D02*
X135000Y665383D01*
G01Y667567D02*
X134458Y667650D01*
X134000Y667775D01*
X133583Y667942D01*
X133125Y668150D01*
X132500Y668483D01*
Y666817D01*
G01X135000Y671250D02*
X132500D01*
X134292Y669708D01*
Y671792D01*
G01X132500Y673850D02*
X132583Y673517D01*
X132792Y673267D01*
X133042Y673100D01*
X133375Y672975D01*
X133750Y672933D01*
X134125Y672975D01*
X134458Y673100D01*
X134708Y673267D01*
X134917Y673517D01*
X135000Y673850D01*
X134917Y674183D01*
X134708Y674433D01*
X134458Y674600D01*
X134125Y674725D01*
X133750Y674767D01*
X133375Y674725D01*
X133042Y674600D01*
X132792Y674433D01*
X132583Y674183D01*
X132500Y673850D01*
G01X131300Y663717D02*
X128800D01*
Y664758D01*
X128925Y665092D01*
X129092Y665300D01*
X129425Y665383D01*
X129758Y665300D01*
X129967Y665050D01*
X130092Y664758D01*
Y663717D01*
G01Y664758D02*
X131300Y665383D01*
G01Y667567D02*
X130758Y667650D01*
X130300Y667775D01*
X129883Y667942D01*
X129425Y668150D01*
X128800Y668483D01*
Y666817D01*
G01Y670750D02*
X128883Y670417D01*
X129092Y670167D01*
X129342Y670000D01*
X129675Y669875D01*
X130050Y669833D01*
X130425Y669875D01*
X130758Y670000D01*
X131008Y670167D01*
X131217Y670417D01*
X131300Y670750D01*
X131217Y671083D01*
X131008Y671333D01*
X130758Y671500D01*
X130425Y671625D01*
X130050Y671667D01*
X129675Y671625D01*
X129342Y671500D01*
X129092Y671333D01*
X128883Y671083D01*
X128800Y670750D01*
G01X131300Y673767D02*
X130758Y673850D01*
X130300Y673975D01*
X129883Y674142D01*
X129425Y674350D01*
X128800Y674683D01*
Y673017D01*
G01X102542Y708767D02*
X102417Y708517D01*
X102334Y708225D01*
Y707892D01*
X102459Y707517D01*
X102667Y707225D01*
X102917Y707017D01*
X103334Y706850D01*
X103709Y706808D01*
X104084Y706892D01*
X104334Y707017D01*
X104584Y707267D01*
X104751Y707558D01*
X104834Y707850D01*
Y708142D01*
X104751Y708433D01*
X104626Y708683D01*
X104459Y708892D01*
G01X104834Y710950D02*
X102334D01*
X102834Y710450D01*
G01X104834D02*
Y711450D01*
G01Y714050D02*
X104792Y714342D01*
X104667Y714675D01*
X104459Y714883D01*
X104167Y714967D01*
X103876Y714883D01*
X103626Y714633D01*
X103501Y714258D01*
Y713842D01*
X103417Y713592D01*
X103209Y713383D01*
X102917Y713300D01*
X102626Y713425D01*
X102417Y713717D01*
X102334Y714050D01*
X102417Y714383D01*
X102626Y714675D01*
X102917Y714800D01*
X103209Y714717D01*
X103417Y714508D01*
X103501Y714258D01*
Y713842D01*
X103626Y713467D01*
X103876Y713217D01*
X104167Y713133D01*
X104459Y713217D01*
X104667Y713425D01*
X104792Y713758D01*
X104834Y714050D01*
G01X102751Y716358D02*
X102501Y716608D01*
X102376Y716900D01*
X102334Y717233D01*
X102417Y717650D01*
X102626Y717942D01*
X102876Y718025D01*
X103126Y717983D01*
X103334Y717817D01*
X103751Y716983D01*
X104042Y716608D01*
X104459Y716358D01*
X104834Y716275D01*
Y718025D01*
G01X88117Y716500D02*
Y714000D01*
X89783D01*
G01X92050D02*
X92342Y714042D01*
X92675Y714167D01*
X92883Y714375D01*
X92967Y714667D01*
X92883Y714958D01*
X92633Y715208D01*
X92258Y715333D01*
X91842D01*
X91592Y715417D01*
X91383Y715625D01*
X91300Y715917D01*
X91425Y716208D01*
X91717Y716417D01*
X92050Y716500D01*
X92383Y716417D01*
X92675Y716208D01*
X92800Y715917D01*
X92717Y715625D01*
X92508Y715417D01*
X92258Y715333D01*
X91842D01*
X91467Y715208D01*
X91217Y714958D01*
X91133Y714667D01*
X91217Y714375D01*
X91425Y714167D01*
X91758Y714042D01*
X92050Y714000D01*
G01X98400Y719100D02*
Y726300D01*
G01X85000Y719100D02*
X98400D01*
G01X85000Y726300D02*
Y719100D01*
G01X140184Y694800D02*
Y695633D01*
X140934D01*
X141184Y695383D01*
X141351Y695092D01*
X141434Y694675D01*
X141351Y694258D01*
X141184Y693967D01*
X140934Y693717D01*
X140642Y693550D01*
X140309Y693467D01*
X140017D01*
X139767Y693550D01*
X139476Y693717D01*
X139226Y693967D01*
X139059Y694217D01*
X138934Y694550D01*
Y694842D01*
X139017Y695175D01*
X139184Y695425D01*
G01X140934Y696733D02*
X141226Y696983D01*
X141392Y697317D01*
X141434Y697692D01*
X141392Y698025D01*
X141184Y698358D01*
X140934Y698567D01*
X140684Y698608D01*
X140392Y698525D01*
X140184Y698233D01*
X140101Y697942D01*
Y697567D01*
G01Y697942D02*
X139976Y698192D01*
X139767Y698400D01*
X139517Y698483D01*
X139267Y698400D01*
X139059Y698192D01*
X138934Y697817D01*
X138976Y697442D01*
X139142Y697067D01*
G01X111467Y720100D02*
Y722600D01*
X112467D01*
X112800Y722475D01*
X113050Y722183D01*
X113133Y721850D01*
X113050Y721517D01*
X112842Y721267D01*
X112467Y721142D01*
X111467D01*
G01X114483Y722600D02*
Y720808D01*
X114650Y720433D01*
X114983Y720183D01*
X115400Y720100D01*
X115817Y720183D01*
X116150Y720433D01*
X116317Y720808D01*
Y722600D01*
G01X117708Y722183D02*
X117958Y722433D01*
X118250Y722558D01*
X118583Y722600D01*
X119000Y722517D01*
X119292Y722308D01*
X119375Y722058D01*
X119333Y721808D01*
X119167Y721600D01*
X118333Y721183D01*
X117958Y720892D01*
X117708Y720475D01*
X117625Y720100D01*
X119375D01*
G01X121169Y706045D02*
Y701045D01*
X126169D01*
G01Y728645D02*
X121169D01*
Y723645D01*
G01X122176Y708939D02*
X119176D01*
G01X122176Y718782D02*
X120176D01*
G01X83834Y706517D02*
X81334D01*
Y707558D01*
X81459Y707892D01*
X81626Y708100D01*
X81959Y708183D01*
X82292Y708100D01*
X82501Y707850D01*
X82626Y707558D01*
Y706517D01*
G01Y707558D02*
X83834Y708183D01*
G01Y710950D02*
X81334D01*
X83126Y709408D01*
Y711492D01*
G01X83542Y712842D02*
X83751Y713133D01*
X83834Y713467D01*
X83751Y713800D01*
X83501Y714092D01*
X83126Y714300D01*
X82751Y714383D01*
X82292D01*
X81917Y714300D01*
X81584Y714092D01*
X81417Y713842D01*
X81334Y713550D01*
X81417Y713217D01*
X81584Y712967D01*
X81834Y712800D01*
X82167Y712717D01*
X82459Y712800D01*
X82751Y713008D01*
X82917Y713258D01*
X82959Y713550D01*
X82876Y713883D01*
X82667Y714133D01*
X82292Y714383D01*
G01X81334Y716650D02*
X81417Y716317D01*
X81626Y716067D01*
X81876Y715900D01*
X82209Y715775D01*
X82584Y715733D01*
X82959Y715775D01*
X83292Y715900D01*
X83542Y716067D01*
X83751Y716317D01*
X83834Y716650D01*
X83751Y716983D01*
X83542Y717233D01*
X83292Y717400D01*
X82959Y717525D01*
X82584Y717567D01*
X82209Y717525D01*
X81876Y717400D01*
X81626Y717233D01*
X81417Y716983D01*
X81334Y716650D01*
G01X78157Y670968D02*
X80157D01*
G01X141767Y746459D02*
X141517Y746584D01*
X141225Y746667D01*
X140892D01*
X140517Y746542D01*
X140225Y746334D01*
X140017Y746084D01*
X139850Y745667D01*
X139808Y745292D01*
X139892Y744917D01*
X140017Y744667D01*
X140267Y744417D01*
X140558Y744250D01*
X140850Y744167D01*
X141142D01*
X141433Y744250D01*
X141683Y744375D01*
X141892Y744542D01*
G01X143950Y744167D02*
Y746667D01*
X143450Y746167D01*
G01Y744167D02*
X144450D01*
G01X147050D02*
X147342Y744209D01*
X147675Y744334D01*
X147883Y744542D01*
X147967Y744834D01*
X147883Y745125D01*
X147633Y745375D01*
X147258Y745500D01*
X146842D01*
X146592Y745584D01*
X146383Y745792D01*
X146300Y746084D01*
X146425Y746375D01*
X146717Y746584D01*
X147050Y746667D01*
X147383Y746584D01*
X147675Y746375D01*
X147800Y746084D01*
X147717Y745792D01*
X147508Y745584D01*
X147258Y745500D01*
X146842D01*
X146467Y745375D01*
X146217Y745125D01*
X146133Y744834D01*
X146217Y744542D01*
X146425Y744334D01*
X146758Y744209D01*
X147050Y744167D01*
G01X150150Y746667D02*
X149817Y746584D01*
X149567Y746375D01*
X149400Y746125D01*
X149275Y745792D01*
X149233Y745417D01*
X149275Y745042D01*
X149400Y744709D01*
X149567Y744459D01*
X149817Y744250D01*
X150150Y744167D01*
X150483Y744250D01*
X150733Y744459D01*
X150900Y744709D01*
X151025Y745042D01*
X151067Y745417D01*
X151025Y745792D01*
X150900Y746125D01*
X150733Y746375D01*
X150483Y746584D01*
X150150Y746667D01*
G01X98400Y726300D02*
X85000D01*
G01X136151Y742915D02*
Y737715D01*
G01X129151Y742915D02*
Y735115D01*
G01X136151Y742915D02*
X129151D01*
G01X136151Y729515D02*
Y738215D01*
G01X129151Y729515D02*
X136151D01*
G01X129151Y735915D02*
Y729515D01*
G01X189817Y449392D02*
X189567Y449517D01*
X189275Y449600D01*
X188942D01*
X188567Y449475D01*
X188275Y449267D01*
X188067Y449017D01*
X187900Y448600D01*
X187858Y448225D01*
X187942Y447850D01*
X188067Y447600D01*
X188317Y447350D01*
X188608Y447183D01*
X188900Y447100D01*
X189192D01*
X189483Y447183D01*
X189733Y447308D01*
X189942Y447475D01*
G01X191083Y447600D02*
X191333Y447308D01*
X191667Y447142D01*
X192042Y447100D01*
X192375Y447142D01*
X192708Y447350D01*
X192917Y447600D01*
X192958Y447850D01*
X192875Y448142D01*
X192583Y448350D01*
X192292Y448433D01*
X191917D01*
G01X192292D02*
X192542Y448558D01*
X192750Y448767D01*
X192833Y449017D01*
X192750Y449267D01*
X192542Y449475D01*
X192167Y449600D01*
X191792Y449558D01*
X191417Y449392D01*
G01X194308Y448142D02*
X194600Y448433D01*
X194850Y448600D01*
X195183Y448683D01*
X195475Y448600D01*
X195683Y448433D01*
X195850Y448183D01*
X195892Y447892D01*
X195850Y447642D01*
X195683Y447392D01*
X195433Y447183D01*
X195142Y447100D01*
X194808Y447183D01*
X194517Y447433D01*
X194350Y447808D01*
X194308Y448225D01*
X194392Y448767D01*
X194517Y449058D01*
X194725Y449350D01*
X195017Y449558D01*
X195308Y449600D01*
X195600Y449517D01*
X195808Y449308D01*
G01X188017Y452500D02*
Y455000D01*
X189058D01*
X189392Y454875D01*
X189600Y454708D01*
X189683Y454375D01*
X189600Y454042D01*
X189350Y453833D01*
X189058Y453708D01*
X188017D01*
G01X189058D02*
X189683Y452500D01*
G01X191950D02*
X192242Y452542D01*
X192575Y452667D01*
X192783Y452875D01*
X192867Y453167D01*
X192783Y453458D01*
X192533Y453708D01*
X192158Y453833D01*
X191742D01*
X191492Y453917D01*
X191283Y454125D01*
X191200Y454417D01*
X191325Y454708D01*
X191617Y454917D01*
X191950Y455000D01*
X192283Y454917D01*
X192575Y454708D01*
X192700Y454417D01*
X192617Y454125D01*
X192408Y453917D01*
X192158Y453833D01*
X191742D01*
X191367Y453708D01*
X191117Y453458D01*
X191033Y453167D01*
X191117Y452875D01*
X191325Y452667D01*
X191658Y452542D01*
X191950Y452500D01*
G01X194133Y453000D02*
X194383Y452708D01*
X194717Y452542D01*
X195092Y452500D01*
X195425Y452542D01*
X195758Y452750D01*
X195967Y453000D01*
X196008Y453250D01*
X195925Y453542D01*
X195633Y453750D01*
X195342Y453833D01*
X194967D01*
G01X195342D02*
X195592Y453958D01*
X195800Y454167D01*
X195883Y454417D01*
X195800Y454667D01*
X195592Y454875D01*
X195217Y455000D01*
X194842Y454958D01*
X194467Y454792D01*
G01X188067Y443400D02*
Y445900D01*
X189108D01*
X189442Y445775D01*
X189650Y445608D01*
X189733Y445275D01*
X189650Y444942D01*
X189400Y444733D01*
X189108Y444608D01*
X188067D01*
G01X189108D02*
X189733Y443400D01*
G01X192000D02*
X192292Y443442D01*
X192625Y443567D01*
X192833Y443775D01*
X192917Y444067D01*
X192833Y444358D01*
X192583Y444608D01*
X192208Y444733D01*
X191792D01*
X191542Y444817D01*
X191333Y445025D01*
X191250Y445317D01*
X191375Y445608D01*
X191667Y445817D01*
X192000Y445900D01*
X192333Y445817D01*
X192625Y445608D01*
X192750Y445317D01*
X192667Y445025D01*
X192458Y444817D01*
X192208Y444733D01*
X191792D01*
X191417Y444608D01*
X191167Y444358D01*
X191083Y444067D01*
X191167Y443775D01*
X191375Y443567D01*
X191708Y443442D01*
X192000Y443400D01*
G01X194308Y444442D02*
X194600Y444733D01*
X194850Y444900D01*
X195183Y444983D01*
X195475Y444900D01*
X195683Y444733D01*
X195850Y444483D01*
X195892Y444192D01*
X195850Y443942D01*
X195683Y443692D01*
X195433Y443483D01*
X195142Y443400D01*
X194808Y443483D01*
X194517Y443733D01*
X194350Y444108D01*
X194308Y444525D01*
X194392Y445067D01*
X194517Y445358D01*
X194725Y445650D01*
X195017Y445858D01*
X195308Y445900D01*
X195600Y445817D01*
X195808Y445608D01*
G01X184944Y457767D02*
Y461767D01*
X177544D01*
G01X188017Y456200D02*
Y458700D01*
X189058D01*
X189392Y458575D01*
X189600Y458408D01*
X189683Y458075D01*
X189600Y457742D01*
X189350Y457533D01*
X189058Y457408D01*
X188017D01*
G01X189058D02*
X189683Y456200D01*
G01X191867D02*
X191950Y456742D01*
X192075Y457200D01*
X192242Y457617D01*
X192450Y458075D01*
X192783Y458700D01*
X191117D01*
G01X194258Y457242D02*
X194550Y457533D01*
X194800Y457700D01*
X195133Y457783D01*
X195425Y457700D01*
X195633Y457533D01*
X195800Y457283D01*
X195842Y456992D01*
X195800Y456742D01*
X195633Y456492D01*
X195383Y456283D01*
X195092Y456200D01*
X194758Y456283D01*
X194467Y456533D01*
X194300Y456908D01*
X194258Y457325D01*
X194342Y457867D01*
X194467Y458158D01*
X194675Y458450D01*
X194967Y458658D01*
X195258Y458700D01*
X195550Y458617D01*
X195758Y458408D01*
G01X197233Y456575D02*
X197483Y456367D01*
X197775Y456242D01*
X198150Y456200D01*
X198525Y456283D01*
X198817Y456450D01*
X199025Y456742D01*
X199067Y457075D01*
X198983Y457408D01*
X198775Y457617D01*
X198483Y457783D01*
X198192Y457825D01*
X197900Y457783D01*
X197525Y457617D01*
X197650Y458700D01*
X198775D01*
G01X144760Y457769D02*
X146730Y455799D01*
G01X157460Y496499D02*
Y455799D01*
G01X151833Y527217D02*
X151033Y527567D01*
X150100Y527800D01*
X149033D01*
X147833Y527450D01*
X146900Y526867D01*
X146233Y526167D01*
X145700Y525000D01*
X145567Y523950D01*
X145833Y522900D01*
X146233Y522200D01*
X147033Y521500D01*
X147967Y521033D01*
X148900Y520800D01*
X149833D01*
X150767Y521033D01*
X151567Y521383D01*
X152233Y521850D01*
G01X200000Y511000D02*
X196500D01*
G01X193900D02*
X153500D01*
G01X202017Y474500D02*
Y477000D01*
X203058D01*
X203392Y476875D01*
X203600Y476708D01*
X203683Y476375D01*
X203600Y476042D01*
X203350Y475833D01*
X203058Y475708D01*
X202017D01*
G01X203058D02*
X203683Y474500D01*
G01X205158Y476583D02*
X205408Y476833D01*
X205700Y476958D01*
X206033Y477000D01*
X206450Y476917D01*
X206742Y476708D01*
X206825Y476458D01*
X206783Y476208D01*
X206617Y476000D01*
X205783Y475583D01*
X205408Y475292D01*
X205158Y474875D01*
X205075Y474500D01*
X206825D01*
G01X208258Y475542D02*
X208550Y475833D01*
X208800Y476000D01*
X209133Y476083D01*
X209425Y476000D01*
X209633Y475833D01*
X209800Y475583D01*
X209842Y475292D01*
X209800Y475042D01*
X209633Y474792D01*
X209383Y474583D01*
X209092Y474500D01*
X208758Y474583D01*
X208467Y474833D01*
X208300Y475208D01*
X208258Y475625D01*
X208342Y476167D01*
X208467Y476458D01*
X208675Y476750D01*
X208967Y476958D01*
X209258Y477000D01*
X209550Y476917D01*
X209758Y476708D01*
G01X211442Y474792D02*
X211733Y474583D01*
X212067Y474500D01*
X212400Y474583D01*
X212692Y474833D01*
X212900Y475208D01*
X212983Y475583D01*
Y476042D01*
X212900Y476417D01*
X212692Y476750D01*
X212442Y476917D01*
X212150Y477000D01*
X211817Y476917D01*
X211567Y476750D01*
X211400Y476500D01*
X211317Y476167D01*
X211400Y475875D01*
X211608Y475583D01*
X211858Y475417D01*
X212150Y475375D01*
X212483Y475458D01*
X212733Y475667D01*
X212983Y476042D01*
G01X206700Y497300D02*
Y493300D01*
X214100D01*
G01X197000Y486717D02*
X194500D01*
Y487758D01*
X194625Y488092D01*
X194792Y488300D01*
X195125Y488383D01*
X195458Y488300D01*
X195667Y488050D01*
X195792Y487758D01*
Y486717D01*
G01Y487758D02*
X197000Y488383D01*
G01X194917Y489858D02*
X194667Y490108D01*
X194542Y490400D01*
X194500Y490733D01*
X194583Y491150D01*
X194792Y491442D01*
X195042Y491525D01*
X195292Y491483D01*
X195500Y491317D01*
X195917Y490483D01*
X196208Y490108D01*
X196625Y489858D01*
X197000Y489775D01*
Y491525D01*
G01Y493750D02*
X196958Y494042D01*
X196833Y494375D01*
X196625Y494583D01*
X196333Y494667D01*
X196042Y494583D01*
X195792Y494333D01*
X195667Y493958D01*
Y493542D01*
X195583Y493292D01*
X195375Y493083D01*
X195083Y493000D01*
X194792Y493125D01*
X194583Y493417D01*
X194500Y493750D01*
X194583Y494083D01*
X194792Y494375D01*
X195083Y494500D01*
X195375Y494417D01*
X195583Y494208D01*
X195667Y493958D01*
Y493542D01*
X195792Y493167D01*
X196042Y492917D01*
X196333Y492833D01*
X196625Y492917D01*
X196833Y493125D01*
X196958Y493458D01*
X197000Y493750D01*
G01Y496767D02*
X196458Y496850D01*
X196000Y496975D01*
X195583Y497142D01*
X195125Y497350D01*
X194500Y497683D01*
Y496017D01*
G01X191000Y501000D02*
X195000D01*
Y508400D01*
G01X144112Y511098D02*
X148112D01*
Y518498D01*
G01X184944Y467867D02*
Y471867D01*
X177544D01*
G01X198567Y489600D02*
Y492100D01*
X199608D01*
X199942Y491975D01*
X200150Y491808D01*
X200233Y491475D01*
X200150Y491142D01*
X199900Y490933D01*
X199608Y490808D01*
X198567D01*
G01X199608D02*
X200233Y489600D01*
G01X202500D02*
X202792Y489642D01*
X203125Y489767D01*
X203333Y489975D01*
X203417Y490267D01*
X203333Y490558D01*
X203083Y490808D01*
X202708Y490933D01*
X202292D01*
X202042Y491017D01*
X201833Y491225D01*
X201750Y491517D01*
X201875Y491808D01*
X202167Y492017D01*
X202500Y492100D01*
X202833Y492017D01*
X203125Y491808D01*
X203250Y491517D01*
X203167Y491225D01*
X202958Y491017D01*
X202708Y490933D01*
X202292D01*
X201917Y490808D01*
X201667Y490558D01*
X201583Y490267D01*
X201667Y489975D01*
X201875Y489767D01*
X202208Y489642D01*
X202500Y489600D01*
G01X205517D02*
X205600Y490142D01*
X205725Y490600D01*
X205892Y491017D01*
X206100Y491475D01*
X206433Y492100D01*
X204767D01*
G01X195400Y504800D02*
Y500800D01*
X202800D01*
G01X172150Y501425D02*
Y503925D01*
X173191D01*
X173525Y503800D01*
X173733Y503633D01*
X173816Y503300D01*
X173733Y502967D01*
X173483Y502758D01*
X173191Y502633D01*
X172150D01*
G01X173191D02*
X173816Y501425D01*
G01X176083D02*
X176375Y501467D01*
X176708Y501592D01*
X176916Y501800D01*
X177000Y502092D01*
X176916Y502383D01*
X176666Y502633D01*
X176291Y502758D01*
X175875D01*
X175625Y502842D01*
X175416Y503050D01*
X175333Y503342D01*
X175458Y503633D01*
X175750Y503842D01*
X176083Y503925D01*
X176416Y503842D01*
X176708Y503633D01*
X176833Y503342D01*
X176750Y503050D01*
X176541Y502842D01*
X176291Y502758D01*
X175875D01*
X175500Y502633D01*
X175250Y502383D01*
X175166Y502092D01*
X175250Y501800D01*
X175458Y501592D01*
X175791Y501467D01*
X176083Y501425D01*
G01X178475Y501717D02*
X178766Y501508D01*
X179100Y501425D01*
X179433Y501508D01*
X179725Y501758D01*
X179933Y502133D01*
X180016Y502508D01*
Y502967D01*
X179933Y503342D01*
X179725Y503675D01*
X179475Y503842D01*
X179183Y503925D01*
X178850Y503842D01*
X178600Y503675D01*
X178433Y503425D01*
X178350Y503092D01*
X178433Y502800D01*
X178641Y502508D01*
X178891Y502342D01*
X179183Y502300D01*
X179516Y502383D01*
X179766Y502592D01*
X180016Y502967D01*
G01X179741Y493710D02*
Y497710D01*
X172341D01*
G01X193800Y463467D02*
X191300D01*
Y464508D01*
X191425Y464842D01*
X191592Y465050D01*
X191925Y465133D01*
X192258Y465050D01*
X192467Y464800D01*
X192592Y464508D01*
Y463467D01*
G01Y464508D02*
X193800Y465133D01*
G01X193508Y466692D02*
X193717Y466983D01*
X193800Y467317D01*
X193717Y467650D01*
X193467Y467942D01*
X193092Y468150D01*
X192717Y468233D01*
X192258D01*
X191883Y468150D01*
X191550Y467942D01*
X191383Y467692D01*
X191300Y467400D01*
X191383Y467067D01*
X191550Y466817D01*
X191800Y466650D01*
X192133Y466567D01*
X192425Y466650D01*
X192717Y466858D01*
X192883Y467108D01*
X192925Y467400D01*
X192842Y467733D01*
X192633Y467983D01*
X192258Y468233D01*
G01X191300Y470500D02*
X191383Y470167D01*
X191592Y469917D01*
X191842Y469750D01*
X192175Y469625D01*
X192550Y469583D01*
X192925Y469625D01*
X193258Y469750D01*
X193508Y469917D01*
X193717Y470167D01*
X193800Y470500D01*
X193717Y470833D01*
X193508Y471083D01*
X193258Y471250D01*
X192925Y471375D01*
X192550Y471417D01*
X192175Y471375D01*
X191842Y471250D01*
X191592Y471083D01*
X191383Y470833D01*
X191300Y470500D01*
G01X181320Y476098D02*
X185320D01*
Y483498D01*
G01X190100Y463467D02*
X187600D01*
Y464508D01*
X187725Y464842D01*
X187892Y465050D01*
X188225Y465133D01*
X188558Y465050D01*
X188767Y464800D01*
X188892Y464508D01*
Y463467D01*
G01Y464508D02*
X190100Y465133D01*
G01X189808Y466692D02*
X190017Y466983D01*
X190100Y467317D01*
X190017Y467650D01*
X189767Y467942D01*
X189392Y468150D01*
X189017Y468233D01*
X188558D01*
X188183Y468150D01*
X187850Y467942D01*
X187683Y467692D01*
X187600Y467400D01*
X187683Y467067D01*
X187850Y466817D01*
X188100Y466650D01*
X188433Y466567D01*
X188725Y466650D01*
X189017Y466858D01*
X189183Y467108D01*
X189225Y467400D01*
X189142Y467733D01*
X188933Y467983D01*
X188558Y468233D01*
G01X190100Y470500D02*
X187600D01*
X188100Y470000D01*
G01X190100D02*
Y471000D01*
G01X176920Y476098D02*
X180920D01*
Y483498D01*
G01X205500Y522300D02*
X201500D01*
Y514900D01*
G01Y522400D02*
X197500D01*
Y515000D01*
G01X172715Y515020D02*
X176715D01*
Y522420D01*
G01X185000Y515000D02*
X189000D01*
Y522400D01*
G01X189100Y514500D02*
X193100D01*
Y521900D01*
G01X189600Y486717D02*
X187100D01*
Y487758D01*
X187225Y488092D01*
X187392Y488300D01*
X187725Y488383D01*
X188058Y488300D01*
X188267Y488050D01*
X188392Y487758D01*
Y486717D01*
G01Y487758D02*
X189600Y488383D01*
G01X187517Y489858D02*
X187267Y490108D01*
X187142Y490400D01*
X187100Y490733D01*
X187183Y491150D01*
X187392Y491442D01*
X187642Y491525D01*
X187892Y491483D01*
X188100Y491317D01*
X188517Y490483D01*
X188808Y490108D01*
X189225Y489858D01*
X189600Y489775D01*
Y491525D01*
G01X187100Y493750D02*
X187183Y493417D01*
X187392Y493167D01*
X187642Y493000D01*
X187975Y492875D01*
X188350Y492833D01*
X188725Y492875D01*
X189058Y493000D01*
X189308Y493167D01*
X189517Y493417D01*
X189600Y493750D01*
X189517Y494083D01*
X189308Y494333D01*
X189058Y494500D01*
X188725Y494625D01*
X188350Y494667D01*
X187975Y494625D01*
X187642Y494500D01*
X187392Y494333D01*
X187183Y494083D01*
X187100Y493750D01*
G01Y496850D02*
X187183Y496517D01*
X187392Y496267D01*
X187642Y496100D01*
X187975Y495975D01*
X188350Y495933D01*
X188725Y495975D01*
X189058Y496100D01*
X189308Y496267D01*
X189517Y496517D01*
X189600Y496850D01*
X189517Y497183D01*
X189308Y497433D01*
X189058Y497600D01*
X188725Y497725D01*
X188350Y497767D01*
X187975Y497725D01*
X187642Y497600D01*
X187392Y497433D01*
X187183Y497183D01*
X187100Y496850D01*
G01X186167Y508384D02*
X182167D01*
Y500984D01*
G01X168700Y515000D02*
X172700D01*
Y522400D01*
G01X164600Y515000D02*
X168600D01*
Y522400D01*
G01X176869Y514993D02*
X180869D01*
Y522393D01*
G01X180874Y514991D02*
X184874D01*
Y522391D01*
G01X158727Y514822D02*
X162727D01*
Y522222D01*
G01X148112Y511098D02*
X152112D01*
Y518498D01*
G01X154721Y514792D02*
X158721D01*
Y522192D01*
G01X193300Y486717D02*
X190800D01*
Y487758D01*
X190925Y488092D01*
X191092Y488300D01*
X191425Y488383D01*
X191758Y488300D01*
X191967Y488050D01*
X192092Y487758D01*
Y486717D01*
G01Y487758D02*
X193300Y488383D01*
G01Y490650D02*
X193258Y490942D01*
X193133Y491275D01*
X192925Y491483D01*
X192633Y491567D01*
X192342Y491483D01*
X192092Y491233D01*
X191967Y490858D01*
Y490442D01*
X191883Y490192D01*
X191675Y489983D01*
X191383Y489900D01*
X191092Y490025D01*
X190883Y490317D01*
X190800Y490650D01*
X190883Y490983D01*
X191092Y491275D01*
X191383Y491400D01*
X191675Y491317D01*
X191883Y491108D01*
X191967Y490858D01*
Y490442D01*
X192092Y490067D01*
X192342Y489817D01*
X192633Y489733D01*
X192925Y489817D01*
X193133Y490025D01*
X193258Y490358D01*
X193300Y490650D01*
G01Y493750D02*
X193258Y494042D01*
X193133Y494375D01*
X192925Y494583D01*
X192633Y494667D01*
X192342Y494583D01*
X192092Y494333D01*
X191967Y493958D01*
Y493542D01*
X191883Y493292D01*
X191675Y493083D01*
X191383Y493000D01*
X191092Y493125D01*
X190883Y493417D01*
X190800Y493750D01*
X190883Y494083D01*
X191092Y494375D01*
X191383Y494500D01*
X191675Y494417D01*
X191883Y494208D01*
X191967Y493958D01*
Y493542D01*
X192092Y493167D01*
X192342Y492917D01*
X192633Y492833D01*
X192925Y492917D01*
X193133Y493125D01*
X193258Y493458D01*
X193300Y493750D01*
G01X186400Y500900D02*
X190400D01*
Y508300D01*
G01X198217Y483100D02*
Y485600D01*
X199258D01*
X199592Y485475D01*
X199800Y485308D01*
X199883Y484975D01*
X199800Y484642D01*
X199550Y484433D01*
X199258Y484308D01*
X198217D01*
G01X199258D02*
X199883Y483100D01*
G01X201233Y483475D02*
X201483Y483267D01*
X201775Y483142D01*
X202150Y483100D01*
X202525Y483183D01*
X202817Y483350D01*
X203025Y483642D01*
X203067Y483975D01*
X202983Y484308D01*
X202775Y484517D01*
X202483Y484683D01*
X202192Y484725D01*
X201900Y484683D01*
X201525Y484517D01*
X201650Y485600D01*
X202775D01*
G01X204542Y483392D02*
X204833Y483183D01*
X205167Y483100D01*
X205500Y483183D01*
X205792Y483433D01*
X206000Y483808D01*
X206083Y484183D01*
Y484642D01*
X206000Y485017D01*
X205792Y485350D01*
X205542Y485517D01*
X205250Y485600D01*
X204917Y485517D01*
X204667Y485350D01*
X204500Y485100D01*
X204417Y484767D01*
X204500Y484475D01*
X204708Y484183D01*
X204958Y484017D01*
X205250Y483975D01*
X205583Y484058D01*
X205833Y484267D01*
X206083Y484642D01*
G01X207642Y483392D02*
X207933Y483183D01*
X208267Y483100D01*
X208600Y483183D01*
X208892Y483433D01*
X209100Y483808D01*
X209183Y484183D01*
Y484642D01*
X209100Y485017D01*
X208892Y485350D01*
X208642Y485517D01*
X208350Y485600D01*
X208017Y485517D01*
X207767Y485350D01*
X207600Y485100D01*
X207517Y484767D01*
X207600Y484475D01*
X207808Y484183D01*
X208058Y484017D01*
X208350Y483975D01*
X208683Y484058D01*
X208933Y484267D01*
X209183Y484642D01*
G01X205600Y493600D02*
Y497600D01*
X198200D01*
G01X177520Y475998D02*
Y471998D01*
X184920D01*
G01X193800Y473717D02*
X191300D01*
Y474758D01*
X191425Y475092D01*
X191592Y475300D01*
X191925Y475383D01*
X192258Y475300D01*
X192467Y475050D01*
X192592Y474758D01*
Y473717D01*
G01Y474758D02*
X193800Y475383D01*
G01Y477567D02*
X193258Y477650D01*
X192800Y477775D01*
X192383Y477942D01*
X191925Y478150D01*
X191300Y478483D01*
Y476817D01*
G01X193800Y480750D02*
X193758Y481042D01*
X193633Y481375D01*
X193425Y481583D01*
X193133Y481667D01*
X192842Y481583D01*
X192592Y481333D01*
X192467Y480958D01*
Y480542D01*
X192383Y480292D01*
X192175Y480083D01*
X191883Y480000D01*
X191592Y480125D01*
X191383Y480417D01*
X191300Y480750D01*
X191383Y481083D01*
X191592Y481375D01*
X191883Y481500D01*
X192175Y481417D01*
X192383Y481208D01*
X192467Y480958D01*
Y480542D01*
X192592Y480167D01*
X192842Y479917D01*
X193133Y479833D01*
X193425Y479917D01*
X193633Y480125D01*
X193758Y480458D01*
X193800Y480750D01*
G01Y483767D02*
X193258Y483850D01*
X192800Y483975D01*
X192383Y484142D01*
X191925Y484350D01*
X191300Y484683D01*
Y483017D01*
G01X185277Y491078D02*
X181277D01*
Y483678D01*
G01X190100Y473717D02*
X187600D01*
Y474758D01*
X187725Y475092D01*
X187892Y475300D01*
X188225Y475383D01*
X188558Y475300D01*
X188767Y475050D01*
X188892Y474758D01*
Y473717D01*
G01Y474758D02*
X190100Y475383D01*
G01Y477567D02*
X189558Y477650D01*
X189100Y477775D01*
X188683Y477942D01*
X188225Y478150D01*
X187600Y478483D01*
Y476817D01*
G01X190100Y480750D02*
X190058Y481042D01*
X189933Y481375D01*
X189725Y481583D01*
X189433Y481667D01*
X189142Y481583D01*
X188892Y481333D01*
X188767Y480958D01*
Y480542D01*
X188683Y480292D01*
X188475Y480083D01*
X188183Y480000D01*
X187892Y480125D01*
X187683Y480417D01*
X187600Y480750D01*
X187683Y481083D01*
X187892Y481375D01*
X188183Y481500D01*
X188475Y481417D01*
X188683Y481208D01*
X188767Y480958D01*
Y480542D01*
X188892Y480167D01*
X189142Y479917D01*
X189433Y479833D01*
X189725Y479917D01*
X189933Y480125D01*
X190058Y480458D01*
X190100Y480750D01*
G01Y483850D02*
X187600D01*
X188100Y483350D01*
G01X190100D02*
Y484350D01*
G01X180920Y491078D02*
X176920D01*
Y483678D01*
G01X202017Y478500D02*
Y481000D01*
X203058D01*
X203392Y480875D01*
X203600Y480708D01*
X203683Y480375D01*
X203600Y480042D01*
X203350Y479833D01*
X203058Y479708D01*
X202017D01*
G01X203058D02*
X203683Y478500D01*
G01X205158Y479542D02*
X205450Y479833D01*
X205700Y480000D01*
X206033Y480083D01*
X206325Y480000D01*
X206533Y479833D01*
X206700Y479583D01*
X206742Y479292D01*
X206700Y479042D01*
X206533Y478792D01*
X206283Y478583D01*
X205992Y478500D01*
X205658Y478583D01*
X205367Y478833D01*
X205200Y479208D01*
X205158Y479625D01*
X205242Y480167D01*
X205367Y480458D01*
X205575Y480750D01*
X205867Y480958D01*
X206158Y481000D01*
X206450Y480917D01*
X206658Y480708D01*
G01X209050Y478500D02*
Y481000D01*
X208550Y480500D01*
G01Y478500D02*
X209550D01*
G01X212150Y481000D02*
X211817Y480917D01*
X211567Y480708D01*
X211400Y480458D01*
X211275Y480125D01*
X211233Y479750D01*
X211275Y479375D01*
X211400Y479042D01*
X211567Y478792D01*
X211817Y478583D01*
X212150Y478500D01*
X212483Y478583D01*
X212733Y478792D01*
X212900Y479042D01*
X213025Y479375D01*
X213067Y479750D01*
X213025Y480125D01*
X212900Y480458D01*
X212733Y480708D01*
X212483Y480917D01*
X212150Y481000D01*
G01X214100Y497300D02*
Y501300D01*
X206700D01*
G01X205400Y507000D02*
Y504500D01*
G01X204442Y507000D02*
X206358D01*
G01X207667Y504500D02*
Y507000D01*
X208667D01*
X209000Y506875D01*
X209250Y506583D01*
X209333Y506250D01*
X209250Y505917D01*
X209042Y505667D01*
X208667Y505542D01*
X207667D01*
G01X210892Y504792D02*
X211183Y504583D01*
X211517Y504500D01*
X211850Y504583D01*
X212142Y504833D01*
X212350Y505208D01*
X212433Y505583D01*
Y506042D01*
X212350Y506417D01*
X212142Y506750D01*
X211892Y506917D01*
X211600Y507000D01*
X211267Y506917D01*
X211017Y506750D01*
X210850Y506500D01*
X210767Y506167D01*
X210850Y505875D01*
X211058Y505583D01*
X211308Y505417D01*
X211600Y505375D01*
X211933Y505458D01*
X212183Y505667D01*
X212433Y506042D01*
G01X150393Y608268D02*
Y533464D01*
X225197D01*
Y608268D01*
X150393D01*
G01X211067Y623733D02*
X211600Y624083D01*
X212000Y624667D01*
X212267Y625483D01*
X212000Y626183D01*
X211467Y626650D01*
X210533Y627000D01*
X206933D01*
Y620000D01*
X211333D01*
X212267Y620467D01*
X212800Y621167D01*
X213067Y621983D01*
X212800Y622800D01*
X212000Y623500D01*
X211067Y623733D01*
X206933D01*
G01X232500Y647800D02*
X204150D01*
G01X197100D02*
X192600D01*
Y650500D01*
G01X163700Y640900D02*
X171200D01*
Y651500D01*
X187500D01*
G01X210567Y651159D02*
X210317Y651284D01*
X210025Y651367D01*
X209692D01*
X209317Y651242D01*
X209025Y651034D01*
X208817Y650784D01*
X208650Y650367D01*
X208608Y649992D01*
X208692Y649617D01*
X208817Y649367D01*
X209067Y649117D01*
X209358Y648950D01*
X209650Y648867D01*
X209942D01*
X210233Y648950D01*
X210483Y649075D01*
X210692Y649242D01*
G01X211833D02*
X212083Y649034D01*
X212375Y648909D01*
X212750Y648867D01*
X213125Y648950D01*
X213417Y649117D01*
X213625Y649409D01*
X213667Y649742D01*
X213583Y650075D01*
X213375Y650284D01*
X213083Y650450D01*
X212792Y650492D01*
X212500Y650450D01*
X212125Y650284D01*
X212250Y651367D01*
X213375D01*
G01X215850Y648867D02*
Y651367D01*
X215350Y650867D01*
G01Y648867D02*
X216350D01*
G01X218242Y649159D02*
X218533Y648950D01*
X218867Y648867D01*
X219200Y648950D01*
X219492Y649200D01*
X219700Y649575D01*
X219783Y649950D01*
Y650409D01*
X219700Y650784D01*
X219492Y651117D01*
X219242Y651284D01*
X218950Y651367D01*
X218617Y651284D01*
X218367Y651117D01*
X218200Y650867D01*
X218117Y650534D01*
X218200Y650242D01*
X218408Y649950D01*
X218658Y649784D01*
X218950Y649742D01*
X219283Y649825D01*
X219533Y650034D01*
X219783Y650409D01*
G01X185708Y654267D02*
X185583Y654017D01*
X185500Y653725D01*
Y653392D01*
X185625Y653017D01*
X185833Y652725D01*
X186083Y652517D01*
X186500Y652350D01*
X186875Y652308D01*
X187250Y652392D01*
X187500Y652517D01*
X187750Y652767D01*
X187917Y653058D01*
X188000Y653350D01*
Y653642D01*
X187917Y653933D01*
X187792Y654183D01*
X187625Y654392D01*
G01Y655533D02*
X187833Y655783D01*
X187958Y656075D01*
X188000Y656450D01*
X187917Y656825D01*
X187750Y657117D01*
X187458Y657325D01*
X187125Y657367D01*
X186792Y657283D01*
X186583Y657075D01*
X186417Y656783D01*
X186375Y656492D01*
X186417Y656200D01*
X186583Y655825D01*
X185500Y655950D01*
Y657075D01*
G01X185917Y658758D02*
X185667Y659008D01*
X185542Y659300D01*
X185500Y659633D01*
X185583Y660050D01*
X185792Y660342D01*
X186042Y660425D01*
X186292Y660383D01*
X186500Y660217D01*
X186917Y659383D01*
X187208Y659008D01*
X187625Y658758D01*
X188000Y658675D01*
Y660425D01*
G01X185500Y662650D02*
X185583Y662317D01*
X185792Y662067D01*
X186042Y661900D01*
X186375Y661775D01*
X186750Y661733D01*
X187125Y661775D01*
X187458Y661900D01*
X187708Y662067D01*
X187917Y662317D01*
X188000Y662650D01*
X187917Y662983D01*
X187708Y663233D01*
X187458Y663400D01*
X187125Y663525D01*
X186750Y663567D01*
X186375Y663525D01*
X186042Y663400D01*
X185792Y663233D01*
X185583Y662983D01*
X185500Y662650D01*
G01X183276Y630868D02*
X187276D01*
Y638268D01*
G01X175100Y631600D02*
X179100D01*
Y639000D01*
G01X171000Y631600D02*
X175000D01*
Y639000D01*
G01X153900Y639300D02*
X149900D01*
Y631900D01*
G01X200560Y622066D02*
X204560D01*
Y629466D01*
G01X195315Y620397D02*
X199315D01*
Y627797D01*
G01X149800Y639300D02*
X145800D01*
Y631900D01*
G01X170900Y639000D02*
X166900D01*
Y631600D01*
G01X151400Y628200D02*
X147400D01*
Y620800D01*
G01X151700D02*
X155700D01*
Y628200D01*
G01X187376Y630868D02*
X191376D01*
Y638268D01*
G01X191476Y630868D02*
X195476D01*
Y638268D01*
G01X195285Y626500D02*
X191285D01*
Y619100D01*
G01X191185Y626500D02*
X187185D01*
Y619100D01*
G01X187085Y626500D02*
X183085D01*
Y619100D01*
G01Y626500D02*
X179085D01*
Y619100D01*
G01X179000Y625400D02*
X175000D01*
Y618000D01*
G01X174900Y625400D02*
X170900D01*
Y618000D01*
G01X179146Y631608D02*
X183146D01*
Y639008D01*
G01X166800Y639000D02*
X162800D01*
Y631600D01*
G01X186400Y642000D02*
X190400D01*
Y649400D01*
G01X199555Y638657D02*
X195555D01*
Y631257D01*
G01X202850Y648400D02*
X198850D01*
Y641000D01*
G01X147300Y643000D02*
X151300D01*
Y650400D01*
G01X210516Y658901D02*
X206516D01*
Y651501D01*
G01X202357Y651486D02*
X206357D01*
Y658886D01*
G01X184500Y653017D02*
X182000D01*
Y654058D01*
X182125Y654392D01*
X182292Y654600D01*
X182625Y654683D01*
X182958Y654600D01*
X183167Y654350D01*
X183292Y654058D01*
Y653017D01*
G01Y654058D02*
X184500Y654683D01*
G01Y656867D02*
X183958Y656950D01*
X183500Y657075D01*
X183083Y657242D01*
X182625Y657450D01*
X182000Y657783D01*
Y656117D01*
G01X184500Y659967D02*
X183958Y660050D01*
X183500Y660175D01*
X183083Y660342D01*
X182625Y660550D01*
X182000Y660883D01*
Y659217D01*
G01X184500Y663150D02*
X184458Y663442D01*
X184333Y663775D01*
X184125Y663983D01*
X183833Y664067D01*
X183542Y663983D01*
X183292Y663733D01*
X183167Y663358D01*
Y662942D01*
X183083Y662692D01*
X182875Y662483D01*
X182583Y662400D01*
X182292Y662525D01*
X182083Y662817D01*
X182000Y663150D01*
X182083Y663483D01*
X182292Y663775D01*
X182583Y663900D01*
X182875Y663817D01*
X183083Y663608D01*
X183167Y663358D01*
Y662942D01*
X183292Y662567D01*
X183542Y662317D01*
X183833Y662233D01*
X184125Y662317D01*
X184333Y662525D01*
X184458Y662858D01*
X184500Y663150D01*
G01X198648Y659021D02*
X194648D01*
Y651621D01*
G01X180500Y653017D02*
X178000D01*
Y654058D01*
X178125Y654392D01*
X178292Y654600D01*
X178625Y654683D01*
X178958Y654600D01*
X179167Y654350D01*
X179292Y654058D01*
Y653017D01*
G01Y654058D02*
X180500Y654683D01*
G01Y656867D02*
X179958Y656950D01*
X179500Y657075D01*
X179083Y657242D01*
X178625Y657450D01*
X178000Y657783D01*
Y656117D01*
G01X180500Y659967D02*
X179958Y660050D01*
X179500Y660175D01*
X179083Y660342D01*
X178625Y660550D01*
X178000Y660883D01*
Y659217D01*
G01X180208Y662442D02*
X180417Y662733D01*
X180500Y663067D01*
X180417Y663400D01*
X180167Y663692D01*
X179792Y663900D01*
X179417Y663983D01*
X178958D01*
X178583Y663900D01*
X178250Y663692D01*
X178083Y663442D01*
X178000Y663150D01*
X178083Y662817D01*
X178250Y662567D01*
X178500Y662400D01*
X178833Y662317D01*
X179125Y662400D01*
X179417Y662608D01*
X179583Y662858D01*
X179625Y663150D01*
X179542Y663483D01*
X179333Y663733D01*
X178958Y663983D01*
G01X189746Y651642D02*
X193746D01*
Y659042D01*
G01X163000Y642300D02*
X167000D01*
Y649700D01*
G01X151400Y650400D02*
Y646400D01*
X158800D01*
G01X163000Y649700D02*
X159000D01*
Y642300D01*
G01X145400Y614917D02*
Y612417D01*
G01X144442Y614917D02*
X146358D01*
G01X147667Y612417D02*
Y614917D01*
X148667D01*
X149000Y614792D01*
X149250Y614500D01*
X149333Y614167D01*
X149250Y613834D01*
X149042Y613584D01*
X148667Y613459D01*
X147667D01*
G01X150683Y612792D02*
X150933Y612584D01*
X151225Y612459D01*
X151600Y612417D01*
X151975Y612500D01*
X152267Y612667D01*
X152475Y612959D01*
X152517Y613292D01*
X152433Y613625D01*
X152225Y613834D01*
X151933Y614000D01*
X151642Y614042D01*
X151350Y614000D01*
X150975Y613834D01*
X151100Y614917D01*
X152225D01*
G01X154617Y612417D02*
X154700Y612959D01*
X154825Y613417D01*
X154992Y613834D01*
X155200Y614292D01*
X155533Y614917D01*
X153867D01*
G01X185042Y700967D02*
X184917Y700717D01*
X184834Y700425D01*
Y700092D01*
X184959Y699717D01*
X185167Y699425D01*
X185417Y699217D01*
X185834Y699050D01*
X186209Y699008D01*
X186584Y699092D01*
X186834Y699217D01*
X187084Y699467D01*
X187251Y699758D01*
X187334Y700050D01*
Y700342D01*
X187251Y700633D01*
X187126Y700883D01*
X186959Y701092D01*
G01X187334Y703150D02*
X184834D01*
X185334Y702650D01*
G01X187334D02*
Y703650D01*
G01Y706250D02*
X187292Y706542D01*
X187167Y706875D01*
X186959Y707083D01*
X186667Y707167D01*
X186376Y707083D01*
X186126Y706833D01*
X186001Y706458D01*
Y706042D01*
X185917Y705792D01*
X185709Y705583D01*
X185417Y705500D01*
X185126Y705625D01*
X184917Y705917D01*
X184834Y706250D01*
X184917Y706583D01*
X185126Y706875D01*
X185417Y707000D01*
X185709Y706917D01*
X185917Y706708D01*
X186001Y706458D01*
Y706042D01*
X186126Y705667D01*
X186376Y705417D01*
X186667Y705333D01*
X186959Y705417D01*
X187167Y705625D01*
X187292Y705958D01*
X187334Y706250D01*
G01Y709350D02*
X184834D01*
X185334Y708850D01*
G01X187334D02*
Y709850D01*
G01X178167Y683892D02*
X177917Y684017D01*
X177625Y684100D01*
X177292D01*
X176917Y683975D01*
X176625Y683767D01*
X176417Y683517D01*
X176250Y683100D01*
X176208Y682725D01*
X176292Y682350D01*
X176417Y682100D01*
X176667Y681850D01*
X176958Y681683D01*
X177250Y681600D01*
X177542D01*
X177833Y681683D01*
X178083Y681808D01*
X178292Y681975D01*
G01X180350Y681600D02*
Y684100D01*
X179850Y683600D01*
G01Y681600D02*
X180850D01*
G01X183450D02*
X183742Y681642D01*
X184075Y681767D01*
X184283Y681975D01*
X184367Y682267D01*
X184283Y682558D01*
X184033Y682808D01*
X183658Y682933D01*
X183242D01*
X182992Y683017D01*
X182783Y683225D01*
X182700Y683517D01*
X182825Y683808D01*
X183117Y684017D01*
X183450Y684100D01*
X183783Y684017D01*
X184075Y683808D01*
X184200Y683517D01*
X184117Y683225D01*
X183908Y683017D01*
X183658Y682933D01*
X183242D01*
X182867Y682808D01*
X182617Y682558D01*
X182533Y682267D01*
X182617Y681975D01*
X182825Y681767D01*
X183158Y681642D01*
X183450Y681600D01*
G01X185633Y682100D02*
X185883Y681808D01*
X186217Y681642D01*
X186592Y681600D01*
X186925Y681642D01*
X187258Y681850D01*
X187467Y682100D01*
X187508Y682350D01*
X187425Y682642D01*
X187133Y682850D01*
X186842Y682933D01*
X186467D01*
G01X186842D02*
X187092Y683058D01*
X187300Y683267D01*
X187383Y683517D01*
X187300Y683767D01*
X187092Y683975D01*
X186717Y684100D01*
X186342Y684058D01*
X185967Y683892D01*
G01X178116Y680007D02*
X177866Y680132D01*
X177574Y680215D01*
X177241D01*
X176866Y680090D01*
X176574Y679882D01*
X176366Y679632D01*
X176199Y679215D01*
X176157Y678840D01*
X176241Y678465D01*
X176366Y678215D01*
X176616Y677965D01*
X176907Y677798D01*
X177199Y677715D01*
X177491D01*
X177782Y677798D01*
X178032Y677923D01*
X178241Y678090D01*
G01X180299Y677715D02*
Y680215D01*
X179799Y679715D01*
G01Y677715D02*
X180799D01*
G01X183399D02*
X183691Y677757D01*
X184024Y677882D01*
X184232Y678090D01*
X184316Y678382D01*
X184232Y678673D01*
X183982Y678923D01*
X183607Y679048D01*
X183191D01*
X182941Y679132D01*
X182732Y679340D01*
X182649Y679632D01*
X182774Y679923D01*
X183066Y680132D01*
X183399Y680215D01*
X183732Y680132D01*
X184024Y679923D01*
X184149Y679632D01*
X184066Y679340D01*
X183857Y679132D01*
X183607Y679048D01*
X183191D01*
X182816Y678923D01*
X182566Y678673D01*
X182482Y678382D01*
X182566Y678090D01*
X182774Y677882D01*
X183107Y677757D01*
X183399Y677715D01*
G01X186999D02*
Y680215D01*
X185457Y678423D01*
X187541D01*
G01X191417Y699359D02*
X191167Y699484D01*
X190875Y699567D01*
X190542D01*
X190167Y699442D01*
X189875Y699234D01*
X189667Y698984D01*
X189500Y698567D01*
X189458Y698192D01*
X189542Y697817D01*
X189667Y697567D01*
X189917Y697317D01*
X190208Y697150D01*
X190500Y697067D01*
X190792D01*
X191083Y697150D01*
X191333Y697275D01*
X191542Y697442D01*
G01X194100Y697067D02*
Y699567D01*
X192558Y697775D01*
X194642D01*
G01X195992Y697359D02*
X196283Y697150D01*
X196617Y697067D01*
X196950Y697150D01*
X197242Y697400D01*
X197450Y697775D01*
X197533Y698150D01*
Y698609D01*
X197450Y698984D01*
X197242Y699317D01*
X196992Y699484D01*
X196700Y699567D01*
X196367Y699484D01*
X196117Y699317D01*
X195950Y699067D01*
X195867Y698734D01*
X195950Y698442D01*
X196158Y698150D01*
X196408Y697984D01*
X196700Y697942D01*
X197033Y698025D01*
X197283Y698234D01*
X197533Y698609D01*
G01X173434Y686317D02*
X170934D01*
Y687358D01*
X171059Y687692D01*
X171226Y687900D01*
X171559Y687983D01*
X171892Y687900D01*
X172101Y687650D01*
X172226Y687358D01*
Y686317D01*
G01Y687358D02*
X173434Y687983D01*
G01Y690750D02*
X170934D01*
X172726Y689208D01*
Y691292D01*
G01X173434Y693350D02*
X173392Y693642D01*
X173267Y693975D01*
X173059Y694183D01*
X172767Y694267D01*
X172476Y694183D01*
X172226Y693933D01*
X172101Y693558D01*
Y693142D01*
X172017Y692892D01*
X171809Y692683D01*
X171517Y692600D01*
X171226Y692725D01*
X171017Y693017D01*
X170934Y693350D01*
X171017Y693683D01*
X171226Y693975D01*
X171517Y694100D01*
X171809Y694017D01*
X172017Y693808D01*
X172101Y693558D01*
Y693142D01*
X172226Y692767D01*
X172476Y692517D01*
X172767Y692433D01*
X173059Y692517D01*
X173267Y692725D01*
X173392Y693058D01*
X173434Y693350D01*
G01X171351Y695658D02*
X171101Y695908D01*
X170976Y696200D01*
X170934Y696533D01*
X171017Y696950D01*
X171226Y697242D01*
X171476Y697325D01*
X171726Y697283D01*
X171934Y697117D01*
X172351Y696283D01*
X172642Y695908D01*
X173059Y695658D01*
X173434Y695575D01*
Y697325D01*
G01X153849Y693715D02*
X157849D01*
Y701115D01*
G01X177334Y686317D02*
X174834D01*
Y687358D01*
X174959Y687692D01*
X175126Y687900D01*
X175459Y687983D01*
X175792Y687900D01*
X176001Y687650D01*
X176126Y687358D01*
Y686317D01*
G01Y687358D02*
X177334Y687983D01*
G01Y690750D02*
X174834D01*
X176626Y689208D01*
Y691292D01*
G01X177334Y693350D02*
X177292Y693642D01*
X177167Y693975D01*
X176959Y694183D01*
X176667Y694267D01*
X176376Y694183D01*
X176126Y693933D01*
X176001Y693558D01*
Y693142D01*
X175917Y692892D01*
X175709Y692683D01*
X175417Y692600D01*
X175126Y692725D01*
X174917Y693017D01*
X174834Y693350D01*
X174917Y693683D01*
X175126Y693975D01*
X175417Y694100D01*
X175709Y694017D01*
X175917Y693808D01*
X176001Y693558D01*
Y693142D01*
X176126Y692767D01*
X176376Y692517D01*
X176667Y692433D01*
X176959Y692517D01*
X177167Y692725D01*
X177292Y693058D01*
X177334Y693350D01*
G01X176959Y695533D02*
X177167Y695783D01*
X177292Y696075D01*
X177334Y696450D01*
X177251Y696825D01*
X177084Y697117D01*
X176792Y697325D01*
X176459Y697367D01*
X176126Y697283D01*
X175917Y697075D01*
X175751Y696783D01*
X175709Y696492D01*
X175751Y696200D01*
X175917Y695825D01*
X174834Y695950D01*
Y697075D01*
G01X166349Y700815D02*
X162349D01*
Y693415D01*
G01X169434Y686417D02*
X166934D01*
Y687458D01*
X167059Y687792D01*
X167226Y688000D01*
X167559Y688083D01*
X167892Y688000D01*
X168101Y687750D01*
X168226Y687458D01*
Y686417D01*
G01Y687458D02*
X169434Y688083D01*
G01Y690850D02*
X166934D01*
X168726Y689308D01*
Y691392D01*
G01X169434Y693450D02*
X169392Y693742D01*
X169267Y694075D01*
X169059Y694283D01*
X168767Y694367D01*
X168476Y694283D01*
X168226Y694033D01*
X168101Y693658D01*
Y693242D01*
X168017Y692992D01*
X167809Y692783D01*
X167517Y692700D01*
X167226Y692825D01*
X167017Y693117D01*
X166934Y693450D01*
X167017Y693783D01*
X167226Y694075D01*
X167517Y694200D01*
X167809Y694117D01*
X168017Y693908D01*
X168101Y693658D01*
Y693242D01*
X168226Y692867D01*
X168476Y692617D01*
X168767Y692533D01*
X169059Y692617D01*
X169267Y692825D01*
X169392Y693158D01*
X169434Y693450D01*
G01X168392Y695758D02*
X168101Y696050D01*
X167934Y696300D01*
X167851Y696633D01*
X167934Y696925D01*
X168101Y697133D01*
X168351Y697300D01*
X168642Y697342D01*
X168892Y697300D01*
X169142Y697133D01*
X169351Y696883D01*
X169434Y696592D01*
X169351Y696258D01*
X169101Y695967D01*
X168726Y695800D01*
X168309Y695758D01*
X167767Y695842D01*
X167476Y695967D01*
X167184Y696175D01*
X166976Y696467D01*
X166934Y696758D01*
X167017Y697050D01*
X167226Y697258D01*
G01X153749Y701115D02*
X149749D01*
Y693715D01*
G01X179634Y699317D02*
X177134D01*
Y700358D01*
X177259Y700692D01*
X177426Y700900D01*
X177759Y700983D01*
X178092Y700900D01*
X178301Y700650D01*
X178426Y700358D01*
Y699317D01*
G01Y700358D02*
X179634Y700983D01*
G01Y703750D02*
X177134D01*
X178926Y702208D01*
Y704292D01*
G01X179634Y706350D02*
X179592Y706642D01*
X179467Y706975D01*
X179259Y707183D01*
X178967Y707267D01*
X178676Y707183D01*
X178426Y706933D01*
X178301Y706558D01*
Y706142D01*
X178217Y705892D01*
X178009Y705683D01*
X177717Y705600D01*
X177426Y705725D01*
X177217Y706017D01*
X177134Y706350D01*
X177217Y706683D01*
X177426Y706975D01*
X177717Y707100D01*
X178009Y707017D01*
X178217Y706808D01*
X178301Y706558D01*
Y706142D01*
X178426Y705767D01*
X178676Y705517D01*
X178967Y705433D01*
X179259Y705517D01*
X179467Y705725D01*
X179592Y706058D01*
X179634Y706350D01*
G01Y709367D02*
X179092Y709450D01*
X178634Y709575D01*
X178217Y709742D01*
X177759Y709950D01*
X177134Y710283D01*
Y708617D01*
G01X156349Y701515D02*
X160349D01*
Y708915D01*
G01X183534Y699217D02*
X181034D01*
Y700258D01*
X181159Y700592D01*
X181326Y700800D01*
X181659Y700883D01*
X181992Y700800D01*
X182201Y700550D01*
X182326Y700258D01*
Y699217D01*
G01Y700258D02*
X183534Y700883D01*
G01Y703650D02*
X181034D01*
X182826Y702108D01*
Y704192D01*
G01X183534Y706250D02*
X183492Y706542D01*
X183367Y706875D01*
X183159Y707083D01*
X182867Y707167D01*
X182576Y707083D01*
X182326Y706833D01*
X182201Y706458D01*
Y706042D01*
X182117Y705792D01*
X181909Y705583D01*
X181617Y705500D01*
X181326Y705625D01*
X181117Y705917D01*
X181034Y706250D01*
X181117Y706583D01*
X181326Y706875D01*
X181617Y707000D01*
X181909Y706917D01*
X182117Y706708D01*
X182201Y706458D01*
Y706042D01*
X182326Y705667D01*
X182576Y705417D01*
X182867Y705333D01*
X183159Y705417D01*
X183367Y705625D01*
X183492Y705958D01*
X183534Y706250D01*
G01Y709350D02*
X183492Y709642D01*
X183367Y709975D01*
X183159Y710183D01*
X182867Y710267D01*
X182576Y710183D01*
X182326Y709933D01*
X182201Y709558D01*
Y709142D01*
X182117Y708892D01*
X181909Y708683D01*
X181617Y708600D01*
X181326Y708725D01*
X181117Y709017D01*
X181034Y709350D01*
X181117Y709683D01*
X181326Y709975D01*
X181617Y710100D01*
X181909Y710017D01*
X182117Y709808D01*
X182201Y709558D01*
Y709142D01*
X182326Y708767D01*
X182576Y708517D01*
X182867Y708433D01*
X183159Y708517D01*
X183367Y708725D01*
X183492Y709058D01*
X183534Y709350D01*
G01X168400Y710200D02*
X164400D01*
Y702800D01*
G01X175634Y699417D02*
X173134D01*
Y700458D01*
X173259Y700792D01*
X173426Y701000D01*
X173759Y701083D01*
X174092Y701000D01*
X174301Y700750D01*
X174426Y700458D01*
Y699417D01*
G01Y700458D02*
X175634Y701083D01*
G01Y703850D02*
X173134D01*
X174926Y702308D01*
Y704392D01*
G01X175342Y705742D02*
X175551Y706033D01*
X175634Y706367D01*
X175551Y706700D01*
X175301Y706992D01*
X174926Y707200D01*
X174551Y707283D01*
X174092D01*
X173717Y707200D01*
X173384Y706992D01*
X173217Y706742D01*
X173134Y706450D01*
X173217Y706117D01*
X173384Y705867D01*
X173634Y705700D01*
X173967Y705617D01*
X174259Y705700D01*
X174551Y705908D01*
X174717Y706158D01*
X174759Y706450D01*
X174676Y706783D01*
X174467Y707033D01*
X174092Y707283D01*
G01X175634Y709550D02*
X173134D01*
X173634Y709050D01*
G01X175634D02*
Y710050D01*
G01X156300Y708915D02*
X152300D01*
Y701515D01*
G01X163617Y711067D02*
Y713567D01*
X164658D01*
X164992Y713442D01*
X165200Y713275D01*
X165283Y712942D01*
X165200Y712609D01*
X164950Y712400D01*
X164658Y712275D01*
X163617D01*
G01X164658D02*
X165283Y711067D01*
G01X168050D02*
Y713567D01*
X166508Y711775D01*
X168592D01*
G01X169942Y711359D02*
X170233Y711150D01*
X170567Y711067D01*
X170900Y711150D01*
X171192Y711400D01*
X171400Y711775D01*
X171483Y712150D01*
Y712609D01*
X171400Y712984D01*
X171192Y713317D01*
X170942Y713484D01*
X170650Y713567D01*
X170317Y713484D01*
X170067Y713317D01*
X169900Y713067D01*
X169817Y712734D01*
X169900Y712442D01*
X170108Y712150D01*
X170358Y711984D01*
X170650Y711942D01*
X170983Y712025D01*
X171233Y712234D01*
X171483Y712609D01*
G01X173750Y711067D02*
X174042Y711109D01*
X174375Y711234D01*
X174583Y711442D01*
X174667Y711734D01*
X174583Y712025D01*
X174333Y712275D01*
X173958Y712400D01*
X173542D01*
X173292Y712484D01*
X173083Y712692D01*
X173000Y712984D01*
X173125Y713275D01*
X173417Y713484D01*
X173750Y713567D01*
X174083Y713484D01*
X174375Y713275D01*
X174500Y712984D01*
X174417Y712692D01*
X174208Y712484D01*
X173958Y712400D01*
X173542D01*
X173167Y712275D01*
X172917Y712025D01*
X172833Y711734D01*
X172917Y711442D01*
X173125Y711234D01*
X173458Y711109D01*
X173750Y711067D01*
G01X153149Y713215D02*
Y709215D01*
X160549D01*
G01X207167Y696467D02*
Y698967D01*
X208208D01*
X208542Y698842D01*
X208750Y698675D01*
X208833Y698342D01*
X208750Y698009D01*
X208500Y697800D01*
X208208Y697675D01*
X207167D01*
G01X208208D02*
X208833Y696467D01*
G01X211017D02*
X211100Y697009D01*
X211225Y697467D01*
X211392Y697884D01*
X211600Y698342D01*
X211933Y698967D01*
X210267D01*
G01X214700Y696467D02*
Y698967D01*
X213158Y697175D01*
X215242D01*
G01X207817Y659867D02*
Y662367D01*
X208858D01*
X209192Y662242D01*
X209400Y662075D01*
X209483Y661742D01*
X209400Y661409D01*
X209150Y661200D01*
X208858Y661075D01*
X207817D01*
G01X208858D02*
X209483Y659867D01*
G01X211667D02*
X211750Y660409D01*
X211875Y660867D01*
X212042Y661284D01*
X212250Y661742D01*
X212583Y662367D01*
X210917D01*
G01X214767Y659867D02*
X214850Y660409D01*
X214975Y660867D01*
X215142Y661284D01*
X215350Y661742D01*
X215683Y662367D01*
X214017D01*
G01X217158Y660909D02*
X217450Y661200D01*
X217700Y661367D01*
X218033Y661450D01*
X218325Y661367D01*
X218533Y661200D01*
X218700Y660950D01*
X218742Y660659D01*
X218700Y660409D01*
X218533Y660159D01*
X218283Y659950D01*
X217992Y659867D01*
X217658Y659950D01*
X217367Y660200D01*
X217200Y660575D01*
X217158Y660992D01*
X217242Y661534D01*
X217367Y661825D01*
X217575Y662117D01*
X217867Y662325D01*
X218158Y662367D01*
X218450Y662284D01*
X218658Y662075D01*
G01X195317Y659867D02*
Y662367D01*
X196358D01*
X196692Y662242D01*
X196900Y662075D01*
X196983Y661742D01*
X196900Y661409D01*
X196650Y661200D01*
X196358Y661075D01*
X195317D01*
G01X196358D02*
X196983Y659867D01*
G01X199167D02*
X199250Y660409D01*
X199375Y660867D01*
X199542Y661284D01*
X199750Y661742D01*
X200083Y662367D01*
X198417D01*
G01X202267Y659867D02*
X202350Y660409D01*
X202475Y660867D01*
X202642Y661284D01*
X202850Y661742D01*
X203183Y662367D01*
X201517D01*
G01X205367Y659867D02*
X205450Y660409D01*
X205575Y660867D01*
X205742Y661284D01*
X205950Y661742D01*
X206283Y662367D01*
X204617D01*
G01X146800Y663217D02*
X144300D01*
Y664258D01*
X144425Y664592D01*
X144592Y664800D01*
X144925Y664883D01*
X145258Y664800D01*
X145467Y664550D01*
X145592Y664258D01*
Y663217D01*
G01Y664258D02*
X146800Y664883D01*
G01X146300Y666233D02*
X146592Y666483D01*
X146758Y666817D01*
X146800Y667192D01*
X146758Y667525D01*
X146550Y667858D01*
X146300Y668067D01*
X146050Y668108D01*
X145758Y668025D01*
X145550Y667733D01*
X145467Y667442D01*
Y667067D01*
G01Y667442D02*
X145342Y667692D01*
X145133Y667900D01*
X144883Y667983D01*
X144633Y667900D01*
X144425Y667692D01*
X144300Y667317D01*
X144342Y666942D01*
X144508Y666567D01*
G01X144717Y669458D02*
X144467Y669708D01*
X144342Y670000D01*
X144300Y670333D01*
X144383Y670750D01*
X144592Y671042D01*
X144842Y671125D01*
X145092Y671083D01*
X145300Y670917D01*
X145717Y670083D01*
X146008Y669708D01*
X146425Y669458D01*
X146800Y669375D01*
Y671125D01*
G01Y673267D02*
X146258Y673350D01*
X145800Y673475D01*
X145383Y673642D01*
X144925Y673850D01*
X144300Y674183D01*
Y672517D01*
G01X190834D02*
X188334D01*
Y673558D01*
X188459Y673892D01*
X188626Y674100D01*
X188959Y674183D01*
X189292Y674100D01*
X189501Y673850D01*
X189626Y673558D01*
Y672517D01*
G01Y673558D02*
X190834Y674183D01*
G01Y676950D02*
X188334D01*
X190126Y675408D01*
Y677492D01*
G01X190834Y679550D02*
X190792Y679842D01*
X190667Y680175D01*
X190459Y680383D01*
X190167Y680467D01*
X189876Y680383D01*
X189626Y680133D01*
X189501Y679758D01*
Y679342D01*
X189417Y679092D01*
X189209Y678883D01*
X188917Y678800D01*
X188626Y678925D01*
X188417Y679217D01*
X188334Y679550D01*
X188417Y679883D01*
X188626Y680175D01*
X188917Y680300D01*
X189209Y680217D01*
X189417Y680008D01*
X189501Y679758D01*
Y679342D01*
X189626Y678967D01*
X189876Y678717D01*
X190167Y678633D01*
X190459Y678717D01*
X190667Y678925D01*
X190792Y679258D01*
X190834Y679550D01*
G01X190542Y681942D02*
X190751Y682233D01*
X190834Y682567D01*
X190751Y682900D01*
X190501Y683192D01*
X190126Y683400D01*
X189751Y683483D01*
X189292D01*
X188917Y683400D01*
X188584Y683192D01*
X188417Y682942D01*
X188334Y682650D01*
X188417Y682317D01*
X188584Y682067D01*
X188834Y681900D01*
X189167Y681817D01*
X189459Y681900D01*
X189751Y682108D01*
X189917Y682358D01*
X189959Y682650D01*
X189876Y682983D01*
X189667Y683233D01*
X189292Y683483D01*
G01X179950Y694367D02*
Y691867D01*
G01X178992Y694367D02*
X180908D01*
G01X182217Y691867D02*
Y694367D01*
X183217D01*
X183550Y694242D01*
X183800Y693950D01*
X183883Y693617D01*
X183800Y693284D01*
X183592Y693034D01*
X183217Y692909D01*
X182217D01*
G01X185067Y691867D02*
Y694367D01*
X186150Y692284D01*
X187233Y694367D01*
Y691867D01*
G01X189250D02*
Y694367D01*
X188750Y693867D01*
G01Y691867D02*
X189750D01*
G01X192401Y665921D02*
X235001D01*
Y693921D01*
X192401D01*
Y665921D01*
G01X188920Y705291D02*
Y716491D01*
G01X206920Y705291D02*
X188920D01*
G01X206920Y716491D02*
Y705291D01*
G01X148869Y723645D02*
Y728645D01*
X143869D01*
G01X147862Y722719D02*
X150862D01*
G01X147862Y712876D02*
X149862D01*
G01X185300Y714500D02*
X149900D01*
Y742500D01*
X185300D01*
Y714500D01*
G01X180292Y667067D02*
Y669567D01*
X182208Y667067D01*
Y669567D01*
G01X183433D02*
Y667775D01*
X183600Y667400D01*
X183933Y667150D01*
X184350Y667067D01*
X184767Y667150D01*
X185100Y667400D01*
X185267Y667775D01*
Y669567D01*
G01X187450D02*
Y667067D01*
G01X186492Y669567D02*
X188408D01*
G01X190550Y667067D02*
Y669567D01*
X190050Y669067D01*
G01Y667067D02*
X191050D01*
G01X208817Y743667D02*
Y746167D01*
X209858D01*
X210192Y746042D01*
X210400Y745875D01*
X210483Y745542D01*
X210400Y745209D01*
X210150Y745000D01*
X209858Y744875D01*
X208817D01*
G01X209858D02*
X210483Y743667D01*
G01X213250D02*
Y746167D01*
X211708Y744375D01*
X213792D01*
G01X215767Y743667D02*
X215850Y744209D01*
X215975Y744667D01*
X216142Y745084D01*
X216350Y745542D01*
X216683Y746167D01*
X215017D01*
G01X218242Y743959D02*
X218533Y743750D01*
X218867Y743667D01*
X219200Y743750D01*
X219492Y744000D01*
X219700Y744375D01*
X219783Y744750D01*
Y745209D01*
X219700Y745584D01*
X219492Y745917D01*
X219242Y746084D01*
X218950Y746167D01*
X218617Y746084D01*
X218367Y745917D01*
X218200Y745667D01*
X218117Y745334D01*
X218200Y745042D01*
X218408Y744750D01*
X218658Y744584D01*
X218950Y744542D01*
X219283Y744625D01*
X219533Y744834D01*
X219783Y745209D01*
G01X208417Y739667D02*
Y742167D01*
X209458D01*
X209792Y742042D01*
X210000Y741875D01*
X210083Y741542D01*
X210000Y741209D01*
X209750Y741000D01*
X209458Y740875D01*
X208417D01*
G01X209458D02*
X210083Y739667D01*
G01X212850D02*
Y742167D01*
X211308Y740375D01*
X213392D01*
G01X215450Y739667D02*
X215742Y739709D01*
X216075Y739834D01*
X216283Y740042D01*
X216367Y740334D01*
X216283Y740625D01*
X216033Y740875D01*
X215658Y741000D01*
X215242D01*
X214992Y741084D01*
X214783Y741292D01*
X214700Y741584D01*
X214825Y741875D01*
X215117Y742084D01*
X215450Y742167D01*
X215783Y742084D01*
X216075Y741875D01*
X216200Y741584D01*
X216117Y741292D01*
X215908Y741084D01*
X215658Y741000D01*
X215242D01*
X214867Y740875D01*
X214617Y740625D01*
X214533Y740334D01*
X214617Y740042D01*
X214825Y739834D01*
X215158Y739709D01*
X215450Y739667D01*
G01X218550Y742167D02*
X218217Y742084D01*
X217967Y741875D01*
X217800Y741625D01*
X217675Y741292D01*
X217633Y740917D01*
X217675Y740542D01*
X217800Y740209D01*
X217967Y739959D01*
X218217Y739750D01*
X218550Y739667D01*
X218883Y739750D01*
X219133Y739959D01*
X219300Y740209D01*
X219425Y740542D01*
X219467Y740917D01*
X219425Y741292D01*
X219300Y741625D01*
X219133Y741875D01*
X218883Y742084D01*
X218550Y742167D01*
G01X208417Y735667D02*
Y738167D01*
X209458D01*
X209792Y738042D01*
X210000Y737875D01*
X210083Y737542D01*
X210000Y737209D01*
X209750Y737000D01*
X209458Y736875D01*
X208417D01*
G01X209458D02*
X210083Y735667D01*
G01X212850D02*
Y738167D01*
X211308Y736375D01*
X213392D01*
G01X215450Y735667D02*
X215742Y735709D01*
X216075Y735834D01*
X216283Y736042D01*
X216367Y736334D01*
X216283Y736625D01*
X216033Y736875D01*
X215658Y737000D01*
X215242D01*
X214992Y737084D01*
X214783Y737292D01*
X214700Y737584D01*
X214825Y737875D01*
X215117Y738084D01*
X215450Y738167D01*
X215783Y738084D01*
X216075Y737875D01*
X216200Y737584D01*
X216117Y737292D01*
X215908Y737084D01*
X215658Y737000D01*
X215242D01*
X214867Y736875D01*
X214617Y736625D01*
X214533Y736334D01*
X214617Y736042D01*
X214825Y735834D01*
X215158Y735709D01*
X215450Y735667D01*
G01X218550D02*
Y738167D01*
X218050Y737667D01*
G01Y735667D02*
X219050D01*
G01X194267Y747458D02*
X194017Y747583D01*
X193725Y747666D01*
X193392D01*
X193017Y747541D01*
X192725Y747333D01*
X192517Y747083D01*
X192350Y746666D01*
X192308Y746291D01*
X192392Y745916D01*
X192517Y745666D01*
X192767Y745416D01*
X193058Y745249D01*
X193350Y745166D01*
X193642D01*
X193933Y745249D01*
X194183Y745374D01*
X194392Y745541D01*
G01X196450Y745166D02*
Y747666D01*
X195950Y747166D01*
G01Y745166D02*
X196950D01*
G01X199467D02*
X199550Y745708D01*
X199675Y746166D01*
X199842Y746583D01*
X200050Y747041D01*
X200383Y747666D01*
X198717D01*
G01X201733Y745541D02*
X201983Y745333D01*
X202275Y745208D01*
X202650Y745166D01*
X203025Y745249D01*
X203317Y745416D01*
X203525Y745708D01*
X203567Y746041D01*
X203483Y746374D01*
X203275Y746583D01*
X202983Y746749D01*
X202692Y746791D01*
X202400Y746749D01*
X202025Y746583D01*
X202150Y747666D01*
X203275D01*
G01X188920Y743691D02*
Y732491D01*
G01X206920Y743691D02*
X188920D01*
G01X206920Y732491D02*
Y743691D01*
G01X165617Y747167D02*
Y744667D01*
X167283D01*
G01X168842Y744959D02*
X169133Y744750D01*
X169467Y744667D01*
X169800Y744750D01*
X170092Y745000D01*
X170300Y745375D01*
X170383Y745750D01*
Y746209D01*
X170300Y746584D01*
X170092Y746917D01*
X169842Y747084D01*
X169550Y747167D01*
X169217Y747084D01*
X168967Y746917D01*
X168800Y746667D01*
X168717Y746334D01*
X168800Y746042D01*
X169008Y745750D01*
X169258Y745584D01*
X169550Y745542D01*
X169883Y745625D01*
X170133Y745834D01*
X170383Y746209D01*
G01X273400Y456200D02*
Y460200D01*
X266000D01*
G01X267075Y445500D02*
X267408Y445292D01*
X267783Y445167D01*
X268117D01*
X268450Y445292D01*
X268700Y445500D01*
X268825Y445792D01*
X268742Y446084D01*
X268533Y446334D01*
X268158Y446500D01*
X267658Y446584D01*
X267367Y446750D01*
X267242Y447042D01*
X267325Y447334D01*
X267533Y447542D01*
X267825Y447667D01*
X268117D01*
X268408Y447584D01*
X268658Y447375D01*
G01X270133Y445167D02*
Y447667D01*
G01X271717D02*
X270133Y446125D01*
G01X271967Y445167D02*
X270842Y446834D01*
G01X274150Y447667D02*
Y445167D01*
G01X273192Y447667D02*
X275108D01*
G01X276458Y447250D02*
X276708Y447500D01*
X277000Y447625D01*
X277333Y447667D01*
X277750Y447584D01*
X278042Y447375D01*
X278125Y447125D01*
X278083Y446875D01*
X277917Y446667D01*
X277083Y446250D01*
X276708Y445959D01*
X276458Y445542D01*
X276375Y445167D01*
X278125D01*
G01X214600Y508900D02*
Y446700D01*
X265000D01*
Y508900D01*
X214600D01*
G01X244100Y446750D02*
X239500Y451350D01*
X234850Y446700D01*
G01X268383Y453067D02*
Y451275D01*
X268550Y450900D01*
X268883Y450650D01*
X269300Y450567D01*
X269717Y450650D01*
X270050Y450900D01*
X270217Y451275D01*
Y453067D01*
G01X271608Y452650D02*
X271858Y452900D01*
X272150Y453025D01*
X272483Y453067D01*
X272900Y452984D01*
X273192Y452775D01*
X273275Y452525D01*
X273233Y452275D01*
X273067Y452067D01*
X272233Y451650D01*
X271858Y451359D01*
X271608Y450942D01*
X271525Y450567D01*
X273275D01*
G01X274792Y450859D02*
X275083Y450650D01*
X275417Y450567D01*
X275750Y450650D01*
X276042Y450900D01*
X276250Y451275D01*
X276333Y451650D01*
Y452109D01*
X276250Y452484D01*
X276042Y452817D01*
X275792Y452984D01*
X275500Y453067D01*
X275167Y452984D01*
X274917Y452817D01*
X274750Y452567D01*
X274667Y452234D01*
X274750Y451942D01*
X274958Y451650D01*
X275208Y451484D01*
X275500Y451442D01*
X275833Y451525D01*
X276083Y451734D01*
X276333Y452109D01*
G01X239800Y457770D02*
X241770Y455800D01*
G01X237830D02*
X239800Y457770D01*
G01X252500Y496500D02*
Y455800D01*
G01X227100D02*
Y496500D01*
G01X252500Y455800D02*
X227100D01*
G01X246000Y526500D02*
X249000D01*
Y546000D01*
X261000D01*
Y554000D01*
X255500D01*
Y554500D01*
G01X228500Y586420D02*
Y526500D01*
X246000D01*
Y511000D01*
X219500D01*
G01X273900Y538500D02*
Y519200D01*
X270900D01*
Y502400D01*
X276600D01*
Y486500D01*
X299400D01*
Y520500D01*
X300700D01*
Y532700D01*
X299443D01*
Y538500D01*
X301200D01*
Y544600D01*
G01X274317Y506792D02*
X274067Y506917D01*
X273775Y507000D01*
X273442D01*
X273067Y506875D01*
X272775Y506667D01*
X272567Y506417D01*
X272400Y506000D01*
X272358Y505625D01*
X272442Y505250D01*
X272567Y505000D01*
X272817Y504750D01*
X273108Y504583D01*
X273400Y504500D01*
X273692D01*
X273983Y504583D01*
X274233Y504708D01*
X274442Y504875D01*
G01X275583Y505000D02*
X275833Y504708D01*
X276167Y504542D01*
X276542Y504500D01*
X276875Y504542D01*
X277208Y504750D01*
X277417Y505000D01*
X277458Y505250D01*
X277375Y505542D01*
X277083Y505750D01*
X276792Y505833D01*
X276417D01*
G01X276792D02*
X277042Y505958D01*
X277250Y506167D01*
X277333Y506417D01*
X277250Y506667D01*
X277042Y506875D01*
X276667Y507000D01*
X276292Y506958D01*
X275917Y506792D01*
G01X278808Y506583D02*
X279058Y506833D01*
X279350Y506958D01*
X279683Y507000D01*
X280100Y506917D01*
X280392Y506708D01*
X280475Y506458D01*
X280433Y506208D01*
X280267Y506000D01*
X279433Y505583D01*
X279058Y505292D01*
X278808Y504875D01*
X278725Y504500D01*
X280475D01*
G01X267117Y482600D02*
Y485100D01*
X268158D01*
X268492Y484975D01*
X268700Y484808D01*
X268783Y484475D01*
X268700Y484142D01*
X268450Y483933D01*
X268158Y483808D01*
X267117D01*
G01X268158D02*
X268783Y482600D01*
G01X270258Y484683D02*
X270508Y484933D01*
X270800Y485058D01*
X271133Y485100D01*
X271550Y485017D01*
X271842Y484808D01*
X271925Y484558D01*
X271883Y484308D01*
X271717Y484100D01*
X270883Y483683D01*
X270508Y483392D01*
X270258Y482975D01*
X270175Y482600D01*
X271925D01*
G01X273358Y483642D02*
X273650Y483933D01*
X273900Y484100D01*
X274233Y484183D01*
X274525Y484100D01*
X274733Y483933D01*
X274900Y483683D01*
X274942Y483392D01*
X274900Y483142D01*
X274733Y482892D01*
X274483Y482683D01*
X274192Y482600D01*
X273858Y482683D01*
X273567Y482933D01*
X273400Y483308D01*
X273358Y483725D01*
X273442Y484267D01*
X273567Y484558D01*
X273775Y484850D01*
X274067Y485058D01*
X274358Y485100D01*
X274650Y485017D01*
X274858Y484808D01*
G01X277167Y482600D02*
X277250Y483142D01*
X277375Y483600D01*
X277542Y484017D01*
X277750Y484475D01*
X278083Y485100D01*
X276417D01*
G01X273800Y488300D02*
Y492300D01*
X266400D01*
G01X228262Y513280D02*
X232262D01*
Y520680D01*
G01X273400Y468300D02*
Y472300D01*
X266000D01*
G01X232348Y513214D02*
X236348D01*
Y520614D01*
G01X236648Y513214D02*
X240648D01*
Y520614D01*
G01X251167Y524567D02*
Y527067D01*
X252208D01*
X252542Y526942D01*
X252750Y526775D01*
X252833Y526442D01*
X252750Y526109D01*
X252500Y525900D01*
X252208Y525775D01*
X251167D01*
G01X252208D02*
X252833Y524567D01*
G01X255600D02*
Y527067D01*
X254058Y525275D01*
X256142D01*
G01X257492Y524859D02*
X257783Y524650D01*
X258117Y524567D01*
X258450Y524650D01*
X258742Y524900D01*
X258950Y525275D01*
X259033Y525650D01*
Y526109D01*
X258950Y526484D01*
X258742Y526817D01*
X258492Y526984D01*
X258200Y527067D01*
X257867Y526984D01*
X257617Y526817D01*
X257450Y526567D01*
X257367Y526234D01*
X257450Y525942D01*
X257658Y525650D01*
X257908Y525484D01*
X258200Y525442D01*
X258533Y525525D01*
X258783Y525734D01*
X259033Y526109D01*
G01X272967Y508600D02*
Y511100D01*
X274008D01*
X274342Y510975D01*
X274550Y510808D01*
X274633Y510475D01*
X274550Y510142D01*
X274300Y509933D01*
X274008Y509808D01*
X272967D01*
G01X274008D02*
X274633Y508600D01*
G01X275983Y508975D02*
X276233Y508767D01*
X276525Y508642D01*
X276900Y508600D01*
X277275Y508683D01*
X277567Y508850D01*
X277775Y509142D01*
X277817Y509475D01*
X277733Y509808D01*
X277525Y510017D01*
X277233Y510183D01*
X276942Y510225D01*
X276650Y510183D01*
X276275Y510017D01*
X276400Y511100D01*
X277525D01*
G01X280000Y508600D02*
Y511100D01*
X279500Y510600D01*
G01Y508600D02*
X280500D01*
G01X265733Y526767D02*
X263233D01*
Y527808D01*
X263358Y528142D01*
X263525Y528350D01*
X263858Y528433D01*
X264191Y528350D01*
X264400Y528100D01*
X264525Y527808D01*
Y526767D01*
G01Y527808D02*
X265733Y528433D01*
G01X265358Y529783D02*
X265566Y530033D01*
X265691Y530325D01*
X265733Y530700D01*
X265650Y531075D01*
X265483Y531367D01*
X265191Y531575D01*
X264858Y531617D01*
X264525Y531533D01*
X264316Y531325D01*
X264150Y531033D01*
X264108Y530742D01*
X264150Y530450D01*
X264316Y530075D01*
X263233Y530200D01*
Y531325D01*
G01X263650Y533008D02*
X263400Y533258D01*
X263275Y533550D01*
X263233Y533883D01*
X263316Y534300D01*
X263525Y534592D01*
X263775Y534675D01*
X264025Y534633D01*
X264233Y534467D01*
X264650Y533633D01*
X264941Y533258D01*
X265358Y533008D01*
X265733Y532925D01*
Y534675D01*
G01X271600Y533500D02*
X267600D01*
Y526100D01*
G01X272967Y512300D02*
Y514800D01*
X274008D01*
X274342Y514675D01*
X274550Y514508D01*
X274633Y514175D01*
X274550Y513842D01*
X274300Y513633D01*
X274008Y513508D01*
X272967D01*
G01X274008D02*
X274633Y512300D01*
G01X275983Y512675D02*
X276233Y512467D01*
X276525Y512342D01*
X276900Y512300D01*
X277275Y512383D01*
X277567Y512550D01*
X277775Y512842D01*
X277817Y513175D01*
X277733Y513508D01*
X277525Y513717D01*
X277233Y513883D01*
X276942Y513925D01*
X276650Y513883D01*
X276275Y513717D01*
X276400Y514800D01*
X277525D01*
G01X280000Y512300D02*
X280292Y512342D01*
X280625Y512467D01*
X280833Y512675D01*
X280917Y512967D01*
X280833Y513258D01*
X280583Y513508D01*
X280208Y513633D01*
X279792D01*
X279542Y513717D01*
X279333Y513925D01*
X279250Y514217D01*
X279375Y514508D01*
X279667Y514717D01*
X280000Y514800D01*
X280333Y514717D01*
X280625Y514508D01*
X280750Y514217D01*
X280667Y513925D01*
X280458Y513717D01*
X280208Y513633D01*
X279792D01*
X279417Y513508D01*
X279167Y513258D01*
X279083Y512967D01*
X279167Y512675D01*
X279375Y512467D01*
X279708Y512342D01*
X280000Y512300D01*
G01X218900Y517666D02*
X214900D01*
Y510266D01*
G01X214600Y522400D02*
X210600D01*
Y515000D01*
G01X240700Y513220D02*
X244700D01*
Y520620D01*
G01X227600Y520780D02*
X223600D01*
Y513380D01*
G01X265900Y476500D02*
Y472500D01*
X273300D01*
G01X275017Y526000D02*
Y528500D01*
X276058D01*
X276392Y528375D01*
X276600Y528208D01*
X276683Y527875D01*
X276600Y527542D01*
X276350Y527333D01*
X276058Y527208D01*
X275017D01*
G01X276058D02*
X276683Y526000D01*
G01X278950D02*
Y528500D01*
X278450Y528000D01*
G01Y526000D02*
X279450D01*
G01X281133Y526500D02*
X281383Y526208D01*
X281717Y526042D01*
X282092Y526000D01*
X282425Y526042D01*
X282758Y526250D01*
X282967Y526500D01*
X283008Y526750D01*
X282925Y527042D01*
X282633Y527250D01*
X282342Y527333D01*
X281967D01*
G01X282342D02*
X282592Y527458D01*
X282800Y527667D01*
X282883Y527917D01*
X282800Y528167D01*
X282592Y528375D01*
X282217Y528500D01*
X281842Y528458D01*
X281467Y528292D01*
G01X285150Y526000D02*
Y528500D01*
X284650Y528000D01*
G01Y526000D02*
X285650D01*
G01X254517Y520767D02*
Y523267D01*
X255558D01*
X255892Y523142D01*
X256100Y522975D01*
X256183Y522642D01*
X256100Y522309D01*
X255850Y522100D01*
X255558Y521975D01*
X254517D01*
G01X255558D02*
X256183Y520767D01*
G01X258367D02*
X258450Y521309D01*
X258575Y521767D01*
X258742Y522184D01*
X258950Y522642D01*
X259283Y523267D01*
X257617D01*
G01X260633Y521267D02*
X260883Y520975D01*
X261217Y520809D01*
X261592Y520767D01*
X261925Y520809D01*
X262258Y521017D01*
X262467Y521267D01*
X262508Y521517D01*
X262425Y521809D01*
X262133Y522017D01*
X261842Y522100D01*
X261467D01*
G01X261842D02*
X262092Y522225D01*
X262300Y522434D01*
X262383Y522684D01*
X262300Y522934D01*
X262092Y523142D01*
X261717Y523267D01*
X261342Y523225D01*
X260967Y523059D01*
G01X264650Y520767D02*
Y523267D01*
X264150Y522767D01*
G01Y520767D02*
X265150D01*
G01X227100Y496500D02*
X252500D01*
G01X228500Y589730D02*
Y593400D01*
G01X255500Y557000D02*
Y581500D01*
X259500D01*
Y590000D01*
X257000D01*
Y599700D01*
G01X245300Y579100D02*
Y583100D01*
X237900D01*
G01X244970Y554658D02*
Y558658D01*
X237570D01*
G01X246066Y569108D02*
Y565108D01*
X253466D01*
G01X245700Y575500D02*
Y571500D01*
X253100D01*
G01X245450Y580300D02*
Y576300D01*
X252850D01*
G01X238300Y590900D02*
Y586900D01*
X245700D01*
G01X237610Y539139D02*
Y535139D01*
X245010D01*
G01X250467Y542167D02*
Y544667D01*
X251508D01*
X251842Y544542D01*
X252050Y544375D01*
X252133Y544042D01*
X252050Y543709D01*
X251800Y543500D01*
X251508Y543375D01*
X250467D01*
G01X251508D02*
X252133Y542167D01*
G01X253483Y542542D02*
X253733Y542334D01*
X254025Y542209D01*
X254400Y542167D01*
X254775Y542250D01*
X255067Y542417D01*
X255275Y542709D01*
X255317Y543042D01*
X255233Y543375D01*
X255025Y543584D01*
X254733Y543750D01*
X254442Y543792D01*
X254150Y543750D01*
X253775Y543584D01*
X253900Y544667D01*
X255025D01*
G01X256792Y542459D02*
X257083Y542250D01*
X257417Y542167D01*
X257750Y542250D01*
X258042Y542500D01*
X258250Y542875D01*
X258333Y543250D01*
Y543709D01*
X258250Y544084D01*
X258042Y544417D01*
X257792Y544584D01*
X257500Y544667D01*
X257167Y544584D01*
X256917Y544417D01*
X256750Y544167D01*
X256667Y543834D01*
X256750Y543542D01*
X256958Y543250D01*
X257208Y543084D01*
X257500Y543042D01*
X257833Y543125D01*
X258083Y543334D01*
X258333Y543709D01*
G01X269241Y541759D02*
Y545759D01*
X261841D01*
G01X245700Y587700D02*
Y583700D01*
X253100D01*
G01X237570Y554558D02*
Y550558D01*
X244970D01*
G01X258367Y561767D02*
Y564267D01*
X259408D01*
X259742Y564142D01*
X259950Y563975D01*
X260033Y563642D01*
X259950Y563309D01*
X259700Y563100D01*
X259408Y562975D01*
X258367D01*
G01X259408D02*
X260033Y561767D01*
G01X261383Y562267D02*
X261633Y561975D01*
X261967Y561809D01*
X262342Y561767D01*
X262675Y561809D01*
X263008Y562017D01*
X263217Y562267D01*
X263258Y562517D01*
X263175Y562809D01*
X262883Y563017D01*
X262592Y563100D01*
X262217D01*
G01X262592D02*
X262842Y563225D01*
X263050Y563434D01*
X263133Y563684D01*
X263050Y563934D01*
X262842Y564142D01*
X262467Y564267D01*
X262092Y564225D01*
X261717Y564059D01*
G01X265400Y561767D02*
X265692Y561809D01*
X266025Y561934D01*
X266233Y562142D01*
X266317Y562434D01*
X266233Y562725D01*
X265983Y562975D01*
X265608Y563100D01*
X265192D01*
X264942Y563184D01*
X264733Y563392D01*
X264650Y563684D01*
X264775Y563975D01*
X265067Y564184D01*
X265400Y564267D01*
X265733Y564184D01*
X266025Y563975D01*
X266150Y563684D01*
X266067Y563392D01*
X265858Y563184D01*
X265608Y563100D01*
X265192D01*
X264817Y562975D01*
X264567Y562725D01*
X264483Y562434D01*
X264567Y562142D01*
X264775Y561934D01*
X265108Y561809D01*
X265400Y561767D01*
G01X267583Y562142D02*
X267833Y561934D01*
X268125Y561809D01*
X268500Y561767D01*
X268875Y561850D01*
X269167Y562017D01*
X269375Y562309D01*
X269417Y562642D01*
X269333Y562975D01*
X269125Y563184D01*
X268833Y563350D01*
X268542Y563392D01*
X268250Y563350D01*
X267875Y563184D01*
X268000Y564267D01*
X269125D01*
G01X268300Y565300D02*
Y569300D01*
X260900D01*
G01X272200Y570100D02*
Y574100D01*
X264800D01*
G01X258800Y541500D02*
Y537500D01*
X266200D01*
G01X258567Y555167D02*
Y557667D01*
X259608D01*
X259942Y557542D01*
X260150Y557375D01*
X260233Y557042D01*
X260150Y556709D01*
X259900Y556500D01*
X259608Y556375D01*
X258567D01*
G01X259608D02*
X260233Y555167D01*
G01X261583Y555542D02*
X261833Y555334D01*
X262125Y555209D01*
X262500Y555167D01*
X262875Y555250D01*
X263167Y555417D01*
X263375Y555709D01*
X263417Y556042D01*
X263333Y556375D01*
X263125Y556584D01*
X262833Y556750D01*
X262542Y556792D01*
X262250Y556750D01*
X261875Y556584D01*
X262000Y557667D01*
X263125D01*
G01X264808Y556209D02*
X265100Y556500D01*
X265350Y556667D01*
X265683Y556750D01*
X265975Y556667D01*
X266183Y556500D01*
X266350Y556250D01*
X266392Y555959D01*
X266350Y555709D01*
X266183Y555459D01*
X265933Y555250D01*
X265642Y555167D01*
X265308Y555250D01*
X265017Y555500D01*
X264850Y555875D01*
X264808Y556292D01*
X264892Y556834D01*
X265017Y557125D01*
X265225Y557417D01*
X265517Y557625D01*
X265808Y557667D01*
X266100Y557584D01*
X266308Y557375D01*
G01X262200Y554100D02*
Y550100D01*
X269600D01*
G01X238596Y562698D02*
Y558698D01*
X245996D01*
G01X238596Y566798D02*
Y562798D01*
X245996D01*
G01X245018Y566821D02*
Y570821D01*
X237618D01*
G01X245018D02*
Y574821D01*
X237618D01*
G01X245400Y574900D02*
Y578900D01*
X238000D01*
G01X252874Y554061D02*
Y550061D01*
X260274D01*
G01X245996Y558761D02*
Y554761D01*
X253396D01*
G01X246077Y565068D02*
Y561068D01*
X253477D01*
G01X247693Y530802D02*
Y534802D01*
X240293D01*
G01X270717Y561167D02*
Y563667D01*
X271758D01*
X272092Y563542D01*
X272300Y563375D01*
X272383Y563042D01*
X272300Y562709D01*
X272050Y562500D01*
X271758Y562375D01*
X270717D01*
G01X271758D02*
X272383Y561167D01*
G01X273858Y562209D02*
X274150Y562500D01*
X274400Y562667D01*
X274733Y562750D01*
X275025Y562667D01*
X275233Y562500D01*
X275400Y562250D01*
X275442Y561959D01*
X275400Y561709D01*
X275233Y561459D01*
X274983Y561250D01*
X274692Y561167D01*
X274358Y561250D01*
X274067Y561500D01*
X273900Y561875D01*
X273858Y562292D01*
X273942Y562834D01*
X274067Y563125D01*
X274275Y563417D01*
X274567Y563625D01*
X274858Y563667D01*
X275150Y563584D01*
X275358Y563375D01*
G01X277750Y563667D02*
X277417Y563584D01*
X277167Y563375D01*
X277000Y563125D01*
X276875Y562792D01*
X276833Y562417D01*
X276875Y562042D01*
X277000Y561709D01*
X277167Y561459D01*
X277417Y561250D01*
X277750Y561167D01*
X278083Y561250D01*
X278333Y561459D01*
X278500Y561709D01*
X278625Y562042D01*
X278667Y562417D01*
X278625Y562792D01*
X278500Y563125D01*
X278333Y563375D01*
X278083Y563584D01*
X277750Y563667D01*
G01X280850Y561167D02*
Y563667D01*
X280350Y563167D01*
G01Y561167D02*
X281350D01*
G01X278767Y555480D02*
Y559480D01*
X271367D01*
G01X272300Y577000D02*
Y573000D01*
X279700D01*
G01X274917Y533800D02*
Y536300D01*
X275958D01*
X276292Y536175D01*
X276500Y536008D01*
X276583Y535675D01*
X276500Y535342D01*
X276250Y535133D01*
X275958Y535008D01*
X274917D01*
G01X275958D02*
X276583Y533800D01*
G01X277933Y534300D02*
X278183Y534008D01*
X278517Y533842D01*
X278892Y533800D01*
X279225Y533842D01*
X279558Y534050D01*
X279767Y534300D01*
X279808Y534550D01*
X279725Y534842D01*
X279433Y535050D01*
X279142Y535133D01*
X278767D01*
G01X279142D02*
X279392Y535258D01*
X279600Y535467D01*
X279683Y535717D01*
X279600Y535967D01*
X279392Y536175D01*
X279017Y536300D01*
X278642Y536258D01*
X278267Y536092D01*
G01X281158Y535883D02*
X281408Y536133D01*
X281700Y536258D01*
X282033Y536300D01*
X282450Y536217D01*
X282742Y536008D01*
X282825Y535758D01*
X282783Y535508D01*
X282617Y535300D01*
X281783Y534883D01*
X281408Y534592D01*
X281158Y534175D01*
X281075Y533800D01*
X282825D01*
G01X284342Y534092D02*
X284633Y533883D01*
X284967Y533800D01*
X285300Y533883D01*
X285592Y534133D01*
X285800Y534508D01*
X285883Y534883D01*
Y535342D01*
X285800Y535717D01*
X285592Y536050D01*
X285342Y536217D01*
X285050Y536300D01*
X284717Y536217D01*
X284467Y536050D01*
X284300Y535800D01*
X284217Y535467D01*
X284300Y535175D01*
X284508Y534883D01*
X284758Y534717D01*
X285050Y534675D01*
X285383Y534758D01*
X285633Y534967D01*
X285883Y535342D01*
G01X275017Y530100D02*
Y532600D01*
X276058D01*
X276392Y532475D01*
X276600Y532308D01*
X276683Y531975D01*
X276600Y531642D01*
X276350Y531433D01*
X276058Y531308D01*
X275017D01*
G01X276058D02*
X276683Y530100D01*
G01X278950D02*
Y532600D01*
X278450Y532100D01*
G01Y530100D02*
X279450D01*
G01X281133Y530600D02*
X281383Y530308D01*
X281717Y530142D01*
X282092Y530100D01*
X282425Y530142D01*
X282758Y530350D01*
X282967Y530600D01*
X283008Y530850D01*
X282925Y531142D01*
X282633Y531350D01*
X282342Y531433D01*
X281967D01*
G01X282342D02*
X282592Y531558D01*
X282800Y531767D01*
X282883Y532017D01*
X282800Y532267D01*
X282592Y532475D01*
X282217Y532600D01*
X281842Y532558D01*
X281467Y532392D01*
G01X284358Y532183D02*
X284608Y532433D01*
X284900Y532558D01*
X285233Y532600D01*
X285650Y532517D01*
X285942Y532308D01*
X286025Y532058D01*
X285983Y531808D01*
X285817Y531600D01*
X284983Y531183D01*
X284608Y530892D01*
X284358Y530475D01*
X284275Y530100D01*
X286025D01*
G01X261620Y530870D02*
Y534870D01*
X254220D01*
G01X258134Y591333D02*
X259926D01*
X260301Y591500D01*
X260551Y591833D01*
X260634Y592250D01*
X260551Y592667D01*
X260301Y593000D01*
X259926Y593167D01*
X258134D01*
G01X260134Y594433D02*
X260426Y594683D01*
X260592Y595017D01*
X260634Y595392D01*
X260592Y595725D01*
X260384Y596058D01*
X260134Y596267D01*
X259884Y596308D01*
X259592Y596225D01*
X259384Y595933D01*
X259301Y595642D01*
Y595267D01*
G01Y595642D02*
X259176Y595892D01*
X258967Y596100D01*
X258717Y596183D01*
X258467Y596100D01*
X258259Y595892D01*
X258134Y595517D01*
X258176Y595142D01*
X258342Y594767D01*
G01X258134Y598450D02*
X258217Y598117D01*
X258426Y597867D01*
X258676Y597700D01*
X259009Y597575D01*
X259384Y597533D01*
X259759Y597575D01*
X260092Y597700D01*
X260342Y597867D01*
X260551Y598117D01*
X260634Y598450D01*
X260551Y598783D01*
X260342Y599033D01*
X260092Y599200D01*
X259759Y599325D01*
X259384Y599367D01*
X259009Y599325D01*
X258676Y599200D01*
X258426Y599033D01*
X258217Y598783D01*
X258134Y598450D01*
G01X272000Y600300D02*
Y581100D01*
X283200D01*
Y600300D01*
X272000D01*
Y599900D01*
G01X271245Y543694D02*
X284645D01*
G01X271245Y555094D02*
Y543694D01*
G01X284645Y555094D02*
X271245D01*
G01X244467Y620300D02*
X247800Y627300D01*
X251133Y620300D01*
G01X249933Y622750D02*
X245667D01*
G01X228500Y598350D02*
Y619500D01*
X231100D01*
Y623000D01*
G01X241500Y628500D02*
X257000D01*
Y610140D01*
G01X258342Y614367D02*
X258217Y614117D01*
X258134Y613825D01*
Y613492D01*
X258259Y613117D01*
X258467Y612825D01*
X258717Y612617D01*
X259134Y612450D01*
X259509Y612408D01*
X259884Y612492D01*
X260134Y612617D01*
X260384Y612867D01*
X260551Y613158D01*
X260634Y613450D01*
Y613742D01*
X260551Y614033D01*
X260426Y614283D01*
X260259Y614492D01*
G01Y615633D02*
X260467Y615883D01*
X260592Y616175D01*
X260634Y616550D01*
X260551Y616925D01*
X260384Y617217D01*
X260092Y617425D01*
X259759Y617467D01*
X259426Y617383D01*
X259217Y617175D01*
X259051Y616883D01*
X259009Y616592D01*
X259051Y616300D01*
X259217Y615925D01*
X258134Y616050D01*
Y617175D01*
G01X260634Y619650D02*
X258134D01*
X258634Y619150D01*
G01X260634D02*
Y620150D01*
G01Y622750D02*
X260592Y623042D01*
X260467Y623375D01*
X260259Y623583D01*
X259967Y623667D01*
X259676Y623583D01*
X259426Y623333D01*
X259301Y622958D01*
Y622542D01*
X259217Y622292D01*
X259009Y622083D01*
X258717Y622000D01*
X258426Y622125D01*
X258217Y622417D01*
X258134Y622750D01*
X258217Y623083D01*
X258426Y623375D01*
X258717Y623500D01*
X259009Y623417D01*
X259217Y623208D01*
X259301Y622958D01*
Y622542D01*
X259426Y622167D01*
X259676Y621917D01*
X259967Y621833D01*
X260259Y621917D01*
X260467Y622125D01*
X260592Y622458D01*
X260634Y622750D01*
G01X269517Y635659D02*
X269267Y635784D01*
X268975Y635867D01*
X268642D01*
X268267Y635742D01*
X267975Y635534D01*
X267767Y635284D01*
X267600Y634867D01*
X267558Y634492D01*
X267642Y634117D01*
X267767Y633867D01*
X268017Y633617D01*
X268308Y633450D01*
X268600Y633367D01*
X268892D01*
X269183Y633450D01*
X269433Y633575D01*
X269642Y633742D01*
G01X270783D02*
X271033Y633534D01*
X271325Y633409D01*
X271700Y633367D01*
X272075Y633450D01*
X272367Y633617D01*
X272575Y633909D01*
X272617Y634242D01*
X272533Y634575D01*
X272325Y634784D01*
X272033Y634950D01*
X271742Y634992D01*
X271450Y634950D01*
X271075Y634784D01*
X271200Y635867D01*
X272325D01*
G01X274008Y635450D02*
X274258Y635700D01*
X274550Y635825D01*
X274883Y635867D01*
X275300Y635784D01*
X275592Y635575D01*
X275675Y635325D01*
X275633Y635075D01*
X275467Y634867D01*
X274633Y634450D01*
X274258Y634159D01*
X274008Y633742D01*
X273925Y633367D01*
X275675D01*
G01X238142Y642967D02*
X238017Y642717D01*
X237934Y642425D01*
Y642092D01*
X238059Y641717D01*
X238267Y641425D01*
X238517Y641217D01*
X238934Y641050D01*
X239309Y641008D01*
X239684Y641092D01*
X239934Y641217D01*
X240184Y641467D01*
X240351Y641758D01*
X240434Y642050D01*
Y642342D01*
X240351Y642633D01*
X240226Y642883D01*
X240059Y643092D01*
G01Y644233D02*
X240267Y644483D01*
X240392Y644775D01*
X240434Y645150D01*
X240351Y645525D01*
X240184Y645817D01*
X239892Y646025D01*
X239559Y646067D01*
X239226Y645983D01*
X239017Y645775D01*
X238851Y645483D01*
X238809Y645192D01*
X238851Y644900D01*
X239017Y644525D01*
X237934Y644650D01*
Y645775D01*
G01Y648250D02*
X238017Y647917D01*
X238226Y647667D01*
X238476Y647500D01*
X238809Y647375D01*
X239184Y647333D01*
X239559Y647375D01*
X239892Y647500D01*
X240142Y647667D01*
X240351Y647917D01*
X240434Y648250D01*
X240351Y648583D01*
X240142Y648833D01*
X239892Y649000D01*
X239559Y649125D01*
X239184Y649167D01*
X238809Y649125D01*
X238476Y649000D01*
X238226Y648833D01*
X238017Y648583D01*
X237934Y648250D01*
G01X222616Y660967D02*
Y656967D01*
X230016D01*
G01X265224Y609367D02*
X262724D01*
Y610408D01*
X262849Y610742D01*
X263016Y610950D01*
X263349Y611033D01*
X263682Y610950D01*
X263891Y610700D01*
X264016Y610408D01*
Y609367D01*
G01Y610408D02*
X265224Y611033D01*
G01X264724Y612383D02*
X265016Y612633D01*
X265182Y612967D01*
X265224Y613342D01*
X265182Y613675D01*
X264974Y614008D01*
X264724Y614217D01*
X264474Y614258D01*
X264182Y614175D01*
X263974Y613883D01*
X263891Y613592D01*
Y613217D01*
G01Y613592D02*
X263766Y613842D01*
X263557Y614050D01*
X263307Y614133D01*
X263057Y614050D01*
X262849Y613842D01*
X262724Y613467D01*
X262766Y613092D01*
X262932Y612717D01*
G01X262724Y616400D02*
X262807Y616067D01*
X263016Y615817D01*
X263266Y615650D01*
X263599Y615525D01*
X263974Y615483D01*
X264349Y615525D01*
X264682Y615650D01*
X264932Y615817D01*
X265141Y616067D01*
X265224Y616400D01*
X265141Y616733D01*
X264932Y616983D01*
X264682Y617150D01*
X264349Y617275D01*
X263974Y617317D01*
X263599Y617275D01*
X263266Y617150D01*
X263016Y616983D01*
X262807Y616733D01*
X262724Y616400D01*
G01X264182Y618708D02*
X263891Y619000D01*
X263724Y619250D01*
X263641Y619583D01*
X263724Y619875D01*
X263891Y620083D01*
X264141Y620250D01*
X264432Y620292D01*
X264682Y620250D01*
X264932Y620083D01*
X265141Y619833D01*
X265224Y619542D01*
X265141Y619208D01*
X264891Y618917D01*
X264516Y618750D01*
X264099Y618708D01*
X263557Y618792D01*
X263266Y618917D01*
X262974Y619125D01*
X262766Y619417D01*
X262724Y619708D01*
X262807Y620000D01*
X263016Y620208D01*
G01X273000Y603500D02*
Y607500D01*
X265600D01*
G01X232800Y635200D02*
Y631200D01*
X240200D01*
G01X254272Y618581D02*
X250272D01*
Y611181D01*
G01X227900Y629100D02*
X223900D01*
Y621700D01*
G01X231900Y630400D02*
X227900D01*
Y623000D01*
G01X223900Y629100D02*
X219900D01*
Y621700D01*
G01X238300Y635600D02*
Y639600D01*
X230900D01*
G01X240000Y628200D02*
X236000D01*
Y620800D01*
G01X236634Y643167D02*
X234134D01*
Y644208D01*
X234259Y644542D01*
X234426Y644750D01*
X234759Y644833D01*
X235092Y644750D01*
X235301Y644500D01*
X235426Y644208D01*
Y643167D01*
G01Y644208D02*
X236634Y644833D01*
G01Y647017D02*
X236092Y647100D01*
X235634Y647225D01*
X235217Y647392D01*
X234759Y647600D01*
X234134Y647933D01*
Y646267D01*
G01X234551Y649408D02*
X234301Y649658D01*
X234176Y649950D01*
X234134Y650283D01*
X234217Y650700D01*
X234426Y650992D01*
X234676Y651075D01*
X234926Y651033D01*
X235134Y650867D01*
X235551Y650033D01*
X235842Y649658D01*
X236259Y649408D01*
X236634Y649325D01*
Y651075D01*
G01X241400Y637500D02*
X245400D01*
Y644900D01*
G01X272000Y641000D02*
Y645000D01*
X264600D01*
G01X249567Y638467D02*
Y640967D01*
X250608D01*
X250942Y640842D01*
X251150Y640675D01*
X251233Y640342D01*
X251150Y640009D01*
X250900Y639800D01*
X250608Y639675D01*
X249567D01*
G01X250608D02*
X251233Y638467D01*
G01X253417D02*
X253500Y639009D01*
X253625Y639467D01*
X253792Y639884D01*
X254000Y640342D01*
X254333Y640967D01*
X252667D01*
G01X255808Y639509D02*
X256100Y639800D01*
X256350Y639967D01*
X256683Y640050D01*
X256975Y639967D01*
X257183Y639800D01*
X257350Y639550D01*
X257392Y639259D01*
X257350Y639009D01*
X257183Y638759D01*
X256933Y638550D01*
X256642Y638467D01*
X256308Y638550D01*
X256017Y638800D01*
X255850Y639175D01*
X255808Y639592D01*
X255892Y640134D01*
X256017Y640425D01*
X256225Y640717D01*
X256517Y640925D01*
X256808Y640967D01*
X257100Y640884D01*
X257308Y640675D01*
G01X263700Y641000D02*
Y645000D01*
X256300D01*
G01X222467Y652967D02*
Y655467D01*
X223508D01*
X223842Y655342D01*
X224050Y655175D01*
X224133Y654842D01*
X224050Y654509D01*
X223800Y654300D01*
X223508Y654175D01*
X222467D01*
G01X223508D02*
X224133Y652967D01*
G01X226317D02*
X226400Y653509D01*
X226525Y653967D01*
X226692Y654384D01*
X226900Y654842D01*
X227233Y655467D01*
X225567D01*
G01X229417Y652967D02*
X229500Y653509D01*
X229625Y653967D01*
X229792Y654384D01*
X230000Y654842D01*
X230333Y655467D01*
X228667D01*
G01X233500Y661100D02*
Y657100D01*
X240900D01*
G01X237900Y603000D02*
Y599000D01*
X245300D01*
G01X246215Y611187D02*
X250215D01*
Y618587D01*
G01X236000Y628200D02*
X232000D01*
Y620800D01*
G01X225400Y643400D02*
X221400D01*
Y636000D01*
G01X217200Y638600D02*
X221200D01*
Y646000D01*
G01X229300Y640100D02*
X233300D01*
Y647500D01*
G01X209706Y635992D02*
X213706D01*
Y643392D01*
G01X246156Y619187D02*
X242156D01*
Y611787D01*
G01X265717Y622767D02*
Y625267D01*
X266758D01*
X267092Y625142D01*
X267300Y624975D01*
X267383Y624642D01*
X267300Y624309D01*
X267050Y624100D01*
X266758Y623975D01*
X265717D01*
G01X266758D02*
X267383Y622767D01*
G01X269567D02*
X269650Y623309D01*
X269775Y623767D01*
X269942Y624184D01*
X270150Y624642D01*
X270483Y625267D01*
X268817D01*
G01X272667Y622767D02*
X272750Y623309D01*
X272875Y623767D01*
X273042Y624184D01*
X273250Y624642D01*
X273583Y625267D01*
X271917D01*
G01X276350Y622767D02*
Y625267D01*
X274808Y623475D01*
X276892D01*
G01X265096Y628071D02*
Y632071D01*
X257696D01*
G01X266917Y627667D02*
Y630167D01*
X267958D01*
X268292Y630042D01*
X268500Y629875D01*
X268583Y629542D01*
X268500Y629209D01*
X268250Y629000D01*
X267958Y628875D01*
X266917D01*
G01X267958D02*
X268583Y627667D01*
G01X270767D02*
X270850Y628209D01*
X270975Y628667D01*
X271142Y629084D01*
X271350Y629542D01*
X271683Y630167D01*
X270017D01*
G01X273867Y627667D02*
X273950Y628209D01*
X274075Y628667D01*
X274242Y629084D01*
X274450Y629542D01*
X274783Y630167D01*
X273117D01*
G01X276133Y628042D02*
X276383Y627834D01*
X276675Y627709D01*
X277050Y627667D01*
X277425Y627750D01*
X277717Y627917D01*
X277925Y628209D01*
X277967Y628542D01*
X277883Y628875D01*
X277675Y629084D01*
X277383Y629250D01*
X277092Y629292D01*
X276800Y629250D01*
X276425Y629084D01*
X276550Y630167D01*
X277675D01*
G01X257873Y636343D02*
Y632343D01*
X265273D01*
G01X254517Y601617D02*
Y604117D01*
X255558D01*
X255892Y603992D01*
X256100Y603825D01*
X256183Y603492D01*
X256100Y603159D01*
X255850Y602950D01*
X255558Y602825D01*
X254517D01*
G01X255558D02*
X256183Y601617D01*
G01X258367D02*
X258450Y602159D01*
X258575Y602617D01*
X258742Y603034D01*
X258950Y603492D01*
X259283Y604117D01*
X257617D01*
G01X261550Y601617D02*
X261842Y601659D01*
X262175Y601784D01*
X262383Y601992D01*
X262467Y602284D01*
X262383Y602575D01*
X262133Y602825D01*
X261758Y602950D01*
X261342D01*
X261092Y603034D01*
X260883Y603242D01*
X260800Y603534D01*
X260925Y603825D01*
X261217Y604034D01*
X261550Y604117D01*
X261883Y604034D01*
X262175Y603825D01*
X262300Y603534D01*
X262217Y603242D01*
X262008Y603034D01*
X261758Y602950D01*
X261342D01*
X260967Y602825D01*
X260717Y602575D01*
X260633Y602284D01*
X260717Y601992D01*
X260925Y601784D01*
X261258Y601659D01*
X261550Y601617D01*
G01X264650Y604117D02*
X264317Y604034D01*
X264067Y603825D01*
X263900Y603575D01*
X263775Y603242D01*
X263733Y602867D01*
X263775Y602492D01*
X263900Y602159D01*
X264067Y601909D01*
X264317Y601700D01*
X264650Y601617D01*
X264983Y601700D01*
X265233Y601909D01*
X265400Y602159D01*
X265525Y602492D01*
X265567Y602867D01*
X265525Y603242D01*
X265400Y603575D01*
X265233Y603825D01*
X264983Y604034D01*
X264650Y604117D01*
G01X280850Y600700D02*
Y604700D01*
X273450D01*
G01X274233Y646950D02*
X274191Y646617D01*
X274025Y646325D01*
X273775Y646075D01*
X273483Y645908D01*
X273150Y645825D01*
X272816D01*
X272483Y645908D01*
X272191Y646075D01*
X271941Y646325D01*
X271775Y646617D01*
X271733Y646950D01*
X271775Y647283D01*
X271941Y647575D01*
X272191Y647825D01*
X272483Y647992D01*
X272816Y648075D01*
X273150D01*
X273483Y647992D01*
X273775Y647825D01*
X274025Y647575D01*
X274191Y647283D01*
X274233Y646950D01*
G01X273566Y647283D02*
X274233Y647783D01*
G01X272150Y649258D02*
X271900Y649508D01*
X271775Y649800D01*
X271733Y650133D01*
X271816Y650550D01*
X272025Y650842D01*
X272275Y650925D01*
X272525Y650883D01*
X272733Y650717D01*
X273150Y649883D01*
X273441Y649508D01*
X273858Y649258D01*
X274233Y649175D01*
Y650925D01*
G01X270500Y646000D02*
Y659000D01*
G01X256500Y646000D02*
X270500D01*
G01X256500Y659000D02*
Y646000D01*
G01X232950Y653267D02*
X232617Y653309D01*
X232325Y653475D01*
X232075Y653725D01*
X231908Y654017D01*
X231825Y654350D01*
Y654684D01*
X231908Y655017D01*
X232075Y655309D01*
X232325Y655559D01*
X232617Y655725D01*
X232950Y655767D01*
X233283Y655725D01*
X233575Y655559D01*
X233825Y655309D01*
X233992Y655017D01*
X234075Y654684D01*
Y654350D01*
X233992Y654017D01*
X233825Y653725D01*
X233575Y653475D01*
X233283Y653309D01*
X232950Y653267D01*
G01X233283Y653934D02*
X233783Y653267D01*
G01X235133Y653767D02*
X235383Y653475D01*
X235717Y653309D01*
X236092Y653267D01*
X236425Y653309D01*
X236758Y653517D01*
X236967Y653767D01*
X237008Y654017D01*
X236925Y654309D01*
X236633Y654517D01*
X236342Y654600D01*
X235967D01*
G01X236342D02*
X236592Y654725D01*
X236800Y654934D01*
X236883Y655184D01*
X236800Y655434D01*
X236592Y655642D01*
X236217Y655767D01*
X235842Y655725D01*
X235467Y655559D01*
G01X241500Y646000D02*
X255500D01*
G01X241500Y659000D02*
Y646000D01*
G01X255500D02*
Y659000D01*
G01X283483Y609217D02*
X266783D01*
Y621317D01*
X283483D01*
Y609217D01*
G01X273117Y700458D02*
X272867Y700583D01*
X272575Y700666D01*
X272242D01*
X271867Y700541D01*
X271575Y700333D01*
X271367Y700083D01*
X271200Y699666D01*
X271158Y699291D01*
X271242Y698916D01*
X271367Y698666D01*
X271617Y698416D01*
X271908Y698249D01*
X272200Y698166D01*
X272492D01*
X272783Y698249D01*
X273033Y698374D01*
X273242Y698541D01*
G01X275217Y698166D02*
X275300Y698708D01*
X275425Y699166D01*
X275592Y699583D01*
X275800Y700041D01*
X276133Y700666D01*
X274467D01*
G01X278400Y698166D02*
X278692Y698208D01*
X279025Y698333D01*
X279233Y698541D01*
X279317Y698833D01*
X279233Y699124D01*
X278983Y699374D01*
X278608Y699499D01*
X278192D01*
X277942Y699583D01*
X277733Y699791D01*
X277650Y700083D01*
X277775Y700374D01*
X278067Y700583D01*
X278400Y700666D01*
X278733Y700583D01*
X279025Y700374D01*
X279150Y700083D01*
X279067Y699791D01*
X278858Y699583D01*
X278608Y699499D01*
X278192D01*
X277817Y699374D01*
X277567Y699124D01*
X277483Y698833D01*
X277567Y698541D01*
X277775Y698333D01*
X278108Y698208D01*
X278400Y698166D01*
G01X217542Y724267D02*
X217417Y724017D01*
X217334Y723725D01*
Y723392D01*
X217459Y723017D01*
X217667Y722725D01*
X217917Y722517D01*
X218334Y722350D01*
X218709Y722308D01*
X219084Y722392D01*
X219334Y722517D01*
X219584Y722767D01*
X219751Y723058D01*
X219834Y723350D01*
Y723642D01*
X219751Y723933D01*
X219626Y724183D01*
X219459Y724392D01*
G01X219834Y726450D02*
X217334D01*
X217834Y725950D01*
G01X219834D02*
Y726950D01*
G01X218792Y728758D02*
X218501Y729050D01*
X218334Y729300D01*
X218251Y729633D01*
X218334Y729925D01*
X218501Y730133D01*
X218751Y730300D01*
X219042Y730342D01*
X219292Y730300D01*
X219542Y730133D01*
X219751Y729883D01*
X219834Y729592D01*
X219751Y729258D01*
X219501Y728967D01*
X219126Y728800D01*
X218709Y728758D01*
X218167Y728842D01*
X217876Y728967D01*
X217584Y729175D01*
X217376Y729467D01*
X217334Y729758D01*
X217417Y730050D01*
X217626Y730258D01*
G01X219542Y731942D02*
X219751Y732233D01*
X219834Y732567D01*
X219751Y732900D01*
X219501Y733192D01*
X219126Y733400D01*
X218751Y733483D01*
X218292D01*
X217917Y733400D01*
X217584Y733192D01*
X217417Y732942D01*
X217334Y732650D01*
X217417Y732317D01*
X217584Y732067D01*
X217834Y731900D01*
X218167Y731817D01*
X218459Y731900D01*
X218751Y732108D01*
X218917Y732358D01*
X218959Y732650D01*
X218876Y732983D01*
X218667Y733233D01*
X218292Y733483D01*
G01X237417Y709059D02*
X237167Y709184D01*
X236875Y709267D01*
X236542D01*
X236167Y709142D01*
X235875Y708934D01*
X235667Y708684D01*
X235500Y708267D01*
X235458Y707892D01*
X235542Y707517D01*
X235667Y707267D01*
X235917Y707017D01*
X236208Y706850D01*
X236500Y706767D01*
X236792D01*
X237083Y706850D01*
X237333Y706975D01*
X237542Y707142D01*
G01X238683Y707267D02*
X238933Y706975D01*
X239267Y706809D01*
X239642Y706767D01*
X239975Y706809D01*
X240308Y707017D01*
X240517Y707267D01*
X240558Y707517D01*
X240475Y707809D01*
X240183Y708017D01*
X239892Y708100D01*
X239517D01*
G01X239892D02*
X240142Y708225D01*
X240350Y708434D01*
X240433Y708684D01*
X240350Y708934D01*
X240142Y709142D01*
X239767Y709267D01*
X239392Y709225D01*
X239017Y709059D01*
G01X243200Y706767D02*
Y709267D01*
X241658Y707475D01*
X243742D01*
G01X239717Y700259D02*
X239467Y700384D01*
X239175Y700467D01*
X238842D01*
X238467Y700342D01*
X238175Y700134D01*
X237967Y699884D01*
X237800Y699467D01*
X237758Y699092D01*
X237842Y698717D01*
X237967Y698467D01*
X238217Y698217D01*
X238508Y698050D01*
X238800Y697967D01*
X239092D01*
X239383Y698050D01*
X239633Y698175D01*
X239842Y698342D01*
G01X240983Y698467D02*
X241233Y698175D01*
X241567Y698009D01*
X241942Y697967D01*
X242275Y698009D01*
X242608Y698217D01*
X242817Y698467D01*
X242858Y698717D01*
X242775Y699009D01*
X242483Y699217D01*
X242192Y699300D01*
X241817D01*
G01X242192D02*
X242442Y699425D01*
X242650Y699634D01*
X242733Y699884D01*
X242650Y700134D01*
X242442Y700342D01*
X242067Y700467D01*
X241692Y700425D01*
X241317Y700259D01*
G01X245000Y697967D02*
X245292Y698009D01*
X245625Y698134D01*
X245833Y698342D01*
X245917Y698634D01*
X245833Y698925D01*
X245583Y699175D01*
X245208Y699300D01*
X244792D01*
X244542Y699384D01*
X244333Y699592D01*
X244250Y699884D01*
X244375Y700175D01*
X244667Y700384D01*
X245000Y700467D01*
X245333Y700384D01*
X245625Y700175D01*
X245750Y699884D01*
X245667Y699592D01*
X245458Y699384D01*
X245208Y699300D01*
X244792D01*
X244417Y699175D01*
X244167Y698925D01*
X244083Y698634D01*
X244167Y698342D01*
X244375Y698134D01*
X244708Y698009D01*
X245000Y697967D01*
G01X213542Y724267D02*
X213417Y724017D01*
X213334Y723725D01*
Y723392D01*
X213459Y723017D01*
X213667Y722725D01*
X213917Y722517D01*
X214334Y722350D01*
X214709Y722308D01*
X215084Y722392D01*
X215334Y722517D01*
X215584Y722767D01*
X215751Y723058D01*
X215834Y723350D01*
Y723642D01*
X215751Y723933D01*
X215626Y724183D01*
X215459Y724392D01*
G01X215834Y726450D02*
X213334D01*
X213834Y725950D01*
G01X215834D02*
Y726950D01*
G01Y729467D02*
X215292Y729550D01*
X214834Y729675D01*
X214417Y729842D01*
X213959Y730050D01*
X213334Y730383D01*
Y728717D01*
G01X213751Y731858D02*
X213501Y732108D01*
X213376Y732400D01*
X213334Y732733D01*
X213417Y733150D01*
X213626Y733442D01*
X213876Y733525D01*
X214126Y733483D01*
X214334Y733317D01*
X214751Y732483D01*
X215042Y732108D01*
X215459Y731858D01*
X215834Y731775D01*
Y733525D01*
G01X209542Y724267D02*
X209417Y724017D01*
X209334Y723725D01*
Y723392D01*
X209459Y723017D01*
X209667Y722725D01*
X209917Y722517D01*
X210334Y722350D01*
X210709Y722308D01*
X211084Y722392D01*
X211334Y722517D01*
X211584Y722767D01*
X211751Y723058D01*
X211834Y723350D01*
Y723642D01*
X211751Y723933D01*
X211626Y724183D01*
X211459Y724392D01*
G01X211834Y726450D02*
X209334D01*
X209834Y725950D01*
G01X211834D02*
Y726950D01*
G01Y729467D02*
X211292Y729550D01*
X210834Y729675D01*
X210417Y729842D01*
X209959Y730050D01*
X209334Y730383D01*
Y728717D01*
G01X211834Y733150D02*
X209334D01*
X211126Y731608D01*
Y733692D01*
G01X222217Y662367D02*
Y664867D01*
X223258D01*
X223592Y664742D01*
X223800Y664575D01*
X223883Y664242D01*
X223800Y663909D01*
X223550Y663700D01*
X223258Y663575D01*
X222217D01*
G01X223258D02*
X223883Y662367D01*
G01X226150D02*
Y664867D01*
X225650Y664367D01*
G01Y662367D02*
X226650D01*
G01X228542Y662659D02*
X228833Y662450D01*
X229167Y662367D01*
X229500Y662450D01*
X229792Y662700D01*
X230000Y663075D01*
X230083Y663450D01*
Y663909D01*
X230000Y664284D01*
X229792Y664617D01*
X229542Y664784D01*
X229250Y664867D01*
X228917Y664784D01*
X228667Y664617D01*
X228500Y664367D01*
X228417Y664034D01*
X228500Y663742D01*
X228708Y663450D01*
X228958Y663284D01*
X229250Y663242D01*
X229583Y663325D01*
X229833Y663534D01*
X230083Y663909D01*
G01X232267Y662367D02*
X232350Y662909D01*
X232475Y663367D01*
X232642Y663784D01*
X232850Y664242D01*
X233183Y664867D01*
X231517D01*
G01X270020Y720920D02*
Y716920D01*
X277420D01*
G01X272600Y721500D02*
Y725500D01*
X265200D01*
G01X217967Y696367D02*
Y698867D01*
X219008D01*
X219342Y698742D01*
X219550Y698575D01*
X219633Y698242D01*
X219550Y697909D01*
X219300Y697700D01*
X219008Y697575D01*
X217967D01*
G01X219008D02*
X219633Y696367D01*
G01X221817D02*
X221900Y696909D01*
X222025Y697367D01*
X222192Y697784D01*
X222400Y698242D01*
X222733Y698867D01*
X221067D01*
G01X225000Y696367D02*
Y698867D01*
X224500Y698367D01*
G01Y696367D02*
X225500D01*
G01X249900Y674300D02*
X253900D01*
Y681700D01*
G01X244900Y681100D02*
X240900D01*
Y673700D01*
G01X224167Y702067D02*
Y704567D01*
X225208D01*
X225542Y704442D01*
X225750Y704275D01*
X225833Y703942D01*
X225750Y703609D01*
X225500Y703400D01*
X225208Y703275D01*
X224167D01*
G01X225208D02*
X225833Y702067D01*
G01X228017D02*
X228100Y702609D01*
X228225Y703067D01*
X228392Y703484D01*
X228600Y703942D01*
X228933Y704567D01*
X227267D01*
G01X230283Y702442D02*
X230533Y702234D01*
X230825Y702109D01*
X231200Y702067D01*
X231575Y702150D01*
X231867Y702317D01*
X232075Y702609D01*
X232117Y702942D01*
X232033Y703275D01*
X231825Y703484D01*
X231533Y703650D01*
X231242Y703692D01*
X230950Y703650D01*
X230575Y703484D01*
X230700Y704567D01*
X231825D01*
G01X236936Y661469D02*
X240936D01*
Y668869D01*
G01X225967Y706867D02*
Y709367D01*
X227008D01*
X227342Y709242D01*
X227550Y709075D01*
X227633Y708742D01*
X227550Y708409D01*
X227300Y708200D01*
X227008Y708075D01*
X225967D01*
G01X227008D02*
X227633Y706867D01*
G01X229817D02*
X229900Y707409D01*
X230025Y707867D01*
X230192Y708284D01*
X230400Y708742D01*
X230733Y709367D01*
X229067D01*
G01X233000Y706867D02*
X233292Y706909D01*
X233625Y707034D01*
X233833Y707242D01*
X233917Y707534D01*
X233833Y707825D01*
X233583Y708075D01*
X233208Y708200D01*
X232792D01*
X232542Y708284D01*
X232333Y708492D01*
X232250Y708784D01*
X232375Y709075D01*
X232667Y709284D01*
X233000Y709367D01*
X233333Y709284D01*
X233625Y709075D01*
X233750Y708784D01*
X233667Y708492D01*
X233458Y708284D01*
X233208Y708200D01*
X232792D01*
X232417Y708075D01*
X232167Y707825D01*
X232083Y707534D01*
X232167Y707242D01*
X232375Y707034D01*
X232708Y706909D01*
X233000Y706867D01*
G01X256500Y673800D02*
X260500D01*
Y681200D01*
G01X276234Y671267D02*
X273734D01*
Y672308D01*
X273859Y672642D01*
X274026Y672850D01*
X274359Y672933D01*
X274692Y672850D01*
X274901Y672600D01*
X275026Y672308D01*
Y671267D01*
G01Y672308D02*
X276234Y672933D01*
G01Y675117D02*
X275692Y675200D01*
X275234Y675325D01*
X274817Y675492D01*
X274359Y675700D01*
X273734Y676033D01*
Y674367D01*
G01X275942Y677592D02*
X276151Y677883D01*
X276234Y678217D01*
X276151Y678550D01*
X275901Y678842D01*
X275526Y679050D01*
X275151Y679133D01*
X274692D01*
X274317Y679050D01*
X273984Y678842D01*
X273817Y678592D01*
X273734Y678300D01*
X273817Y677967D01*
X273984Y677717D01*
X274234Y677550D01*
X274567Y677467D01*
X274859Y677550D01*
X275151Y677758D01*
X275317Y678008D01*
X275359Y678300D01*
X275276Y678633D01*
X275067Y678883D01*
X274692Y679133D01*
G01X264800Y665600D02*
X268800D01*
Y673000D01*
G01X240234Y688167D02*
X237734D01*
Y689208D01*
X237859Y689542D01*
X238026Y689750D01*
X238359Y689833D01*
X238692Y689750D01*
X238901Y689500D01*
X239026Y689208D01*
Y688167D01*
G01Y689208D02*
X240234Y689833D01*
G01Y692100D02*
X240192Y692392D01*
X240067Y692725D01*
X239859Y692933D01*
X239567Y693017D01*
X239276Y692933D01*
X239026Y692683D01*
X238901Y692308D01*
Y691892D01*
X238817Y691642D01*
X238609Y691433D01*
X238317Y691350D01*
X238026Y691475D01*
X237817Y691767D01*
X237734Y692100D01*
X237817Y692433D01*
X238026Y692725D01*
X238317Y692850D01*
X238609Y692767D01*
X238817Y692558D01*
X238901Y692308D01*
Y691892D01*
X239026Y691517D01*
X239276Y691267D01*
X239567Y691183D01*
X239859Y691267D01*
X240067Y691475D01*
X240192Y691808D01*
X240234Y692100D01*
G01X237734Y695200D02*
X237817Y694867D01*
X238026Y694617D01*
X238276Y694450D01*
X238609Y694325D01*
X238984Y694283D01*
X239359Y694325D01*
X239692Y694450D01*
X239942Y694617D01*
X240151Y694867D01*
X240234Y695200D01*
X240151Y695533D01*
X239942Y695783D01*
X239692Y695950D01*
X239359Y696075D01*
X238984Y696117D01*
X238609Y696075D01*
X238276Y695950D01*
X238026Y695783D01*
X237817Y695533D01*
X237734Y695200D01*
G01X256319Y664209D02*
Y660209D01*
X263719D01*
G01X259634Y722167D02*
X257134D01*
Y723208D01*
X257259Y723542D01*
X257426Y723750D01*
X257759Y723833D01*
X258092Y723750D01*
X258301Y723500D01*
X258426Y723208D01*
Y722167D01*
G01Y723208D02*
X259634Y723833D01*
G01Y726100D02*
X259592Y726392D01*
X259467Y726725D01*
X259259Y726933D01*
X258967Y727017D01*
X258676Y726933D01*
X258426Y726683D01*
X258301Y726308D01*
Y725892D01*
X258217Y725642D01*
X258009Y725433D01*
X257717Y725350D01*
X257426Y725475D01*
X257217Y725767D01*
X257134Y726100D01*
X257217Y726433D01*
X257426Y726725D01*
X257717Y726850D01*
X258009Y726767D01*
X258217Y726558D01*
X258301Y726308D01*
Y725892D01*
X258426Y725517D01*
X258676Y725267D01*
X258967Y725183D01*
X259259Y725267D01*
X259467Y725475D01*
X259592Y725808D01*
X259634Y726100D01*
G01Y729200D02*
X257134D01*
X257634Y728700D01*
G01X259634D02*
Y729700D01*
G01X260431Y709890D02*
X256431D01*
Y702490D01*
G01X263634Y721667D02*
X261134D01*
Y722708D01*
X261259Y723042D01*
X261426Y723250D01*
X261759Y723333D01*
X262092Y723250D01*
X262301Y723000D01*
X262426Y722708D01*
Y721667D01*
G01Y722708D02*
X263634Y723333D01*
G01Y725600D02*
X263592Y725892D01*
X263467Y726225D01*
X263259Y726433D01*
X262967Y726517D01*
X262676Y726433D01*
X262426Y726183D01*
X262301Y725808D01*
Y725392D01*
X262217Y725142D01*
X262009Y724933D01*
X261717Y724850D01*
X261426Y724975D01*
X261217Y725267D01*
X261134Y725600D01*
X261217Y725933D01*
X261426Y726225D01*
X261717Y726350D01*
X262009Y726267D01*
X262217Y726058D01*
X262301Y725808D01*
Y725392D01*
X262426Y725017D01*
X262676Y724767D01*
X262967Y724683D01*
X263259Y724767D01*
X263467Y724975D01*
X263592Y725308D01*
X263634Y725600D01*
G01X261551Y727908D02*
X261301Y728158D01*
X261176Y728450D01*
X261134Y728783D01*
X261217Y729200D01*
X261426Y729492D01*
X261676Y729575D01*
X261926Y729533D01*
X262134Y729367D01*
X262551Y728533D01*
X262842Y728158D01*
X263259Y727908D01*
X263634Y727825D01*
Y729575D01*
G01X260645Y702501D02*
X264645D01*
Y709901D01*
G01X268900Y668600D02*
X272900D01*
Y676000D01*
G01X256034Y722217D02*
X253534D01*
Y723258D01*
X253659Y723592D01*
X253826Y723800D01*
X254159Y723883D01*
X254492Y723800D01*
X254701Y723550D01*
X254826Y723258D01*
Y722217D01*
G01Y723258D02*
X256034Y723883D01*
G01X255534Y725233D02*
X255826Y725483D01*
X255992Y725817D01*
X256034Y726192D01*
X255992Y726525D01*
X255784Y726858D01*
X255534Y727067D01*
X255284Y727108D01*
X254992Y727025D01*
X254784Y726733D01*
X254701Y726442D01*
Y726067D01*
G01Y726442D02*
X254576Y726692D01*
X254367Y726900D01*
X254117Y726983D01*
X253867Y726900D01*
X253659Y726692D01*
X253534Y726317D01*
X253576Y725942D01*
X253742Y725567D01*
G01X255659Y728333D02*
X255867Y728583D01*
X255992Y728875D01*
X256034Y729250D01*
X255951Y729625D01*
X255784Y729917D01*
X255492Y730125D01*
X255159Y730167D01*
X254826Y730083D01*
X254617Y729875D01*
X254451Y729583D01*
X254409Y729292D01*
X254451Y729000D01*
X254617Y728625D01*
X253534Y728750D01*
Y729875D01*
G01X254992Y731558D02*
X254701Y731850D01*
X254534Y732100D01*
X254451Y732433D01*
X254534Y732725D01*
X254701Y732933D01*
X254951Y733100D01*
X255242Y733142D01*
X255492Y733100D01*
X255742Y732933D01*
X255951Y732683D01*
X256034Y732392D01*
X255951Y732058D01*
X255701Y731767D01*
X255326Y731600D01*
X254909Y731558D01*
X254367Y731642D01*
X254076Y731767D01*
X253784Y731975D01*
X253576Y732267D01*
X253534Y732558D01*
X253617Y732850D01*
X253826Y733058D01*
G01X251842Y712710D02*
X247842D01*
Y705310D01*
G01X258183Y719967D02*
Y718175D01*
X258350Y717800D01*
X258683Y717550D01*
X259100Y717467D01*
X259517Y717550D01*
X259850Y717800D01*
X260017Y718175D01*
Y719967D01*
G01X262200Y717467D02*
Y719967D01*
X261700Y719467D01*
G01Y717467D02*
X262700D01*
G01X265300Y719967D02*
X264967Y719884D01*
X264717Y719675D01*
X264550Y719425D01*
X264425Y719092D01*
X264383Y718717D01*
X264425Y718342D01*
X264550Y718009D01*
X264717Y717759D01*
X264967Y717550D01*
X265300Y717467D01*
X265633Y717550D01*
X265883Y717759D01*
X266050Y718009D01*
X266175Y718342D01*
X266217Y718717D01*
X266175Y719092D01*
X266050Y719425D01*
X265883Y719675D01*
X265633Y719884D01*
X265300Y719967D01*
G01X255931Y682624D02*
Y696024D01*
G01X265931Y682624D02*
X255931D01*
G01X265931Y696024D02*
Y682624D01*
G01X255931Y696024D02*
X265931D01*
G01X213533Y702967D02*
Y701175D01*
X213700Y700800D01*
X214033Y700550D01*
X214450Y700467D01*
X214867Y700550D01*
X215200Y700800D01*
X215367Y701175D01*
Y702967D01*
G01X216842Y700759D02*
X217133Y700550D01*
X217467Y700467D01*
X217800Y700550D01*
X218092Y700800D01*
X218300Y701175D01*
X218383Y701550D01*
Y702009D01*
X218300Y702384D01*
X218092Y702717D01*
X217842Y702884D01*
X217550Y702967D01*
X217217Y702884D01*
X216967Y702717D01*
X216800Y702467D01*
X216717Y702134D01*
X216800Y701842D01*
X217008Y701550D01*
X217258Y701384D01*
X217550Y701342D01*
X217883Y701425D01*
X218133Y701634D01*
X218383Y702009D01*
G01X243531Y682824D02*
Y696224D01*
G01X253531Y682824D02*
X243531D01*
G01X253531Y696224D02*
Y682824D01*
G01X243531Y696224D02*
X253531D01*
G01X262283Y700667D02*
Y698875D01*
X262450Y698500D01*
X262783Y698250D01*
X263200Y698167D01*
X263617Y698250D01*
X263950Y698500D01*
X264117Y698875D01*
Y700667D01*
G01X265383Y698667D02*
X265633Y698375D01*
X265967Y698209D01*
X266342Y698167D01*
X266675Y698209D01*
X267008Y698417D01*
X267217Y698667D01*
X267258Y698917D01*
X267175Y699209D01*
X266883Y699417D01*
X266592Y699500D01*
X266217D01*
G01X266592D02*
X266842Y699625D01*
X267050Y699834D01*
X267133Y700084D01*
X267050Y700334D01*
X266842Y700542D01*
X266467Y700667D01*
X266092Y700625D01*
X265717Y700459D01*
G01X269400Y698167D02*
Y700667D01*
X268900Y700167D01*
G01Y698167D02*
X269900D01*
G01X268800Y696300D02*
X278800D01*
G01X268800Y682900D02*
Y696300D01*
G01X278800Y682900D02*
X268800D01*
G01X236034Y700650D02*
X235992Y700317D01*
X235826Y700025D01*
X235576Y699775D01*
X235284Y699608D01*
X234951Y699525D01*
X234617D01*
X234284Y699608D01*
X233992Y699775D01*
X233742Y700025D01*
X233576Y700317D01*
X233534Y700650D01*
X233576Y700983D01*
X233742Y701275D01*
X233992Y701525D01*
X234284Y701692D01*
X234617Y701775D01*
X234951D01*
X235284Y701692D01*
X235576Y701525D01*
X235826Y701275D01*
X235992Y700983D01*
X236034Y700650D01*
G01X235367Y700983D02*
X236034Y701483D01*
G01Y704250D02*
X233534D01*
X235326Y702708D01*
Y704792D01*
G01X241500Y660000D02*
X255500D01*
G01X241500Y673000D02*
Y660000D01*
G01X255500Y673000D02*
X241500D01*
G01X255500Y660000D02*
Y673000D01*
G01X239117Y704759D02*
X238867Y704884D01*
X238575Y704967D01*
X238242D01*
X237867Y704842D01*
X237575Y704634D01*
X237367Y704384D01*
X237200Y703967D01*
X237158Y703592D01*
X237242Y703217D01*
X237367Y702967D01*
X237617Y702717D01*
X237908Y702550D01*
X238200Y702467D01*
X238492D01*
X238783Y702550D01*
X239033Y702675D01*
X239242Y702842D01*
G01X240383Y702967D02*
X240633Y702675D01*
X240967Y702509D01*
X241342Y702467D01*
X241675Y702509D01*
X242008Y702717D01*
X242217Y702967D01*
X242258Y703217D01*
X242175Y703509D01*
X241883Y703717D01*
X241592Y703800D01*
X241217D01*
G01X241592D02*
X241842Y703925D01*
X242050Y704134D01*
X242133Y704384D01*
X242050Y704634D01*
X241842Y704842D01*
X241467Y704967D01*
X241092Y704925D01*
X240717Y704759D01*
G01X243483Y702842D02*
X243733Y702634D01*
X244025Y702509D01*
X244400Y702467D01*
X244775Y702550D01*
X245067Y702717D01*
X245275Y703009D01*
X245317Y703342D01*
X245233Y703675D01*
X245025Y703884D01*
X244733Y704050D01*
X244442Y704092D01*
X244150Y704050D01*
X243775Y703884D01*
X243900Y704967D01*
X245025D01*
G01X246499Y722747D02*
Y714747D01*
X228899D01*
Y722747D01*
X246499D01*
G01X270500Y659000D02*
X256500D01*
G01X255500D02*
X241500D01*
G01X270200Y667100D02*
X286300D01*
G01X270200Y660100D02*
Y667100D01*
G01X286300Y660100D02*
X270200D01*
G01X212250Y747633D02*
X215750Y752633D01*
G01X212250D02*
X215750Y747633D01*
G01X218017Y751800D02*
X218517Y752300D01*
X219100Y752550D01*
X219767Y752633D01*
X220600Y752466D01*
X221183Y752050D01*
X221350Y751550D01*
X221267Y751050D01*
X220933Y750633D01*
X219267Y749800D01*
X218517Y749216D01*
X218017Y748383D01*
X217850Y747633D01*
X221350D01*
G01X225200Y747466D02*
X225033Y747550D01*
Y747716D01*
X225200Y747800D01*
X225367Y747716D01*
Y747550D01*
X225200Y747466D01*
G01Y749716D02*
X225033Y749800D01*
Y749966D01*
X225200Y750050D01*
X225367Y749966D01*
Y749800D01*
X225200Y749716D01*
G01X228967Y748383D02*
X229467Y747966D01*
X230050Y747716D01*
X230800Y747633D01*
X231550Y747800D01*
X232133Y748133D01*
X232550Y748716D01*
X232633Y749383D01*
X232467Y750050D01*
X232050Y750466D01*
X231467Y750800D01*
X230883Y750883D01*
X230300Y750800D01*
X229550Y750466D01*
X229800Y752633D01*
X232050D01*
G01X236400D02*
X235733Y752466D01*
X235233Y752050D01*
X234900Y751550D01*
X234650Y750883D01*
X234567Y750133D01*
X234650Y749383D01*
X234900Y748716D01*
X235233Y748216D01*
X235733Y747800D01*
X236400Y747633D01*
X237067Y747800D01*
X237567Y748216D01*
X237900Y748716D01*
X238150Y749383D01*
X238233Y750133D01*
X238150Y750883D01*
X237900Y751550D01*
X237567Y752050D01*
X237067Y752466D01*
X236400Y752633D01*
G01X239833Y747633D02*
Y752633D01*
X242000Y748466D01*
X244167Y752633D01*
Y747633D01*
G01X245850D02*
Y752633D01*
G01X249350D02*
Y747633D01*
G01Y750133D02*
X245850D01*
G01X251617Y752633D02*
X254783D01*
X251617Y747633D01*
X254783D01*
G01X265467Y736058D02*
X265217Y736183D01*
X264925Y736266D01*
X264592D01*
X264217Y736141D01*
X263925Y735933D01*
X263717Y735683D01*
X263550Y735266D01*
X263508Y734891D01*
X263592Y734516D01*
X263717Y734266D01*
X263967Y734016D01*
X264258Y733849D01*
X264550Y733766D01*
X264842D01*
X265133Y733849D01*
X265383Y733974D01*
X265592Y734141D01*
G01X267650Y733766D02*
Y736266D01*
X267150Y735766D01*
G01Y733766D02*
X268150D01*
G01X270042Y734058D02*
X270333Y733849D01*
X270667Y733766D01*
X271000Y733849D01*
X271292Y734099D01*
X271500Y734474D01*
X271583Y734849D01*
Y735308D01*
X271500Y735683D01*
X271292Y736016D01*
X271042Y736183D01*
X270750Y736266D01*
X270417Y736183D01*
X270167Y736016D01*
X270000Y735766D01*
X269917Y735433D01*
X270000Y735141D01*
X270208Y734849D01*
X270458Y734683D01*
X270750Y734641D01*
X271083Y734724D01*
X271333Y734933D01*
X271583Y735308D01*
G01X273058Y734808D02*
X273350Y735099D01*
X273600Y735266D01*
X273933Y735349D01*
X274225Y735266D01*
X274433Y735099D01*
X274600Y734849D01*
X274642Y734558D01*
X274600Y734308D01*
X274433Y734058D01*
X274183Y733849D01*
X273892Y733766D01*
X273558Y733849D01*
X273267Y734099D01*
X273100Y734474D01*
X273058Y734891D01*
X273142Y735433D01*
X273267Y735724D01*
X273475Y736016D01*
X273767Y736224D01*
X274058Y736266D01*
X274350Y736183D01*
X274558Y735974D01*
G01X262367Y741159D02*
X262117Y741284D01*
X261825Y741367D01*
X261492D01*
X261117Y741242D01*
X260825Y741034D01*
X260617Y740784D01*
X260450Y740367D01*
X260408Y739992D01*
X260492Y739617D01*
X260617Y739367D01*
X260867Y739117D01*
X261158Y738950D01*
X261450Y738867D01*
X261742D01*
X262033Y738950D01*
X262283Y739075D01*
X262492Y739242D01*
G01X263758Y740950D02*
X264008Y741200D01*
X264300Y741325D01*
X264633Y741367D01*
X265050Y741284D01*
X265342Y741075D01*
X265425Y740825D01*
X265383Y740575D01*
X265217Y740367D01*
X264383Y739950D01*
X264008Y739659D01*
X263758Y739242D01*
X263675Y738867D01*
X265425D01*
G01X267650Y741367D02*
X267317Y741284D01*
X267067Y741075D01*
X266900Y740825D01*
X266775Y740492D01*
X266733Y740117D01*
X266775Y739742D01*
X266900Y739409D01*
X267067Y739159D01*
X267317Y738950D01*
X267650Y738867D01*
X267983Y738950D01*
X268233Y739159D01*
X268400Y739409D01*
X268525Y739742D01*
X268567Y740117D01*
X268525Y740492D01*
X268400Y740825D01*
X268233Y741075D01*
X267983Y741284D01*
X267650Y741367D01*
G01X270750Y738867D02*
Y741367D01*
X270250Y740867D01*
G01Y738867D02*
X271250D01*
G01X260417Y742967D02*
Y745467D01*
X261458D01*
X261792Y745342D01*
X262000Y745175D01*
X262083Y744842D01*
X262000Y744509D01*
X261750Y744300D01*
X261458Y744175D01*
X260417D01*
G01X261458D02*
X262083Y742967D01*
G01X263433Y743342D02*
X263683Y743134D01*
X263975Y743009D01*
X264350Y742967D01*
X264725Y743050D01*
X265017Y743217D01*
X265225Y743509D01*
X265267Y743842D01*
X265183Y744175D01*
X264975Y744384D01*
X264683Y744550D01*
X264392Y744592D01*
X264100Y744550D01*
X263725Y744384D01*
X263850Y745467D01*
X264975D01*
G01X267450D02*
X267117Y745384D01*
X266867Y745175D01*
X266700Y744925D01*
X266575Y744592D01*
X266533Y744217D01*
X266575Y743842D01*
X266700Y743509D01*
X266867Y743259D01*
X267117Y743050D01*
X267450Y742967D01*
X267783Y743050D01*
X268033Y743259D01*
X268200Y743509D01*
X268325Y743842D01*
X268367Y744217D01*
X268325Y744592D01*
X268200Y744925D01*
X268033Y745175D01*
X267783Y745384D01*
X267450Y745467D01*
G01X269842Y743259D02*
X270133Y743050D01*
X270467Y742967D01*
X270800Y743050D01*
X271092Y743300D01*
X271300Y743675D01*
X271383Y744050D01*
Y744509D01*
X271300Y744884D01*
X271092Y745217D01*
X270842Y745384D01*
X270550Y745467D01*
X270217Y745384D01*
X269967Y745217D01*
X269800Y744967D01*
X269717Y744634D01*
X269800Y744342D01*
X270008Y744050D01*
X270258Y743884D01*
X270550Y743842D01*
X270883Y743925D01*
X271133Y744134D01*
X271383Y744509D01*
G01X259317Y747467D02*
Y749967D01*
X260358D01*
X260692Y749842D01*
X260900Y749675D01*
X260983Y749342D01*
X260900Y749009D01*
X260650Y748800D01*
X260358Y748675D01*
X259317D01*
G01X260358D02*
X260983Y747467D01*
G01X262333Y747842D02*
X262583Y747634D01*
X262875Y747509D01*
X263250Y747467D01*
X263625Y747550D01*
X263917Y747717D01*
X264125Y748009D01*
X264167Y748342D01*
X264083Y748675D01*
X263875Y748884D01*
X263583Y749050D01*
X263292Y749092D01*
X263000Y749050D01*
X262625Y748884D01*
X262750Y749967D01*
X263875D01*
G01X266350Y747467D02*
Y749967D01*
X265850Y749467D01*
G01Y747467D02*
X266850D01*
G01X269450Y749967D02*
X269117Y749884D01*
X268867Y749675D01*
X268700Y749425D01*
X268575Y749092D01*
X268533Y748717D01*
X268575Y748342D01*
X268700Y748009D01*
X268867Y747759D01*
X269117Y747550D01*
X269450Y747467D01*
X269783Y747550D01*
X270033Y747759D01*
X270200Y748009D01*
X270325Y748342D01*
X270367Y748717D01*
X270325Y749092D01*
X270200Y749425D01*
X270033Y749675D01*
X269783Y749884D01*
X269450Y749967D01*
G01X273042Y740667D02*
X272917Y740417D01*
X272834Y740125D01*
Y739792D01*
X272959Y739417D01*
X273167Y739125D01*
X273417Y738917D01*
X273834Y738750D01*
X274209Y738708D01*
X274584Y738792D01*
X274834Y738917D01*
X275084Y739167D01*
X275251Y739458D01*
X275334Y739750D01*
Y740042D01*
X275251Y740333D01*
X275126Y740583D01*
X274959Y740792D01*
G01X275334Y742850D02*
X272834D01*
X273334Y742350D01*
G01X275334D02*
Y743350D01*
G01X275042Y745242D02*
X275251Y745533D01*
X275334Y745867D01*
X275251Y746200D01*
X275001Y746492D01*
X274626Y746700D01*
X274251Y746783D01*
X273792D01*
X273417Y746700D01*
X273084Y746492D01*
X272917Y746242D01*
X272834Y745950D01*
X272917Y745617D01*
X273084Y745367D01*
X273334Y745200D01*
X273667Y745117D01*
X273959Y745200D01*
X274251Y745408D01*
X274417Y745658D01*
X274459Y745950D01*
X274376Y746283D01*
X274167Y746533D01*
X273792Y746783D01*
G01X275334Y748967D02*
X274792Y749050D01*
X274334Y749175D01*
X273917Y749342D01*
X273459Y749550D01*
X272834Y749883D01*
Y748217D01*
G01X246499Y741947D02*
Y733947D01*
X228899D01*
Y741947D01*
X246499D01*
G01Y732347D02*
Y724347D01*
X228899D01*
Y732347D01*
X246499D01*
G01X363650Y0D02*
Y-3197D01*
X336350D01*
G01X363650Y0D02*
X336350D01*
Y44003D01*
X335350D01*
Y55603D01*
X336350D01*
Y87503D01*
X335350D01*
Y100203D01*
X364650D01*
Y86103D01*
X363650D01*
Y54253D01*
X364650D01*
Y45353D01*
X363650D01*
Y0D01*
G01X336350Y-3197D02*
Y0D01*
G01X327768Y68342D02*
X329560D01*
X329935Y68509D01*
X330185Y68842D01*
X330268Y69259D01*
X330185Y69676D01*
X329935Y70009D01*
X329560Y70176D01*
X327768D01*
G01X329935Y71484D02*
X330143Y71817D01*
X330268Y72192D01*
Y72526D01*
X330143Y72859D01*
X329935Y73109D01*
X329643Y73234D01*
X329351Y73151D01*
X329101Y72942D01*
X328935Y72567D01*
X328851Y72067D01*
X328685Y71776D01*
X328393Y71651D01*
X328101Y71734D01*
X327893Y71942D01*
X327768Y72234D01*
Y72526D01*
X327851Y72817D01*
X328060Y73067D01*
G01X328935Y75792D02*
X328810Y75959D01*
X328601Y76084D01*
X328310Y76167D01*
X328060Y76084D01*
X327893Y75917D01*
X327768Y75626D01*
Y74501D01*
X330268D01*
Y75876D01*
X330101Y76167D01*
X329851Y76334D01*
X329560Y76417D01*
X329268Y76334D01*
X329018Y76084D01*
X328935Y75792D01*
Y74501D01*
G01X330268Y78559D02*
X327768D01*
X328268Y78059D01*
G01X330268D02*
Y79059D01*
G01X331333Y122039D02*
X331208Y121789D01*
X331125Y121497D01*
Y121164D01*
X331250Y120789D01*
X331458Y120497D01*
X331708Y120289D01*
X332125Y120122D01*
X332500Y120080D01*
X332875Y120164D01*
X333125Y120289D01*
X333375Y120539D01*
X333542Y120830D01*
X333625Y121122D01*
Y121414D01*
X333542Y121705D01*
X333417Y121955D01*
X333250Y122164D01*
G01X333625Y124222D02*
X331125D01*
X331625Y123722D01*
G01X333625D02*
Y124722D01*
G01X330667Y105800D02*
Y103300D01*
X332333D01*
G01X333808Y105383D02*
X334058Y105633D01*
X334350Y105758D01*
X334683Y105800D01*
X335100Y105717D01*
X335392Y105508D01*
X335475Y105258D01*
X335433Y105008D01*
X335267Y104800D01*
X334433Y104383D01*
X334058Y104092D01*
X333808Y103675D01*
X333725Y103300D01*
X335475D01*
G01X336783Y103800D02*
X337033Y103508D01*
X337367Y103342D01*
X337742Y103300D01*
X338075Y103342D01*
X338408Y103550D01*
X338617Y103800D01*
X338658Y104050D01*
X338575Y104342D01*
X338283Y104550D01*
X337992Y104633D01*
X337617D01*
G01X337992D02*
X338242Y104758D01*
X338450Y104967D01*
X338533Y105217D01*
X338450Y105467D01*
X338242Y105675D01*
X337867Y105800D01*
X337492Y105758D01*
X337117Y105592D01*
G01X335513Y112992D02*
X337305D01*
X337680Y113159D01*
X337930Y113492D01*
X338013Y113909D01*
X337930Y114326D01*
X337680Y114659D01*
X337305Y114826D01*
X335513D01*
G01X337721Y116301D02*
X337930Y116592D01*
X338013Y116926D01*
X337930Y117259D01*
X337680Y117551D01*
X337305Y117759D01*
X336930Y117842D01*
X336471D01*
X336096Y117759D01*
X335763Y117551D01*
X335596Y117301D01*
X335513Y117009D01*
X335596Y116676D01*
X335763Y116426D01*
X336013Y116259D01*
X336346Y116176D01*
X336638Y116259D01*
X336930Y116467D01*
X337096Y116717D01*
X337138Y117009D01*
X337055Y117342D01*
X336846Y117592D01*
X336471Y117842D01*
G01X338013Y120109D02*
X337971Y120401D01*
X337846Y120734D01*
X337638Y120942D01*
X337346Y121026D01*
X337055Y120942D01*
X336805Y120692D01*
X336680Y120317D01*
Y119901D01*
X336596Y119651D01*
X336388Y119442D01*
X336096Y119359D01*
X335805Y119484D01*
X335596Y119776D01*
X335513Y120109D01*
X335596Y120442D01*
X335805Y120734D01*
X336096Y120859D01*
X336388Y120776D01*
X336596Y120567D01*
X336680Y120317D01*
Y119901D01*
X336805Y119526D01*
X337055Y119276D01*
X337346Y119192D01*
X337638Y119276D01*
X337846Y119484D01*
X337971Y119817D01*
X338013Y120109D01*
G01X333870Y108627D02*
X331370D01*
Y109461D01*
X331495Y109794D01*
X331662Y110044D01*
X331912Y110252D01*
X332203Y110419D01*
X332620Y110461D01*
X333037Y110419D01*
X333328Y110252D01*
X333578Y110044D01*
X333745Y109794D01*
X333870Y109461D01*
Y108627D01*
G01Y112644D02*
X331370D01*
X331870Y112144D01*
G01X333870D02*
Y113144D01*
G01X333370Y114827D02*
X333662Y115077D01*
X333828Y115411D01*
X333870Y115786D01*
X333828Y116119D01*
X333620Y116452D01*
X333370Y116661D01*
X333120Y116702D01*
X332828Y116619D01*
X332620Y116327D01*
X332537Y116036D01*
Y115661D01*
G01Y116036D02*
X332412Y116286D01*
X332203Y116494D01*
X331953Y116577D01*
X331703Y116494D01*
X331495Y116286D01*
X331370Y115911D01*
X331412Y115536D01*
X331578Y115161D01*
G01X327067Y190166D02*
X326817Y190291D01*
X326525Y190374D01*
X326192D01*
X325817Y190249D01*
X325525Y190041D01*
X325317Y189791D01*
X325150Y189374D01*
X325108Y188999D01*
X325192Y188624D01*
X325317Y188374D01*
X325567Y188124D01*
X325858Y187957D01*
X326150Y187874D01*
X326442D01*
X326733Y187957D01*
X326983Y188082D01*
X327192Y188249D01*
G01X329250Y187874D02*
Y190374D01*
X328750Y189874D01*
G01Y187874D02*
X329750D01*
G01X332350D02*
X332642Y187916D01*
X332975Y188041D01*
X333183Y188249D01*
X333267Y188541D01*
X333183Y188832D01*
X332933Y189082D01*
X332558Y189207D01*
X332142D01*
X331892Y189291D01*
X331683Y189499D01*
X331600Y189791D01*
X331725Y190082D01*
X332017Y190291D01*
X332350Y190374D01*
X332683Y190291D01*
X332975Y190082D01*
X333100Y189791D01*
X333017Y189499D01*
X332808Y189291D01*
X332558Y189207D01*
X332142D01*
X331767Y189082D01*
X331517Y188832D01*
X331433Y188541D01*
X331517Y188249D01*
X331725Y188041D01*
X332058Y187916D01*
X332350Y187874D01*
G01X334742Y188166D02*
X335033Y187957D01*
X335367Y187874D01*
X335700Y187957D01*
X335992Y188207D01*
X336200Y188582D01*
X336283Y188957D01*
Y189416D01*
X336200Y189791D01*
X335992Y190124D01*
X335742Y190291D01*
X335450Y190374D01*
X335117Y190291D01*
X334867Y190124D01*
X334700Y189874D01*
X334617Y189541D01*
X334700Y189249D01*
X334908Y188957D01*
X335158Y188791D01*
X335450Y188749D01*
X335783Y188832D01*
X336033Y189041D01*
X336283Y189416D01*
G01X325346Y191678D02*
Y194178D01*
X326387D01*
X326721Y194053D01*
X326929Y193886D01*
X327012Y193553D01*
X326929Y193220D01*
X326679Y193011D01*
X326387Y192886D01*
X325346D01*
G01X326387D02*
X327012Y191678D01*
G01X328362Y192053D02*
X328612Y191845D01*
X328904Y191720D01*
X329279Y191678D01*
X329654Y191761D01*
X329946Y191928D01*
X330154Y192220D01*
X330196Y192553D01*
X330112Y192886D01*
X329904Y193095D01*
X329612Y193261D01*
X329321Y193303D01*
X329029Y193261D01*
X328654Y193095D01*
X328779Y194178D01*
X329904D01*
G01X332379D02*
X332046Y194095D01*
X331796Y193886D01*
X331629Y193636D01*
X331504Y193303D01*
X331462Y192928D01*
X331504Y192553D01*
X331629Y192220D01*
X331796Y191970D01*
X332046Y191761D01*
X332379Y191678D01*
X332712Y191761D01*
X332962Y191970D01*
X333129Y192220D01*
X333254Y192553D01*
X333296Y192928D01*
X333254Y193303D01*
X333129Y193636D01*
X332962Y193886D01*
X332712Y194095D01*
X332379Y194178D01*
G01X334562Y192178D02*
X334812Y191886D01*
X335146Y191720D01*
X335521Y191678D01*
X335854Y191720D01*
X336187Y191928D01*
X336396Y192178D01*
X336437Y192428D01*
X336354Y192720D01*
X336062Y192928D01*
X335771Y193011D01*
X335396D01*
G01X335771D02*
X336021Y193136D01*
X336229Y193345D01*
X336312Y193595D01*
X336229Y193845D01*
X336021Y194053D01*
X335646Y194178D01*
X335271Y194136D01*
X334896Y193970D01*
G01X340229Y195678D02*
Y191678D01*
X347629D01*
G01X340651Y167984D02*
X338151D01*
Y169025D01*
X338276Y169359D01*
X338443Y169567D01*
X338776Y169650D01*
X339109Y169567D01*
X339318Y169317D01*
X339443Y169025D01*
Y167984D01*
G01Y169025D02*
X340651Y169650D01*
G01Y171917D02*
X338151D01*
X338651Y171417D01*
G01X340651D02*
Y172417D01*
G01X339609Y174225D02*
X339318Y174517D01*
X339151Y174767D01*
X339068Y175100D01*
X339151Y175392D01*
X339318Y175600D01*
X339568Y175767D01*
X339859Y175809D01*
X340109Y175767D01*
X340359Y175600D01*
X340568Y175350D01*
X340651Y175059D01*
X340568Y174725D01*
X340318Y174434D01*
X339943Y174267D01*
X339526Y174225D01*
X338984Y174309D01*
X338693Y174434D01*
X338401Y174642D01*
X338193Y174934D01*
X338151Y175225D01*
X338234Y175517D01*
X338443Y175725D01*
G01X341851Y184917D02*
X337851D01*
Y177517D01*
G01X292106Y392530D02*
Y178730D01*
X319706D01*
Y392530D01*
X292106D01*
G01X327864Y227692D02*
Y230192D01*
X328905D01*
X329239Y230067D01*
X329447Y229900D01*
X329530Y229567D01*
X329447Y229234D01*
X329197Y229025D01*
X328905Y228900D01*
X327864D01*
G01X328905D02*
X329530Y227692D01*
G01X330880Y228192D02*
X331130Y227900D01*
X331464Y227734D01*
X331839Y227692D01*
X332172Y227734D01*
X332505Y227942D01*
X332714Y228192D01*
X332755Y228442D01*
X332672Y228734D01*
X332380Y228942D01*
X332089Y229025D01*
X331714D01*
G01X332089D02*
X332339Y229150D01*
X332547Y229359D01*
X332630Y229609D01*
X332547Y229859D01*
X332339Y230067D01*
X331964Y230192D01*
X331589Y230150D01*
X331214Y229984D01*
G01X345647Y224992D02*
Y228992D01*
X338247D01*
G01X327834Y231856D02*
Y234356D01*
X328875D01*
X329209Y234231D01*
X329417Y234064D01*
X329500Y233731D01*
X329417Y233398D01*
X329167Y233189D01*
X328875Y233064D01*
X327834D01*
G01X328875D02*
X329500Y231856D01*
G01X332267D02*
Y234356D01*
X330725Y232564D01*
X332809D01*
G01X338217Y233156D02*
Y229156D01*
X345617D01*
G01X330499Y241041D02*
Y243541D01*
X331540D01*
X331874Y243416D01*
X332082Y243249D01*
X332165Y242916D01*
X332082Y242583D01*
X331832Y242374D01*
X331540Y242249D01*
X330499D01*
G01X331540D02*
X332165Y241041D01*
G01X333515Y241416D02*
X333765Y241208D01*
X334057Y241083D01*
X334432Y241041D01*
X334807Y241124D01*
X335099Y241291D01*
X335307Y241583D01*
X335349Y241916D01*
X335265Y242249D01*
X335057Y242458D01*
X334765Y242624D01*
X334474Y242666D01*
X334182Y242624D01*
X333807Y242458D01*
X333932Y243541D01*
X335057D01*
G01X330817Y246174D02*
Y248674D01*
X331858D01*
X332192Y248549D01*
X332400Y248382D01*
X332483Y248049D01*
X332400Y247716D01*
X332150Y247507D01*
X331858Y247382D01*
X330817D01*
G01X331858D02*
X332483Y246174D01*
G01X334667D02*
X334750Y246716D01*
X334875Y247174D01*
X335042Y247591D01*
X335250Y248049D01*
X335583Y248674D01*
X333917D01*
G01X345682Y254474D02*
Y258474D01*
X338282D01*
G01X338259Y263112D02*
Y259112D01*
X345659D01*
G01X333166Y204241D02*
X330666D01*
Y205241D01*
X330791Y205574D01*
X331083Y205824D01*
X331416Y205907D01*
X331749Y205824D01*
X331999Y205616D01*
X332124Y205241D01*
Y204241D01*
G01X333166Y208174D02*
X333124Y207841D01*
X332958Y207549D01*
X332708Y207299D01*
X332416Y207132D01*
X332083Y207049D01*
X331749D01*
X331416Y207132D01*
X331124Y207299D01*
X330874Y207549D01*
X330708Y207841D01*
X330666Y208174D01*
X330708Y208507D01*
X330874Y208799D01*
X331124Y209049D01*
X331416Y209216D01*
X331749Y209299D01*
X332083D01*
X332416Y209216D01*
X332708Y209049D01*
X332958Y208799D01*
X333124Y208507D01*
X333166Y208174D01*
G01X332499Y208507D02*
X333166Y209007D01*
G01X332666Y210357D02*
X332958Y210607D01*
X333124Y210941D01*
X333166Y211316D01*
X333124Y211649D01*
X332916Y211982D01*
X332666Y212191D01*
X332416Y212232D01*
X332124Y212149D01*
X331916Y211857D01*
X331833Y211566D01*
Y211191D01*
G01Y211566D02*
X331708Y211816D01*
X331499Y212024D01*
X331249Y212107D01*
X330999Y212024D01*
X330791Y211816D01*
X330666Y211441D01*
X330708Y211066D01*
X330874Y210691D01*
G01X338411Y212364D02*
X340511Y210564D01*
X338411Y208364D01*
G01X338311Y204764D02*
X357511D01*
Y215964D01*
X338311D01*
Y204764D01*
X338711D01*
G01X299417Y396700D02*
Y399200D01*
X300500Y397117D01*
X301583Y399200D01*
Y396700D01*
G01X304433D02*
X302767D01*
Y399200D01*
X304433D01*
G01X303767Y397992D02*
X302767D01*
G01X305908Y399200D02*
X307492D01*
X305908Y396700D01*
X307492D01*
G01X309008Y399200D02*
X310592D01*
X309008Y396700D01*
X310592D01*
G01X312900D02*
Y399200D01*
X312400Y398700D01*
G01Y396700D02*
X313400D01*
G01X289200Y425000D02*
X406000D01*
Y447500D01*
X289200D01*
Y425000D01*
G01X278917Y459200D02*
Y461700D01*
X279958D01*
X280292Y461575D01*
X280500Y461408D01*
X280583Y461075D01*
X280500Y460742D01*
X280250Y460533D01*
X279958Y460408D01*
X278917D01*
G01X279958D02*
X280583Y459200D01*
G01X282058Y461283D02*
X282308Y461533D01*
X282600Y461658D01*
X282933Y461700D01*
X283350Y461617D01*
X283642Y461408D01*
X283725Y461158D01*
X283683Y460908D01*
X283517Y460700D01*
X282683Y460283D01*
X282308Y459992D01*
X282058Y459575D01*
X281975Y459200D01*
X283725D01*
G01X285158Y460242D02*
X285450Y460533D01*
X285700Y460700D01*
X286033Y460783D01*
X286325Y460700D01*
X286533Y460533D01*
X286700Y460283D01*
X286742Y459992D01*
X286700Y459742D01*
X286533Y459492D01*
X286283Y459283D01*
X285992Y459200D01*
X285658Y459283D01*
X285367Y459533D01*
X285200Y459908D01*
X285158Y460325D01*
X285242Y460867D01*
X285367Y461158D01*
X285575Y461450D01*
X285867Y461658D01*
X286158Y461700D01*
X286450Y461617D01*
X286658Y461408D01*
G01X289050Y459200D02*
X289342Y459242D01*
X289675Y459367D01*
X289883Y459575D01*
X289967Y459867D01*
X289883Y460158D01*
X289633Y460408D01*
X289258Y460533D01*
X288842D01*
X288592Y460617D01*
X288383Y460825D01*
X288300Y461117D01*
X288425Y461408D01*
X288717Y461617D01*
X289050Y461700D01*
X289383Y461617D01*
X289675Y461408D01*
X289800Y461117D01*
X289717Y460825D01*
X289508Y460617D01*
X289258Y460533D01*
X288842D01*
X288467Y460408D01*
X288217Y460158D01*
X288133Y459867D01*
X288217Y459575D01*
X288425Y459367D01*
X288758Y459242D01*
X289050Y459200D01*
G01X305433Y434517D02*
X302933D01*
Y435558D01*
X303058Y435892D01*
X303225Y436100D01*
X303558Y436183D01*
X303891Y436100D01*
X304100Y435850D01*
X304225Y435558D01*
Y434517D01*
G01Y435558D02*
X305433Y436183D01*
G01X304933Y437533D02*
X305225Y437783D01*
X305391Y438117D01*
X305433Y438492D01*
X305391Y438825D01*
X305183Y439158D01*
X304933Y439367D01*
X304683Y439408D01*
X304391Y439325D01*
X304183Y439033D01*
X304100Y438742D01*
Y438367D01*
G01Y438742D02*
X303975Y438992D01*
X303766Y439200D01*
X303516Y439283D01*
X303266Y439200D01*
X303058Y438992D01*
X302933Y438617D01*
X302975Y438242D01*
X303141Y437867D01*
G01X305433Y441467D02*
X304891Y441550D01*
X304433Y441675D01*
X304016Y441842D01*
X303558Y442050D01*
X302933Y442383D01*
Y440717D01*
G01X305141Y443942D02*
X305350Y444233D01*
X305433Y444567D01*
X305350Y444900D01*
X305100Y445192D01*
X304725Y445400D01*
X304350Y445483D01*
X303891D01*
X303516Y445400D01*
X303183Y445192D01*
X303016Y444942D01*
X302933Y444650D01*
X303016Y444317D01*
X303183Y444067D01*
X303433Y443900D01*
X303766Y443817D01*
X304058Y443900D01*
X304350Y444108D01*
X304516Y444358D01*
X304558Y444650D01*
X304475Y444983D01*
X304266Y445233D01*
X303891Y445483D01*
G01X329033Y434717D02*
X326533D01*
Y435758D01*
X326658Y436092D01*
X326825Y436300D01*
X327158Y436383D01*
X327491Y436300D01*
X327700Y436050D01*
X327825Y435758D01*
Y434717D01*
G01Y435758D02*
X329033Y436383D01*
G01Y438650D02*
X326533D01*
X327033Y438150D01*
G01X329033D02*
Y439150D01*
G01X328658Y440833D02*
X328866Y441083D01*
X328991Y441375D01*
X329033Y441750D01*
X328950Y442125D01*
X328783Y442417D01*
X328491Y442625D01*
X328158Y442667D01*
X327825Y442583D01*
X327616Y442375D01*
X327450Y442083D01*
X327408Y441792D01*
X327450Y441500D01*
X327616Y441125D01*
X326533Y441250D01*
Y442375D01*
G01X329033Y444850D02*
X328991Y445142D01*
X328866Y445475D01*
X328658Y445683D01*
X328366Y445767D01*
X328075Y445683D01*
X327825Y445433D01*
X327700Y445058D01*
Y444642D01*
X327616Y444392D01*
X327408Y444183D01*
X327116Y444100D01*
X326825Y444225D01*
X326616Y444517D01*
X326533Y444850D01*
X326616Y445183D01*
X326825Y445475D01*
X327116Y445600D01*
X327408Y445517D01*
X327616Y445308D01*
X327700Y445058D01*
Y444642D01*
X327825Y444267D01*
X328075Y444017D01*
X328366Y443933D01*
X328658Y444017D01*
X328866Y444225D01*
X328991Y444558D01*
X329033Y444850D01*
G01X341533Y434717D02*
X339033D01*
Y435758D01*
X339158Y436092D01*
X339325Y436300D01*
X339658Y436383D01*
X339991Y436300D01*
X340200Y436050D01*
X340325Y435758D01*
Y434717D01*
G01Y435758D02*
X341533Y436383D01*
G01Y438650D02*
X339033D01*
X339533Y438150D01*
G01X341533D02*
Y439150D01*
G01Y441667D02*
X340991Y441750D01*
X340533Y441875D01*
X340116Y442042D01*
X339658Y442250D01*
X339033Y442583D01*
Y440917D01*
G01X341533Y444767D02*
X340991Y444850D01*
X340533Y444975D01*
X340116Y445142D01*
X339658Y445350D01*
X339033Y445683D01*
Y444017D01*
G01X325033Y434717D02*
X322533D01*
Y435758D01*
X322658Y436092D01*
X322825Y436300D01*
X323158Y436383D01*
X323491Y436300D01*
X323700Y436050D01*
X323825Y435758D01*
Y434717D01*
G01Y435758D02*
X325033Y436383D01*
G01X322950Y437858D02*
X322700Y438108D01*
X322575Y438400D01*
X322533Y438733D01*
X322616Y439150D01*
X322825Y439442D01*
X323075Y439525D01*
X323325Y439483D01*
X323533Y439317D01*
X323950Y438483D01*
X324241Y438108D01*
X324658Y437858D01*
X325033Y437775D01*
Y439525D01*
G01X323991Y440958D02*
X323700Y441250D01*
X323533Y441500D01*
X323450Y441833D01*
X323533Y442125D01*
X323700Y442333D01*
X323950Y442500D01*
X324241Y442542D01*
X324491Y442500D01*
X324741Y442333D01*
X324950Y442083D01*
X325033Y441792D01*
X324950Y441458D01*
X324700Y441167D01*
X324325Y441000D01*
X323908Y440958D01*
X323366Y441042D01*
X323075Y441167D01*
X322783Y441375D01*
X322575Y441667D01*
X322533Y441958D01*
X322616Y442250D01*
X322825Y442458D01*
G01X322950Y444058D02*
X322700Y444308D01*
X322575Y444600D01*
X322533Y444933D01*
X322616Y445350D01*
X322825Y445642D01*
X323075Y445725D01*
X323325Y445683D01*
X323533Y445517D01*
X323950Y444683D01*
X324241Y444308D01*
X324658Y444058D01*
X325033Y443975D01*
Y445725D01*
G01X321033Y434717D02*
X318533D01*
Y435758D01*
X318658Y436092D01*
X318825Y436300D01*
X319158Y436383D01*
X319491Y436300D01*
X319700Y436050D01*
X319825Y435758D01*
Y434717D01*
G01Y435758D02*
X321033Y436383D01*
G01X318950Y437858D02*
X318700Y438108D01*
X318575Y438400D01*
X318533Y438733D01*
X318616Y439150D01*
X318825Y439442D01*
X319075Y439525D01*
X319325Y439483D01*
X319533Y439317D01*
X319950Y438483D01*
X320241Y438108D01*
X320658Y437858D01*
X321033Y437775D01*
Y439525D01*
G01X319991Y440958D02*
X319700Y441250D01*
X319533Y441500D01*
X319450Y441833D01*
X319533Y442125D01*
X319700Y442333D01*
X319950Y442500D01*
X320241Y442542D01*
X320491Y442500D01*
X320741Y442333D01*
X320950Y442083D01*
X321033Y441792D01*
X320950Y441458D01*
X320700Y441167D01*
X320325Y441000D01*
X319908Y440958D01*
X319366Y441042D01*
X319075Y441167D01*
X318783Y441375D01*
X318575Y441667D01*
X318533Y441958D01*
X318616Y442250D01*
X318825Y442458D01*
G01X320533Y443933D02*
X320825Y444183D01*
X320991Y444517D01*
X321033Y444892D01*
X320991Y445225D01*
X320783Y445558D01*
X320533Y445767D01*
X320283Y445808D01*
X319991Y445725D01*
X319783Y445433D01*
X319700Y445142D01*
Y444767D01*
G01Y445142D02*
X319575Y445392D01*
X319366Y445600D01*
X319116Y445683D01*
X318866Y445600D01*
X318658Y445392D01*
X318533Y445017D01*
X318575Y444642D01*
X318741Y444267D01*
G01X333033Y434717D02*
X330533D01*
Y435758D01*
X330658Y436092D01*
X330825Y436300D01*
X331158Y436383D01*
X331491Y436300D01*
X331700Y436050D01*
X331825Y435758D01*
Y434717D01*
G01Y435758D02*
X333033Y436383D01*
G01X330950Y437858D02*
X330700Y438108D01*
X330575Y438400D01*
X330533Y438733D01*
X330616Y439150D01*
X330825Y439442D01*
X331075Y439525D01*
X331325Y439483D01*
X331533Y439317D01*
X331950Y438483D01*
X332241Y438108D01*
X332658Y437858D01*
X333033Y437775D01*
Y439525D01*
G01X331991Y440958D02*
X331700Y441250D01*
X331533Y441500D01*
X331450Y441833D01*
X331533Y442125D01*
X331700Y442333D01*
X331950Y442500D01*
X332241Y442542D01*
X332491Y442500D01*
X332741Y442333D01*
X332950Y442083D01*
X333033Y441792D01*
X332950Y441458D01*
X332700Y441167D01*
X332325Y441000D01*
X331908Y440958D01*
X331366Y441042D01*
X331075Y441167D01*
X330783Y441375D01*
X330575Y441667D01*
X330533Y441958D01*
X330616Y442250D01*
X330825Y442458D01*
G01X333033Y445350D02*
X330533D01*
X332325Y443808D01*
Y445892D01*
G01X337533Y434717D02*
X335033D01*
Y435758D01*
X335158Y436092D01*
X335325Y436300D01*
X335658Y436383D01*
X335991Y436300D01*
X336200Y436050D01*
X336325Y435758D01*
Y434717D01*
G01Y435758D02*
X337533Y436383D01*
G01X335450Y437858D02*
X335200Y438108D01*
X335075Y438400D01*
X335033Y438733D01*
X335116Y439150D01*
X335325Y439442D01*
X335575Y439525D01*
X335825Y439483D01*
X336033Y439317D01*
X336450Y438483D01*
X336741Y438108D01*
X337158Y437858D01*
X337533Y437775D01*
Y439525D01*
G01X336491Y440958D02*
X336200Y441250D01*
X336033Y441500D01*
X335950Y441833D01*
X336033Y442125D01*
X336200Y442333D01*
X336450Y442500D01*
X336741Y442542D01*
X336991Y442500D01*
X337241Y442333D01*
X337450Y442083D01*
X337533Y441792D01*
X337450Y441458D01*
X337200Y441167D01*
X336825Y441000D01*
X336408Y440958D01*
X335866Y441042D01*
X335575Y441167D01*
X335283Y441375D01*
X335075Y441667D01*
X335033Y441958D01*
X335116Y442250D01*
X335325Y442458D01*
G01X337158Y443933D02*
X337366Y444183D01*
X337491Y444475D01*
X337533Y444850D01*
X337450Y445225D01*
X337283Y445517D01*
X336991Y445725D01*
X336658Y445767D01*
X336325Y445683D01*
X336116Y445475D01*
X335950Y445183D01*
X335908Y444892D01*
X335950Y444600D01*
X336116Y444225D01*
X335033Y444350D01*
Y445475D01*
G01X290717Y435866D02*
Y438366D01*
X291758D01*
X292092Y438241D01*
X292300Y438074D01*
X292383Y437741D01*
X292300Y437408D01*
X292050Y437199D01*
X291758Y437074D01*
X290717D01*
G01X291758D02*
X292383Y435866D01*
G01X293733Y436366D02*
X293983Y436074D01*
X294317Y435908D01*
X294692Y435866D01*
X295025Y435908D01*
X295358Y436116D01*
X295567Y436366D01*
X295608Y436616D01*
X295525Y436908D01*
X295233Y437116D01*
X294942Y437199D01*
X294567D01*
G01X294942D02*
X295192Y437324D01*
X295400Y437533D01*
X295483Y437783D01*
X295400Y438033D01*
X295192Y438241D01*
X294817Y438366D01*
X294442Y438324D01*
X294067Y438158D01*
G01X297750Y438366D02*
X297417Y438283D01*
X297167Y438074D01*
X297000Y437824D01*
X296875Y437491D01*
X296833Y437116D01*
X296875Y436741D01*
X297000Y436408D01*
X297167Y436158D01*
X297417Y435949D01*
X297750Y435866D01*
X298083Y435949D01*
X298333Y436158D01*
X298500Y436408D01*
X298625Y436741D01*
X298667Y437116D01*
X298625Y437491D01*
X298500Y437824D01*
X298333Y438074D01*
X298083Y438283D01*
X297750Y438366D01*
G01X300850Y435866D02*
X301142Y435908D01*
X301475Y436033D01*
X301683Y436241D01*
X301767Y436533D01*
X301683Y436824D01*
X301433Y437074D01*
X301058Y437199D01*
X300642D01*
X300392Y437283D01*
X300183Y437491D01*
X300100Y437783D01*
X300225Y438074D01*
X300517Y438283D01*
X300850Y438366D01*
X301183Y438283D01*
X301475Y438074D01*
X301600Y437783D01*
X301517Y437491D01*
X301308Y437283D01*
X301058Y437199D01*
X300642D01*
X300267Y437074D01*
X300017Y436824D01*
X299933Y436533D01*
X300017Y436241D01*
X300225Y436033D01*
X300558Y435908D01*
X300850Y435866D01*
G01X317033Y434717D02*
X314533D01*
Y435758D01*
X314658Y436092D01*
X314825Y436300D01*
X315158Y436383D01*
X315491Y436300D01*
X315700Y436050D01*
X315825Y435758D01*
Y434717D01*
G01Y435758D02*
X317033Y436383D01*
G01X316533Y437733D02*
X316825Y437983D01*
X316991Y438317D01*
X317033Y438692D01*
X316991Y439025D01*
X316783Y439358D01*
X316533Y439567D01*
X316283Y439608D01*
X315991Y439525D01*
X315783Y439233D01*
X315700Y438942D01*
Y438567D01*
G01Y438942D02*
X315575Y439192D01*
X315366Y439400D01*
X315116Y439483D01*
X314866Y439400D01*
X314658Y439192D01*
X314533Y438817D01*
X314575Y438442D01*
X314741Y438067D01*
G01X317033Y441667D02*
X316491Y441750D01*
X316033Y441875D01*
X315616Y442042D01*
X315158Y442250D01*
X314533Y442583D01*
Y440917D01*
G01X315991Y444058D02*
X315700Y444350D01*
X315533Y444600D01*
X315450Y444933D01*
X315533Y445225D01*
X315700Y445433D01*
X315950Y445600D01*
X316241Y445642D01*
X316491Y445600D01*
X316741Y445433D01*
X316950Y445183D01*
X317033Y444892D01*
X316950Y444558D01*
X316700Y444267D01*
X316325Y444100D01*
X315908Y444058D01*
X315366Y444142D01*
X315075Y444267D01*
X314783Y444475D01*
X314575Y444767D01*
X314533Y445058D01*
X314616Y445350D01*
X314825Y445558D01*
G01X309433Y434517D02*
X306933D01*
Y435558D01*
X307058Y435892D01*
X307225Y436100D01*
X307558Y436183D01*
X307891Y436100D01*
X308100Y435850D01*
X308225Y435558D01*
Y434517D01*
G01Y435558D02*
X309433Y436183D01*
G01X308933Y437533D02*
X309225Y437783D01*
X309391Y438117D01*
X309433Y438492D01*
X309391Y438825D01*
X309183Y439158D01*
X308933Y439367D01*
X308683Y439408D01*
X308391Y439325D01*
X308183Y439033D01*
X308100Y438742D01*
Y438367D01*
G01Y438742D02*
X307975Y438992D01*
X307766Y439200D01*
X307516Y439283D01*
X307266Y439200D01*
X307058Y438992D01*
X306933Y438617D01*
X306975Y438242D01*
X307141Y437867D01*
G01X309433Y441467D02*
X308891Y441550D01*
X308433Y441675D01*
X308016Y441842D01*
X307558Y442050D01*
X306933Y442383D01*
Y440717D01*
G01X309433Y444567D02*
X308891Y444650D01*
X308433Y444775D01*
X308016Y444942D01*
X307558Y445150D01*
X306933Y445483D01*
Y443817D01*
G01X313033Y434717D02*
X310533D01*
Y435758D01*
X310658Y436092D01*
X310825Y436300D01*
X311158Y436383D01*
X311491Y436300D01*
X311700Y436050D01*
X311825Y435758D01*
Y434717D01*
G01Y435758D02*
X313033Y436383D01*
G01X312533Y437733D02*
X312825Y437983D01*
X312991Y438317D01*
X313033Y438692D01*
X312991Y439025D01*
X312783Y439358D01*
X312533Y439567D01*
X312283Y439608D01*
X311991Y439525D01*
X311783Y439233D01*
X311700Y438942D01*
Y438567D01*
G01Y438942D02*
X311575Y439192D01*
X311366Y439400D01*
X311116Y439483D01*
X310866Y439400D01*
X310658Y439192D01*
X310533Y438817D01*
X310575Y438442D01*
X310741Y438067D01*
G01X313033Y441667D02*
X312491Y441750D01*
X312033Y441875D01*
X311616Y442042D01*
X311158Y442250D01*
X310533Y442583D01*
Y440917D01*
G01X313033Y444850D02*
X312991Y445142D01*
X312866Y445475D01*
X312658Y445683D01*
X312366Y445767D01*
X312075Y445683D01*
X311825Y445433D01*
X311700Y445058D01*
Y444642D01*
X311616Y444392D01*
X311408Y444183D01*
X311116Y444100D01*
X310825Y444225D01*
X310616Y444517D01*
X310533Y444850D01*
X310616Y445183D01*
X310825Y445475D01*
X311116Y445600D01*
X311408Y445517D01*
X311616Y445308D01*
X311700Y445058D01*
Y444642D01*
X311825Y444267D01*
X312075Y444017D01*
X312366Y443933D01*
X312658Y444017D01*
X312866Y444225D01*
X312991Y444558D01*
X313033Y444850D01*
G01X290317Y441867D02*
Y444367D01*
X291358D01*
X291692Y444242D01*
X291900Y444075D01*
X291983Y443742D01*
X291900Y443409D01*
X291650Y443200D01*
X291358Y443075D01*
X290317D01*
G01X291358D02*
X291983Y441867D01*
G01X293333Y442367D02*
X293583Y442075D01*
X293917Y441909D01*
X294292Y441867D01*
X294625Y441909D01*
X294958Y442117D01*
X295167Y442367D01*
X295208Y442617D01*
X295125Y442909D01*
X294833Y443117D01*
X294542Y443200D01*
X294167D01*
G01X294542D02*
X294792Y443325D01*
X295000Y443534D01*
X295083Y443784D01*
X295000Y444034D01*
X294792Y444242D01*
X294417Y444367D01*
X294042Y444325D01*
X293667Y444159D01*
G01X297350Y441867D02*
Y444367D01*
X296850Y443867D01*
G01Y441867D02*
X297850D01*
G01X299658Y443950D02*
X299908Y444200D01*
X300200Y444325D01*
X300533Y444367D01*
X300950Y444284D01*
X301242Y444075D01*
X301325Y443825D01*
X301283Y443575D01*
X301117Y443367D01*
X300283Y442950D01*
X299908Y442659D01*
X299658Y442242D01*
X299575Y441867D01*
X301325D01*
G01X283217Y467259D02*
X282967Y467384D01*
X282675Y467467D01*
X282342D01*
X281967Y467342D01*
X281675Y467134D01*
X281467Y466884D01*
X281300Y466467D01*
X281258Y466092D01*
X281342Y465717D01*
X281467Y465467D01*
X281717Y465217D01*
X282008Y465050D01*
X282300Y464967D01*
X282592D01*
X282883Y465050D01*
X283133Y465175D01*
X283342Y465342D01*
G01X285317Y464967D02*
X285400Y465509D01*
X285525Y465967D01*
X285692Y466384D01*
X285900Y466842D01*
X286233Y467467D01*
X284567D01*
G01X289000Y464967D02*
Y467467D01*
X287458Y465675D01*
X289542D01*
G01X284289Y510608D02*
X284039Y510733D01*
X283747Y510816D01*
X283414D01*
X283039Y510691D01*
X282747Y510483D01*
X282539Y510233D01*
X282372Y509816D01*
X282330Y509441D01*
X282414Y509066D01*
X282539Y508816D01*
X282789Y508566D01*
X283080Y508399D01*
X283372Y508316D01*
X283664D01*
X283955Y508399D01*
X284205Y508524D01*
X284414Y508691D01*
G01X286472Y508316D02*
Y510816D01*
X285972Y510316D01*
G01Y508316D02*
X286972D01*
G01X288655Y508816D02*
X288905Y508524D01*
X289239Y508358D01*
X289614Y508316D01*
X289947Y508358D01*
X290280Y508566D01*
X290489Y508816D01*
X290530Y509066D01*
X290447Y509358D01*
X290155Y509566D01*
X289864Y509649D01*
X289489D01*
G01X289864D02*
X290114Y509774D01*
X290322Y509983D01*
X290405Y510233D01*
X290322Y510483D01*
X290114Y510691D01*
X289739Y510816D01*
X289364Y510774D01*
X288989Y510608D01*
G01X291755Y508691D02*
X292005Y508483D01*
X292297Y508358D01*
X292672Y508316D01*
X293047Y508399D01*
X293339Y508566D01*
X293547Y508858D01*
X293589Y509191D01*
X293505Y509524D01*
X293297Y509733D01*
X293005Y509899D01*
X292714Y509941D01*
X292422Y509899D01*
X292047Y509733D01*
X292172Y510816D01*
X293297D01*
G01X284967Y490292D02*
X284717Y490417D01*
X284425Y490500D01*
X284092D01*
X283717Y490375D01*
X283425Y490167D01*
X283217Y489917D01*
X283050Y489500D01*
X283008Y489125D01*
X283092Y488750D01*
X283217Y488500D01*
X283467Y488250D01*
X283758Y488083D01*
X284050Y488000D01*
X284342D01*
X284633Y488083D01*
X284883Y488208D01*
X285092Y488375D01*
G01X286233D02*
X286483Y488167D01*
X286775Y488042D01*
X287150Y488000D01*
X287525Y488083D01*
X287817Y488250D01*
X288025Y488542D01*
X288067Y488875D01*
X287983Y489208D01*
X287775Y489417D01*
X287483Y489583D01*
X287192Y489625D01*
X286900Y489583D01*
X286525Y489417D01*
X286650Y490500D01*
X287775D01*
G01X290250Y488000D02*
Y490500D01*
X289750Y490000D01*
G01Y488000D02*
X290750D01*
G01X292433Y488500D02*
X292683Y488208D01*
X293017Y488042D01*
X293392Y488000D01*
X293725Y488042D01*
X294058Y488250D01*
X294267Y488500D01*
X294308Y488750D01*
X294225Y489042D01*
X293933Y489250D01*
X293642Y489333D01*
X293267D01*
G01X293642D02*
X293892Y489458D01*
X294100Y489667D01*
X294183Y489917D01*
X294100Y490167D01*
X293892Y490375D01*
X293517Y490500D01*
X293142Y490458D01*
X292767Y490292D01*
G01X326417Y499392D02*
X326167Y499517D01*
X325875Y499600D01*
X325542D01*
X325167Y499475D01*
X324875Y499267D01*
X324667Y499017D01*
X324500Y498600D01*
X324458Y498225D01*
X324542Y497850D01*
X324667Y497600D01*
X324917Y497350D01*
X325208Y497183D01*
X325500Y497100D01*
X325792D01*
X326083Y497183D01*
X326333Y497308D01*
X326542Y497475D01*
G01X329100Y497100D02*
Y499600D01*
X327558Y497808D01*
X329642D01*
G01X331700Y497100D02*
X331992Y497142D01*
X332325Y497267D01*
X332533Y497475D01*
X332617Y497767D01*
X332533Y498058D01*
X332283Y498308D01*
X331908Y498433D01*
X331492D01*
X331242Y498517D01*
X331033Y498725D01*
X330950Y499017D01*
X331075Y499308D01*
X331367Y499517D01*
X331700Y499600D01*
X332033Y499517D01*
X332325Y499308D01*
X332450Y499017D01*
X332367Y498725D01*
X332158Y498517D01*
X331908Y498433D01*
X331492D01*
X331117Y498308D01*
X330867Y498058D01*
X330783Y497767D01*
X330867Y497475D01*
X331075Y497267D01*
X331408Y497142D01*
X331700Y497100D01*
G01X333883Y497475D02*
X334133Y497267D01*
X334425Y497142D01*
X334800Y497100D01*
X335175Y497183D01*
X335467Y497350D01*
X335675Y497642D01*
X335717Y497975D01*
X335633Y498308D01*
X335425Y498517D01*
X335133Y498683D01*
X334842Y498725D01*
X334550Y498683D01*
X334175Y498517D01*
X334300Y499600D01*
X335425D01*
G01X326417Y510492D02*
X326167Y510617D01*
X325875Y510700D01*
X325542D01*
X325167Y510575D01*
X324875Y510367D01*
X324667Y510117D01*
X324500Y509700D01*
X324458Y509325D01*
X324542Y508950D01*
X324667Y508700D01*
X324917Y508450D01*
X325208Y508283D01*
X325500Y508200D01*
X325792D01*
X326083Y508283D01*
X326333Y508408D01*
X326542Y508575D01*
G01X329100Y508200D02*
Y510700D01*
X327558Y508908D01*
X329642D01*
G01X331700Y510700D02*
X331367Y510617D01*
X331117Y510408D01*
X330950Y510158D01*
X330825Y509825D01*
X330783Y509450D01*
X330825Y509075D01*
X330950Y508742D01*
X331117Y508492D01*
X331367Y508283D01*
X331700Y508200D01*
X332033Y508283D01*
X332283Y508492D01*
X332450Y508742D01*
X332575Y509075D01*
X332617Y509450D01*
X332575Y509825D01*
X332450Y510158D01*
X332283Y510408D01*
X332033Y510617D01*
X331700Y510700D01*
G01X277517Y471167D02*
Y473667D01*
X278558D01*
X278892Y473542D01*
X279100Y473375D01*
X279183Y473042D01*
X279100Y472709D01*
X278850Y472500D01*
X278558Y472375D01*
X277517D01*
G01X278558D02*
X279183Y471167D01*
G01X280658Y473250D02*
X280908Y473500D01*
X281200Y473625D01*
X281533Y473667D01*
X281950Y473584D01*
X282242Y473375D01*
X282325Y473125D01*
X282283Y472875D01*
X282117Y472667D01*
X281283Y472250D01*
X280908Y471959D01*
X280658Y471542D01*
X280575Y471167D01*
X282325D01*
G01X283758Y472209D02*
X284050Y472500D01*
X284300Y472667D01*
X284633Y472750D01*
X284925Y472667D01*
X285133Y472500D01*
X285300Y472250D01*
X285342Y471959D01*
X285300Y471709D01*
X285133Y471459D01*
X284883Y471250D01*
X284592Y471167D01*
X284258Y471250D01*
X283967Y471500D01*
X283800Y471875D01*
X283758Y472292D01*
X283842Y472834D01*
X283967Y473125D01*
X284175Y473417D01*
X284467Y473625D01*
X284758Y473667D01*
X285050Y473584D01*
X285258Y473375D01*
G01X286858Y472209D02*
X287150Y472500D01*
X287400Y472667D01*
X287733Y472750D01*
X288025Y472667D01*
X288233Y472500D01*
X288400Y472250D01*
X288442Y471959D01*
X288400Y471709D01*
X288233Y471459D01*
X287983Y471250D01*
X287692Y471167D01*
X287358Y471250D01*
X287067Y471500D01*
X286900Y471875D01*
X286858Y472292D01*
X286942Y472834D01*
X287067Y473125D01*
X287275Y473417D01*
X287567Y473625D01*
X287858Y473667D01*
X288150Y473584D01*
X288358Y473375D01*
G01X337143Y522000D02*
X334643D01*
Y523041D01*
X334768Y523375D01*
X334935Y523583D01*
X335268Y523666D01*
X335601Y523583D01*
X335810Y523333D01*
X335935Y523041D01*
Y522000D01*
G01Y523041D02*
X337143Y523666D01*
G01Y525933D02*
X334643D01*
X335143Y525433D01*
G01X337143D02*
Y526433D01*
G01X336643Y528116D02*
X336935Y528366D01*
X337101Y528700D01*
X337143Y529075D01*
X337101Y529408D01*
X336893Y529741D01*
X336643Y529950D01*
X336393Y529991D01*
X336101Y529908D01*
X335893Y529616D01*
X335810Y529325D01*
Y528950D01*
G01Y529325D02*
X335685Y529575D01*
X335476Y529783D01*
X335226Y529866D01*
X334976Y529783D01*
X334768Y529575D01*
X334643Y529200D01*
X334685Y528825D01*
X334851Y528450D01*
G01X337143Y532633D02*
X334643D01*
X336435Y531091D01*
Y533175D01*
G01X342942Y533926D02*
X338942D01*
Y526526D01*
G01X339978Y519086D02*
Y515086D01*
X347378D01*
G01X277517Y475667D02*
Y478167D01*
X278558D01*
X278892Y478042D01*
X279100Y477875D01*
X279183Y477542D01*
X279100Y477209D01*
X278850Y477000D01*
X278558Y476875D01*
X277517D01*
G01X278558D02*
X279183Y475667D01*
G01X281367D02*
X281450Y476209D01*
X281575Y476667D01*
X281742Y477084D01*
X281950Y477542D01*
X282283Y478167D01*
X280617D01*
G01X283758Y476709D02*
X284050Y477000D01*
X284300Y477167D01*
X284633Y477250D01*
X284925Y477167D01*
X285133Y477000D01*
X285300Y476750D01*
X285342Y476459D01*
X285300Y476209D01*
X285133Y475959D01*
X284883Y475750D01*
X284592Y475667D01*
X284258Y475750D01*
X283967Y476000D01*
X283800Y476375D01*
X283758Y476792D01*
X283842Y477334D01*
X283967Y477625D01*
X284175Y477917D01*
X284467Y478125D01*
X284758Y478167D01*
X285050Y478084D01*
X285258Y477875D01*
G01X288150Y475667D02*
Y478167D01*
X286608Y476375D01*
X288692D01*
G01X284317Y519200D02*
Y521700D01*
X285358D01*
X285692Y521575D01*
X285900Y521408D01*
X285983Y521075D01*
X285900Y520742D01*
X285650Y520533D01*
X285358Y520408D01*
X284317D01*
G01X285358D02*
X285983Y519200D01*
G01X288250D02*
Y521700D01*
X287750Y521200D01*
G01Y519200D02*
X288750D01*
G01X290433Y519700D02*
X290683Y519408D01*
X291017Y519242D01*
X291392Y519200D01*
X291725Y519242D01*
X292058Y519450D01*
X292267Y519700D01*
X292308Y519950D01*
X292225Y520242D01*
X291933Y520450D01*
X291642Y520533D01*
X291267D01*
G01X291642D02*
X291892Y520658D01*
X292100Y520867D01*
X292183Y521117D01*
X292100Y521367D01*
X291892Y521575D01*
X291517Y521700D01*
X291142Y521658D01*
X290767Y521492D01*
G01X294450Y521700D02*
X294117Y521617D01*
X293867Y521408D01*
X293700Y521158D01*
X293575Y520825D01*
X293533Y520450D01*
X293575Y520075D01*
X293700Y519742D01*
X293867Y519492D01*
X294117Y519283D01*
X294450Y519200D01*
X294783Y519283D01*
X295033Y519492D01*
X295200Y519742D01*
X295325Y520075D01*
X295367Y520450D01*
X295325Y520825D01*
X295200Y521158D01*
X295033Y521408D01*
X294783Y521617D01*
X294450Y521700D01*
G01X282539Y512016D02*
Y514516D01*
X283580D01*
X283914Y514391D01*
X284122Y514224D01*
X284205Y513891D01*
X284122Y513558D01*
X283872Y513349D01*
X283580Y513224D01*
X282539D01*
G01X283580D02*
X284205Y512016D01*
G01X286472D02*
Y514516D01*
X285972Y514016D01*
G01Y512016D02*
X286972D01*
G01X288780Y514099D02*
X289030Y514349D01*
X289322Y514474D01*
X289655Y514516D01*
X290072Y514433D01*
X290364Y514224D01*
X290447Y513974D01*
X290405Y513724D01*
X290239Y513516D01*
X289405Y513099D01*
X289030Y512808D01*
X288780Y512391D01*
X288697Y512016D01*
X290447D01*
G01X291964Y512308D02*
X292255Y512099D01*
X292589Y512016D01*
X292922Y512099D01*
X293214Y512349D01*
X293422Y512724D01*
X293505Y513099D01*
Y513558D01*
X293422Y513933D01*
X293214Y514266D01*
X292964Y514433D01*
X292672Y514516D01*
X292339Y514433D01*
X292089Y514266D01*
X291922Y514016D01*
X291839Y513683D01*
X291922Y513391D01*
X292130Y513099D01*
X292380Y512933D01*
X292672Y512891D01*
X293005Y512974D01*
X293255Y513183D01*
X293505Y513558D01*
G01X324667Y500800D02*
Y503300D01*
X325708D01*
X326042Y503175D01*
X326250Y503008D01*
X326333Y502675D01*
X326250Y502342D01*
X326000Y502133D01*
X325708Y502008D01*
X324667D01*
G01X325708D02*
X326333Y500800D01*
G01X327683Y501175D02*
X327933Y500967D01*
X328225Y500842D01*
X328600Y500800D01*
X328975Y500883D01*
X329267Y501050D01*
X329475Y501342D01*
X329517Y501675D01*
X329433Y502008D01*
X329225Y502217D01*
X328933Y502383D01*
X328642Y502425D01*
X328350Y502383D01*
X327975Y502217D01*
X328100Y503300D01*
X329225D01*
G01X330783Y501300D02*
X331033Y501008D01*
X331367Y500842D01*
X331742Y500800D01*
X332075Y500842D01*
X332408Y501050D01*
X332617Y501300D01*
X332658Y501550D01*
X332575Y501842D01*
X332283Y502050D01*
X331992Y502133D01*
X331617D01*
G01X331992D02*
X332242Y502258D01*
X332450Y502467D01*
X332533Y502717D01*
X332450Y502967D01*
X332242Y503175D01*
X331867Y503300D01*
X331492Y503258D01*
X331117Y503092D01*
G01X332521Y524309D02*
Y528309D01*
X325121D01*
G01X324667Y504500D02*
Y507000D01*
X325708D01*
X326042Y506875D01*
X326250Y506708D01*
X326333Y506375D01*
X326250Y506042D01*
X326000Y505833D01*
X325708Y505708D01*
X324667D01*
G01X325708D02*
X326333Y504500D01*
G01X327683Y504875D02*
X327933Y504667D01*
X328225Y504542D01*
X328600Y504500D01*
X328975Y504583D01*
X329267Y504750D01*
X329475Y505042D01*
X329517Y505375D01*
X329433Y505708D01*
X329225Y505917D01*
X328933Y506083D01*
X328642Y506125D01*
X328350Y506083D01*
X327975Y505917D01*
X328100Y507000D01*
X329225D01*
G01X331700D02*
X331367Y506917D01*
X331117Y506708D01*
X330950Y506458D01*
X330825Y506125D01*
X330783Y505750D01*
X330825Y505375D01*
X330950Y505042D01*
X331117Y504792D01*
X331367Y504583D01*
X331700Y504500D01*
X332033Y504583D01*
X332283Y504792D01*
X332450Y505042D01*
X332575Y505375D01*
X332617Y505750D01*
X332575Y506125D01*
X332450Y506458D01*
X332283Y506708D01*
X332033Y506917D01*
X331700Y507000D01*
G01X284500Y491817D02*
X282000D01*
Y492858D01*
X282125Y493192D01*
X282292Y493400D01*
X282625Y493483D01*
X282958Y493400D01*
X283167Y493150D01*
X283292Y492858D01*
Y491817D01*
G01Y492858D02*
X284500Y493483D01*
G01Y495667D02*
X283958Y495750D01*
X283500Y495875D01*
X283083Y496042D01*
X282625Y496250D01*
X282000Y496583D01*
Y494917D01*
G01X284000Y497933D02*
X284292Y498183D01*
X284458Y498517D01*
X284500Y498892D01*
X284458Y499225D01*
X284250Y499558D01*
X284000Y499767D01*
X283750Y499808D01*
X283458Y499725D01*
X283250Y499433D01*
X283167Y499142D01*
Y498767D01*
G01Y499142D02*
X283042Y499392D01*
X282833Y499600D01*
X282583Y499683D01*
X282333Y499600D01*
X282125Y499392D01*
X282000Y499017D01*
X282042Y498642D01*
X282208Y498267D01*
G01X284500Y501950D02*
X284458Y502242D01*
X284333Y502575D01*
X284125Y502783D01*
X283833Y502867D01*
X283542Y502783D01*
X283292Y502533D01*
X283167Y502158D01*
Y501742D01*
X283083Y501492D01*
X282875Y501283D01*
X282583Y501200D01*
X282292Y501325D01*
X282083Y501617D01*
X282000Y501950D01*
X282083Y502283D01*
X282292Y502575D01*
X282583Y502700D01*
X282875Y502617D01*
X283083Y502408D01*
X283167Y502158D01*
Y501742D01*
X283292Y501367D01*
X283542Y501117D01*
X283833Y501033D01*
X284125Y501117D01*
X284333Y501325D01*
X284458Y501658D01*
X284500Y501950D01*
G01X324767Y512300D02*
Y514800D01*
X325808D01*
X326142Y514675D01*
X326350Y514508D01*
X326433Y514175D01*
X326350Y513842D01*
X326100Y513633D01*
X325808Y513508D01*
X324767D01*
G01X325808D02*
X326433Y512300D01*
G01X328700D02*
Y514800D01*
X328200Y514300D01*
G01Y512300D02*
X329200D01*
G01X331800Y514800D02*
X331467Y514717D01*
X331217Y514508D01*
X331050Y514258D01*
X330925Y513925D01*
X330883Y513550D01*
X330925Y513175D01*
X331050Y512842D01*
X331217Y512592D01*
X331467Y512383D01*
X331800Y512300D01*
X332133Y512383D01*
X332383Y512592D01*
X332550Y512842D01*
X332675Y513175D01*
X332717Y513550D01*
X332675Y513925D01*
X332550Y514258D01*
X332383Y514508D01*
X332133Y514717D01*
X331800Y514800D01*
G01X333983Y512675D02*
X334233Y512467D01*
X334525Y512342D01*
X334900Y512300D01*
X335275Y512383D01*
X335567Y512550D01*
X335775Y512842D01*
X335817Y513175D01*
X335733Y513508D01*
X335525Y513717D01*
X335233Y513883D01*
X334942Y513925D01*
X334650Y513883D01*
X334275Y513717D01*
X334400Y514800D01*
X335525D01*
G01X324767Y516000D02*
Y518500D01*
X325808D01*
X326142Y518375D01*
X326350Y518208D01*
X326433Y517875D01*
X326350Y517542D01*
X326100Y517333D01*
X325808Y517208D01*
X324767D01*
G01X325808D02*
X326433Y516000D01*
G01X327992Y516292D02*
X328283Y516083D01*
X328617Y516000D01*
X328950Y516083D01*
X329242Y516333D01*
X329450Y516708D01*
X329533Y517083D01*
Y517542D01*
X329450Y517917D01*
X329242Y518250D01*
X328992Y518417D01*
X328700Y518500D01*
X328367Y518417D01*
X328117Y518250D01*
X327950Y518000D01*
X327867Y517667D01*
X327950Y517375D01*
X328158Y517083D01*
X328408Y516917D01*
X328700Y516875D01*
X329033Y516958D01*
X329283Y517167D01*
X329533Y517542D01*
G01X331092Y516292D02*
X331383Y516083D01*
X331717Y516000D01*
X332050Y516083D01*
X332342Y516333D01*
X332550Y516708D01*
X332633Y517083D01*
Y517542D01*
X332550Y517917D01*
X332342Y518250D01*
X332092Y518417D01*
X331800Y518500D01*
X331467Y518417D01*
X331217Y518250D01*
X331050Y518000D01*
X330967Y517667D01*
X331050Y517375D01*
X331258Y517083D01*
X331508Y516917D01*
X331800Y516875D01*
X332133Y516958D01*
X332383Y517167D01*
X332633Y517542D01*
G01X313667Y514600D02*
Y517100D01*
X314708D01*
X315042Y516975D01*
X315250Y516808D01*
X315333Y516475D01*
X315250Y516142D01*
X315000Y515933D01*
X314708Y515808D01*
X313667D01*
G01X314708D02*
X315333Y514600D01*
G01X316892Y514892D02*
X317183Y514683D01*
X317517Y514600D01*
X317850Y514683D01*
X318142Y514933D01*
X318350Y515308D01*
X318433Y515683D01*
Y516142D01*
X318350Y516517D01*
X318142Y516850D01*
X317892Y517017D01*
X317600Y517100D01*
X317267Y517017D01*
X317017Y516850D01*
X316850Y516600D01*
X316767Y516267D01*
X316850Y515975D01*
X317058Y515683D01*
X317308Y515517D01*
X317600Y515475D01*
X317933Y515558D01*
X318183Y515767D01*
X318433Y516142D01*
G01X320700Y514600D02*
X320992Y514642D01*
X321325Y514767D01*
X321533Y514975D01*
X321617Y515267D01*
X321533Y515558D01*
X321283Y515808D01*
X320908Y515933D01*
X320492D01*
X320242Y516017D01*
X320033Y516225D01*
X319950Y516517D01*
X320075Y516808D01*
X320367Y517017D01*
X320700Y517100D01*
X321033Y517017D01*
X321325Y516808D01*
X321450Y516517D01*
X321367Y516225D01*
X321158Y516017D01*
X320908Y515933D01*
X320492D01*
X320117Y515808D01*
X319867Y515558D01*
X319783Y515267D01*
X319867Y514975D01*
X320075Y514767D01*
X320408Y514642D01*
X320700Y514600D01*
G01X304167Y514500D02*
Y517000D01*
X305208D01*
X305542Y516875D01*
X305750Y516708D01*
X305833Y516375D01*
X305750Y516042D01*
X305500Y515833D01*
X305208Y515708D01*
X304167D01*
G01X305208D02*
X305833Y514500D01*
G01X307392Y514792D02*
X307683Y514583D01*
X308017Y514500D01*
X308350Y514583D01*
X308642Y514833D01*
X308850Y515208D01*
X308933Y515583D01*
Y516042D01*
X308850Y516417D01*
X308642Y516750D01*
X308392Y516917D01*
X308100Y517000D01*
X307767Y516917D01*
X307517Y516750D01*
X307350Y516500D01*
X307267Y516167D01*
X307350Y515875D01*
X307558Y515583D01*
X307808Y515417D01*
X308100Y515375D01*
X308433Y515458D01*
X308683Y515667D01*
X308933Y516042D01*
G01X310283Y514875D02*
X310533Y514667D01*
X310825Y514542D01*
X311200Y514500D01*
X311575Y514583D01*
X311867Y514750D01*
X312075Y515042D01*
X312117Y515375D01*
X312033Y515708D01*
X311825Y515917D01*
X311533Y516083D01*
X311242Y516125D01*
X310950Y516083D01*
X310575Y515917D01*
X310700Y517000D01*
X311825D01*
G01X288200Y491817D02*
X285700D01*
Y492858D01*
X285825Y493192D01*
X285992Y493400D01*
X286325Y493483D01*
X286658Y493400D01*
X286867Y493150D01*
X286992Y492858D01*
Y491817D01*
G01Y492858D02*
X288200Y493483D01*
G01X287825Y494833D02*
X288033Y495083D01*
X288158Y495375D01*
X288200Y495750D01*
X288117Y496125D01*
X287950Y496417D01*
X287658Y496625D01*
X287325Y496667D01*
X286992Y496583D01*
X286783Y496375D01*
X286617Y496083D01*
X286575Y495792D01*
X286617Y495500D01*
X286783Y495125D01*
X285700Y495250D01*
Y496375D01*
G01X288200Y499350D02*
X285700D01*
X287492Y497808D01*
Y499892D01*
G01X280800Y491817D02*
X278300D01*
Y492858D01*
X278425Y493192D01*
X278592Y493400D01*
X278925Y493483D01*
X279258Y493400D01*
X279467Y493150D01*
X279592Y492858D01*
Y491817D01*
G01Y492858D02*
X280800Y493483D01*
G01Y495750D02*
X278300D01*
X278800Y495250D01*
G01X280800D02*
Y496250D01*
G01X278300Y498850D02*
X278383Y498517D01*
X278592Y498267D01*
X278842Y498100D01*
X279175Y497975D01*
X279550Y497933D01*
X279925Y497975D01*
X280258Y498100D01*
X280508Y498267D01*
X280717Y498517D01*
X280800Y498850D01*
X280717Y499183D01*
X280508Y499433D01*
X280258Y499600D01*
X279925Y499725D01*
X279550Y499767D01*
X279175Y499725D01*
X278842Y499600D01*
X278592Y499433D01*
X278383Y499183D01*
X278300Y498850D01*
G01X278717Y501158D02*
X278467Y501408D01*
X278342Y501700D01*
X278300Y502033D01*
X278383Y502450D01*
X278592Y502742D01*
X278842Y502825D01*
X279092Y502783D01*
X279300Y502617D01*
X279717Y501783D01*
X280008Y501408D01*
X280425Y501158D01*
X280800Y501075D01*
Y502825D01*
G01X307883Y512600D02*
Y510808D01*
X308050Y510433D01*
X308383Y510183D01*
X308800Y510100D01*
X309217Y510183D01*
X309550Y510433D01*
X309717Y510808D01*
Y512600D01*
G01X312400Y510100D02*
Y512600D01*
X310858Y510808D01*
X312942D01*
G01X314083Y510475D02*
X314333Y510267D01*
X314625Y510142D01*
X315000Y510100D01*
X315375Y510183D01*
X315667Y510350D01*
X315875Y510642D01*
X315917Y510975D01*
X315833Y511308D01*
X315625Y511517D01*
X315333Y511683D01*
X315042Y511725D01*
X314750Y511683D01*
X314375Y511517D01*
X314500Y512600D01*
X315625D01*
G01X313770Y530491D02*
Y520291D01*
G01X309170Y519591D02*
Y530491D01*
G01Y519591D02*
X320470D01*
G01X311470Y520791D02*
X310270Y519591D01*
G01X311470Y520791D02*
X312670Y519591D01*
G01X288998Y574114D02*
X288966D01*
Y562563D01*
X292163D01*
Y555663D01*
X285454D01*
Y542150D01*
X276000D01*
G01X301200Y550200D02*
Y550900D01*
X308462D01*
Y557151D01*
X310139D01*
Y571487D01*
X303778D01*
Y575174D01*
X298588D01*
Y575633D01*
X292844D01*
G01X326917Y550192D02*
X326667Y550317D01*
X326375Y550400D01*
X326042D01*
X325667Y550275D01*
X325375Y550067D01*
X325167Y549817D01*
X325000Y549400D01*
X324958Y549025D01*
X325042Y548650D01*
X325167Y548400D01*
X325417Y548150D01*
X325708Y547983D01*
X326000Y547900D01*
X326292D01*
X326583Y547983D01*
X326833Y548108D01*
X327042Y548275D01*
G01X328183Y548400D02*
X328433Y548108D01*
X328767Y547942D01*
X329142Y547900D01*
X329475Y547942D01*
X329808Y548150D01*
X330017Y548400D01*
X330058Y548650D01*
X329975Y548942D01*
X329683Y549150D01*
X329392Y549233D01*
X329017D01*
G01X329392D02*
X329642Y549358D01*
X329850Y549567D01*
X329933Y549817D01*
X329850Y550067D01*
X329642Y550275D01*
X329267Y550400D01*
X328892Y550358D01*
X328517Y550192D01*
G01X332200Y550400D02*
X331867Y550317D01*
X331617Y550108D01*
X331450Y549858D01*
X331325Y549525D01*
X331283Y549150D01*
X331325Y548775D01*
X331450Y548442D01*
X331617Y548192D01*
X331867Y547983D01*
X332200Y547900D01*
X332533Y547983D01*
X332783Y548192D01*
X332950Y548442D01*
X333075Y548775D01*
X333117Y549150D01*
X333075Y549525D01*
X332950Y549858D01*
X332783Y550108D01*
X332533Y550317D01*
X332200Y550400D01*
G01X295934Y588417D02*
X293434D01*
Y589458D01*
X293559Y589792D01*
X293726Y590000D01*
X294059Y590083D01*
X294392Y590000D01*
X294601Y589750D01*
X294726Y589458D01*
Y588417D01*
G01Y589458D02*
X295934Y590083D01*
G01X295434Y591433D02*
X295726Y591683D01*
X295892Y592017D01*
X295934Y592392D01*
X295892Y592725D01*
X295684Y593058D01*
X295434Y593267D01*
X295184Y593308D01*
X294892Y593225D01*
X294684Y592933D01*
X294601Y592642D01*
Y592267D01*
G01Y592642D02*
X294476Y592892D01*
X294267Y593100D01*
X294017Y593183D01*
X293767Y593100D01*
X293559Y592892D01*
X293434Y592517D01*
X293476Y592142D01*
X293642Y591767D01*
G01X293434Y595450D02*
X293517Y595117D01*
X293726Y594867D01*
X293976Y594700D01*
X294309Y594575D01*
X294684Y594533D01*
X295059Y594575D01*
X295392Y594700D01*
X295642Y594867D01*
X295851Y595117D01*
X295934Y595450D01*
X295851Y595783D01*
X295642Y596033D01*
X295392Y596200D01*
X295059Y596325D01*
X294684Y596367D01*
X294309Y596325D01*
X293976Y596200D01*
X293726Y596033D01*
X293517Y595783D01*
X293434Y595450D01*
G01X295934Y598467D02*
X295392Y598550D01*
X294934Y598675D01*
X294517Y598842D01*
X294059Y599050D01*
X293434Y599383D01*
Y597717D01*
G01X298200Y588200D02*
X302200D01*
Y595600D01*
G01X275917Y565067D02*
Y567567D01*
X276958D01*
X277292Y567442D01*
X277500Y567275D01*
X277583Y566942D01*
X277500Y566609D01*
X277250Y566400D01*
X276958Y566275D01*
X275917D01*
G01X276958D02*
X277583Y565067D01*
G01X278933Y565567D02*
X279183Y565275D01*
X279517Y565109D01*
X279892Y565067D01*
X280225Y565109D01*
X280558Y565317D01*
X280767Y565567D01*
X280808Y565817D01*
X280725Y566109D01*
X280433Y566317D01*
X280142Y566400D01*
X279767D01*
G01X280142D02*
X280392Y566525D01*
X280600Y566734D01*
X280683Y566984D01*
X280600Y567234D01*
X280392Y567442D01*
X280017Y567567D01*
X279642Y567525D01*
X279267Y567359D01*
G01X282950Y565067D02*
X283242Y565109D01*
X283575Y565234D01*
X283783Y565442D01*
X283867Y565734D01*
X283783Y566025D01*
X283533Y566275D01*
X283158Y566400D01*
X282742D01*
X282492Y566484D01*
X282283Y566692D01*
X282200Y566984D01*
X282325Y567275D01*
X282617Y567484D01*
X282950Y567567D01*
X283283Y567484D01*
X283575Y567275D01*
X283700Y566984D01*
X283617Y566692D01*
X283408Y566484D01*
X283158Y566400D01*
X282742D01*
X282367Y566275D01*
X282117Y566025D01*
X282033Y565734D01*
X282117Y565442D01*
X282325Y565234D01*
X282658Y565109D01*
X282950Y565067D01*
G01X286050Y567567D02*
X285717Y567484D01*
X285467Y567275D01*
X285300Y567025D01*
X285175Y566692D01*
X285133Y566317D01*
X285175Y565942D01*
X285300Y565609D01*
X285467Y565359D01*
X285717Y565150D01*
X286050Y565067D01*
X286383Y565150D01*
X286633Y565359D01*
X286800Y565609D01*
X286925Y565942D01*
X286967Y566317D01*
X286925Y566692D01*
X286800Y567025D01*
X286633Y567275D01*
X286383Y567484D01*
X286050Y567567D01*
G01X296855Y544906D02*
Y548906D01*
X289455D01*
G01X296900Y549300D02*
Y553300D01*
X289500D01*
G01X342100Y537217D02*
X339600D01*
Y538258D01*
X339725Y538592D01*
X339892Y538800D01*
X340225Y538883D01*
X340558Y538800D01*
X340767Y538550D01*
X340892Y538258D01*
Y537217D01*
G01Y538258D02*
X342100Y538883D01*
G01Y541150D02*
X339600D01*
X340100Y540650D01*
G01X342100D02*
Y541650D01*
G01X341600Y543333D02*
X341892Y543583D01*
X342058Y543917D01*
X342100Y544292D01*
X342058Y544625D01*
X341850Y544958D01*
X341600Y545167D01*
X341350Y545208D01*
X341058Y545125D01*
X340850Y544833D01*
X340767Y544542D01*
Y544167D01*
G01Y544542D02*
X340642Y544792D01*
X340433Y545000D01*
X340183Y545083D01*
X339933Y545000D01*
X339725Y544792D01*
X339600Y544417D01*
X339642Y544042D01*
X339808Y543667D01*
G01X341600Y546433D02*
X341892Y546683D01*
X342058Y547017D01*
X342100Y547392D01*
X342058Y547725D01*
X341850Y548058D01*
X341600Y548267D01*
X341350Y548308D01*
X341058Y548225D01*
X340850Y547933D01*
X340767Y547642D01*
Y547267D01*
G01Y547642D02*
X340642Y547892D01*
X340433Y548100D01*
X340183Y548183D01*
X339933Y548100D01*
X339725Y547892D01*
X339600Y547517D01*
X339642Y547142D01*
X339808Y546767D01*
G01X302300Y588200D02*
X306300D01*
Y595600D01*
G01X284267Y576467D02*
Y578967D01*
X285308D01*
X285642Y578842D01*
X285850Y578675D01*
X285933Y578342D01*
X285850Y578009D01*
X285600Y577800D01*
X285308Y577675D01*
X284267D01*
G01X285308D02*
X285933Y576467D01*
G01X287408Y577509D02*
X287700Y577800D01*
X287950Y577967D01*
X288283Y578050D01*
X288575Y577967D01*
X288783Y577800D01*
X288950Y577550D01*
X288992Y577259D01*
X288950Y577009D01*
X288783Y576759D01*
X288533Y576550D01*
X288242Y576467D01*
X287908Y576550D01*
X287617Y576800D01*
X287450Y577175D01*
X287408Y577592D01*
X287492Y578134D01*
X287617Y578425D01*
X287825Y578717D01*
X288117Y578925D01*
X288408Y578967D01*
X288700Y578884D01*
X288908Y578675D01*
G01X291300Y576467D02*
Y578967D01*
X290800Y578467D01*
G01Y576467D02*
X291800D01*
G01X294317D02*
X294400Y577009D01*
X294525Y577467D01*
X294692Y577884D01*
X294900Y578342D01*
X295233Y578967D01*
X293567D01*
G01X297032Y580108D02*
Y576108D01*
X304432D01*
G01X276417Y568967D02*
Y571467D01*
X277458D01*
X277792Y571342D01*
X278000Y571175D01*
X278083Y570842D01*
X278000Y570509D01*
X277750Y570300D01*
X277458Y570175D01*
X276417D01*
G01X277458D02*
X278083Y568967D01*
G01X280267D02*
X280350Y569509D01*
X280475Y569967D01*
X280642Y570384D01*
X280850Y570842D01*
X281183Y571467D01*
X279517D01*
G01X282658Y570009D02*
X282950Y570300D01*
X283200Y570467D01*
X283533Y570550D01*
X283825Y570467D01*
X284033Y570300D01*
X284200Y570050D01*
X284242Y569759D01*
X284200Y569509D01*
X284033Y569259D01*
X283783Y569050D01*
X283492Y568967D01*
X283158Y569050D01*
X282867Y569300D01*
X282700Y569675D01*
X282658Y570092D01*
X282742Y570634D01*
X282867Y570925D01*
X283075Y571217D01*
X283367Y571425D01*
X283658Y571467D01*
X283950Y571384D01*
X284158Y571175D01*
G01X285633Y569467D02*
X285883Y569175D01*
X286217Y569009D01*
X286592Y568967D01*
X286925Y569009D01*
X287258Y569217D01*
X287467Y569467D01*
X287508Y569717D01*
X287425Y570009D01*
X287133Y570217D01*
X286842Y570300D01*
X286467D01*
G01X286842D02*
X287092Y570425D01*
X287300Y570634D01*
X287383Y570884D01*
X287300Y571134D01*
X287092Y571342D01*
X286717Y571467D01*
X286342Y571425D01*
X285967Y571259D01*
G01X291400Y575700D02*
Y571700D01*
X298800D01*
G01X292100D02*
Y567700D01*
X299500D01*
G01X289700Y567600D02*
Y563600D01*
X297100D01*
G01X297200Y566200D02*
Y562200D01*
X304600D01*
G01X297476Y559611D02*
Y555611D01*
X304876D01*
G01X332180Y529380D02*
Y533380D01*
X324780D01*
G01X291150Y533300D02*
X295150D01*
Y540700D01*
G01X316181Y591450D02*
X312181D01*
Y584050D01*
G01X337865Y537609D02*
Y541609D01*
X330465D01*
G01X331716Y541816D02*
Y545816D01*
X324316D01*
G01X310633Y537357D02*
Y533357D01*
X318033D01*
G01X310451Y533356D02*
Y537356D01*
X303051D01*
G01X299175Y540454D02*
X295175D01*
Y533054D01*
G01X287050Y533300D02*
X291050D01*
Y540700D01*
G01X331633Y584400D02*
Y582608D01*
X331800Y582233D01*
X332133Y581983D01*
X332550Y581900D01*
X332967Y581983D01*
X333300Y582233D01*
X333467Y582608D01*
Y584400D01*
G01X335650Y581900D02*
Y584400D01*
X335150Y583900D01*
G01Y581900D02*
X336150D01*
G01X338750Y584400D02*
X338417Y584317D01*
X338167Y584108D01*
X338000Y583858D01*
X337875Y583525D01*
X337833Y583150D01*
X337875Y582775D01*
X338000Y582442D01*
X338167Y582192D01*
X338417Y581983D01*
X338750Y581900D01*
X339083Y581983D01*
X339333Y582192D01*
X339500Y582442D01*
X339625Y582775D01*
X339667Y583150D01*
X339625Y583525D01*
X339500Y583858D01*
X339333Y584108D01*
X339083Y584317D01*
X338750Y584400D01*
G01X341058Y583983D02*
X341308Y584233D01*
X341600Y584358D01*
X341933Y584400D01*
X342350Y584317D01*
X342642Y584108D01*
X342725Y583858D01*
X342683Y583608D01*
X342517Y583400D01*
X341683Y582983D01*
X341308Y582692D01*
X341058Y582275D01*
X340975Y581900D01*
X342725D01*
G01X330700Y584500D02*
X317300D01*
G01X330700Y594500D02*
Y584500D01*
G01X317300D02*
Y594500D01*
G01X282933Y559867D02*
Y558075D01*
X283100Y557700D01*
X283433Y557450D01*
X283850Y557367D01*
X284267Y557450D01*
X284600Y557700D01*
X284767Y558075D01*
Y559867D01*
G01X286033Y557742D02*
X286283Y557534D01*
X286575Y557409D01*
X286950Y557367D01*
X287325Y557450D01*
X287617Y557617D01*
X287825Y557909D01*
X287867Y558242D01*
X287783Y558575D01*
X287575Y558784D01*
X287283Y558950D01*
X286992Y558992D01*
X286700Y558950D01*
X286325Y558784D01*
X286450Y559867D01*
X287575D01*
G01X284645Y543694D02*
Y555094D01*
G01X309170Y530491D02*
X313770D01*
G01X310683Y552600D02*
Y550808D01*
X310850Y550433D01*
X311183Y550183D01*
X311600Y550100D01*
X312017Y550183D01*
X312350Y550433D01*
X312517Y550808D01*
Y552600D01*
G01X314700Y550100D02*
Y552600D01*
X314200Y552100D01*
G01Y550100D02*
X315200D01*
G01X317092Y550392D02*
X317383Y550183D01*
X317717Y550100D01*
X318050Y550183D01*
X318342Y550433D01*
X318550Y550808D01*
X318633Y551183D01*
Y551642D01*
X318550Y552017D01*
X318342Y552350D01*
X318092Y552517D01*
X317800Y552600D01*
X317467Y552517D01*
X317217Y552350D01*
X317050Y552100D01*
X316967Y551767D01*
X317050Y551475D01*
X317258Y551183D01*
X317508Y551017D01*
X317800Y550975D01*
X318133Y551058D01*
X318383Y551267D01*
X318633Y551642D01*
G01X312052Y548320D02*
Y548170D01*
X310802Y546920D01*
X309602Y548120D01*
Y548370D01*
G01X302052Y548320D02*
X319252D01*
Y538420D01*
X302052D01*
Y548320D01*
G01X334533Y551800D02*
Y550008D01*
X334700Y549633D01*
X335033Y549383D01*
X335450Y549300D01*
X335867Y549383D01*
X336200Y549633D01*
X336367Y550008D01*
Y551800D01*
G01X338550Y549300D02*
Y551800D01*
X338050Y551300D01*
G01Y549300D02*
X339050D01*
G01X341650Y551800D02*
X341317Y551717D01*
X341067Y551508D01*
X340900Y551258D01*
X340775Y550925D01*
X340733Y550550D01*
X340775Y550175D01*
X340900Y549842D01*
X341067Y549592D01*
X341317Y549383D01*
X341650Y549300D01*
X341983Y549383D01*
X342233Y549592D01*
X342400Y549842D01*
X342525Y550175D01*
X342567Y550550D01*
X342525Y550925D01*
X342400Y551258D01*
X342233Y551508D01*
X341983Y551717D01*
X341650Y551800D01*
G01X343833Y549675D02*
X344083Y549467D01*
X344375Y549342D01*
X344750Y549300D01*
X345125Y549383D01*
X345417Y549550D01*
X345625Y549842D01*
X345667Y550175D01*
X345583Y550508D01*
X345375Y550717D01*
X345083Y550883D01*
X344792Y550925D01*
X344500Y550883D01*
X344125Y550717D01*
X344250Y551800D01*
X345375D01*
G01X290067Y608059D02*
X289817Y608184D01*
X289525Y608267D01*
X289192D01*
X288817Y608142D01*
X288525Y607934D01*
X288317Y607684D01*
X288150Y607267D01*
X288108Y606892D01*
X288192Y606517D01*
X288317Y606267D01*
X288567Y606017D01*
X288858Y605850D01*
X289150Y605767D01*
X289442D01*
X289733Y605850D01*
X289983Y605975D01*
X290192Y606142D01*
G01X291458Y607850D02*
X291708Y608100D01*
X292000Y608225D01*
X292333Y608267D01*
X292750Y608184D01*
X293042Y607975D01*
X293125Y607725D01*
X293083Y607475D01*
X292917Y607267D01*
X292083Y606850D01*
X291708Y606559D01*
X291458Y606142D01*
X291375Y605767D01*
X293125D01*
G01X294433Y606267D02*
X294683Y605975D01*
X295017Y605809D01*
X295392Y605767D01*
X295725Y605809D01*
X296058Y606017D01*
X296267Y606267D01*
X296308Y606517D01*
X296225Y606809D01*
X295933Y607017D01*
X295642Y607100D01*
X295267D01*
G01X295642D02*
X295892Y607225D01*
X296100Y607434D01*
X296183Y607684D01*
X296100Y607934D01*
X295892Y608142D01*
X295517Y608267D01*
X295142Y608225D01*
X294767Y608059D01*
G01X298950Y605767D02*
Y608267D01*
X297408Y606475D01*
X299492D01*
G01X327608Y597767D02*
X327483Y597517D01*
X327400Y597225D01*
Y596892D01*
X327525Y596517D01*
X327733Y596225D01*
X327983Y596017D01*
X328400Y595850D01*
X328775Y595808D01*
X329150Y595892D01*
X329400Y596017D01*
X329650Y596267D01*
X329817Y596558D01*
X329900Y596850D01*
Y597142D01*
X329817Y597433D01*
X329692Y597683D01*
X329525Y597892D01*
G01X327817Y599158D02*
X327567Y599408D01*
X327442Y599700D01*
X327400Y600033D01*
X327483Y600450D01*
X327692Y600742D01*
X327942Y600825D01*
X328192Y600783D01*
X328400Y600617D01*
X328817Y599783D01*
X329108Y599408D01*
X329525Y599158D01*
X329900Y599075D01*
Y600825D01*
G01X329400Y602133D02*
X329692Y602383D01*
X329858Y602717D01*
X329900Y603092D01*
X329858Y603425D01*
X329650Y603758D01*
X329400Y603967D01*
X329150Y604008D01*
X328858Y603925D01*
X328650Y603633D01*
X328567Y603342D01*
Y602967D01*
G01Y603342D02*
X328442Y603592D01*
X328233Y603800D01*
X327983Y603883D01*
X327733Y603800D01*
X327525Y603592D01*
X327400Y603217D01*
X327442Y602842D01*
X327608Y602467D01*
G01X329608Y605442D02*
X329817Y605733D01*
X329900Y606067D01*
X329817Y606400D01*
X329567Y606692D01*
X329192Y606900D01*
X328817Y606983D01*
X328358D01*
X327983Y606900D01*
X327650Y606692D01*
X327483Y606442D01*
X327400Y606150D01*
X327483Y605817D01*
X327650Y605567D01*
X327900Y605400D01*
X328233Y605317D01*
X328525Y605400D01*
X328817Y605608D01*
X328983Y605858D01*
X329025Y606150D01*
X328942Y606483D01*
X328733Y606733D01*
X328358Y606983D01*
G01X281067Y626059D02*
X280817Y626184D01*
X280525Y626267D01*
X280192D01*
X279817Y626142D01*
X279525Y625934D01*
X279317Y625684D01*
X279150Y625267D01*
X279108Y624892D01*
X279192Y624517D01*
X279317Y624267D01*
X279567Y624017D01*
X279858Y623850D01*
X280150Y623767D01*
X280442D01*
X280733Y623850D01*
X280983Y623975D01*
X281192Y624142D01*
G01X282458Y625850D02*
X282708Y626100D01*
X283000Y626225D01*
X283333Y626267D01*
X283750Y626184D01*
X284042Y625975D01*
X284125Y625725D01*
X284083Y625475D01*
X283917Y625267D01*
X283083Y624850D01*
X282708Y624559D01*
X282458Y624142D01*
X282375Y623767D01*
X284125D01*
G01X286850D02*
Y626267D01*
X285308Y624475D01*
X287392D01*
G01X289450Y626267D02*
X289117Y626184D01*
X288867Y625975D01*
X288700Y625725D01*
X288575Y625392D01*
X288533Y625017D01*
X288575Y624642D01*
X288700Y624309D01*
X288867Y624059D01*
X289117Y623850D01*
X289450Y623767D01*
X289783Y623850D01*
X290033Y624059D01*
X290200Y624309D01*
X290325Y624642D01*
X290367Y625017D01*
X290325Y625392D01*
X290200Y625725D01*
X290033Y625975D01*
X289783Y626184D01*
X289450Y626267D01*
G01X328967Y649992D02*
X328717Y650117D01*
X328425Y650200D01*
X328092D01*
X327717Y650075D01*
X327425Y649867D01*
X327217Y649617D01*
X327050Y649200D01*
X327008Y648825D01*
X327092Y648450D01*
X327217Y648200D01*
X327467Y647950D01*
X327758Y647783D01*
X328050Y647700D01*
X328342D01*
X328633Y647783D01*
X328883Y647908D01*
X329092Y648075D01*
G01X330358Y649783D02*
X330608Y650033D01*
X330900Y650158D01*
X331233Y650200D01*
X331650Y650117D01*
X331942Y649908D01*
X332025Y649658D01*
X331983Y649408D01*
X331817Y649200D01*
X330983Y648783D01*
X330608Y648492D01*
X330358Y648075D01*
X330275Y647700D01*
X332025D01*
G01X334750D02*
Y650200D01*
X333208Y648408D01*
X335292D01*
G01X336558Y649783D02*
X336808Y650033D01*
X337100Y650158D01*
X337433Y650200D01*
X337850Y650117D01*
X338142Y649908D01*
X338225Y649658D01*
X338183Y649408D01*
X338017Y649200D01*
X337183Y648783D01*
X336808Y648492D01*
X336558Y648075D01*
X336475Y647700D01*
X338225D01*
G01X280657Y630359D02*
X280407Y630484D01*
X280115Y630567D01*
X279782D01*
X279407Y630442D01*
X279115Y630234D01*
X278907Y629984D01*
X278740Y629567D01*
X278698Y629192D01*
X278782Y628817D01*
X278907Y628567D01*
X279157Y628317D01*
X279448Y628150D01*
X279740Y628067D01*
X280032D01*
X280323Y628150D01*
X280573Y628275D01*
X280782Y628442D01*
G01X282048Y630150D02*
X282298Y630400D01*
X282590Y630525D01*
X282923Y630567D01*
X283340Y630484D01*
X283632Y630275D01*
X283715Y630025D01*
X283673Y629775D01*
X283507Y629567D01*
X282673Y629150D01*
X282298Y628859D01*
X282048Y628442D01*
X281965Y628067D01*
X283715D01*
G01X286440D02*
Y630567D01*
X284898Y628775D01*
X286982D01*
G01X288123Y628442D02*
X288373Y628234D01*
X288665Y628109D01*
X289040Y628067D01*
X289415Y628150D01*
X289707Y628317D01*
X289915Y628609D01*
X289957Y628942D01*
X289873Y629275D01*
X289665Y629484D01*
X289373Y629650D01*
X289082Y629692D01*
X288790Y629650D01*
X288415Y629484D01*
X288540Y630567D01*
X289665D01*
G01X337617Y597058D02*
X337367Y597183D01*
X337075Y597266D01*
X336742D01*
X336367Y597141D01*
X336075Y596933D01*
X335867Y596683D01*
X335700Y596266D01*
X335658Y595891D01*
X335742Y595516D01*
X335867Y595266D01*
X336117Y595016D01*
X336408Y594849D01*
X336700Y594766D01*
X336992D01*
X337283Y594849D01*
X337533Y594974D01*
X337742Y595141D01*
G01X340300Y594766D02*
Y597266D01*
X338758Y595474D01*
X340842D01*
G01X343400Y594766D02*
Y597266D01*
X341858Y595474D01*
X343942D01*
G01X296317Y604258D02*
X296067Y604383D01*
X295775Y604466D01*
X295442D01*
X295067Y604341D01*
X294775Y604133D01*
X294567Y603883D01*
X294400Y603466D01*
X294358Y603091D01*
X294442Y602716D01*
X294567Y602466D01*
X294817Y602216D01*
X295108Y602049D01*
X295400Y601966D01*
X295692D01*
X295983Y602049D01*
X296233Y602174D01*
X296442Y602341D01*
G01X298417Y601966D02*
X298500Y602508D01*
X298625Y602966D01*
X298792Y603383D01*
X299000Y603841D01*
X299333Y604466D01*
X297667D01*
G01X300683Y602341D02*
X300933Y602133D01*
X301225Y602008D01*
X301600Y601966D01*
X301975Y602049D01*
X302267Y602216D01*
X302475Y602508D01*
X302517Y602841D01*
X302433Y603174D01*
X302225Y603383D01*
X301933Y603549D01*
X301642Y603591D01*
X301350Y603549D01*
X300975Y603383D01*
X301100Y604466D01*
X302225D01*
G01X286417Y604158D02*
X286167Y604283D01*
X285875Y604366D01*
X285542D01*
X285167Y604241D01*
X284875Y604033D01*
X284667Y603783D01*
X284500Y603366D01*
X284458Y602991D01*
X284542Y602616D01*
X284667Y602366D01*
X284917Y602116D01*
X285208Y601949D01*
X285500Y601866D01*
X285792D01*
X286083Y601949D01*
X286333Y602074D01*
X286542Y602241D01*
G01X288517Y601866D02*
X288600Y602408D01*
X288725Y602866D01*
X288892Y603283D01*
X289100Y603741D01*
X289433Y604366D01*
X287767D01*
G01X290908Y602908D02*
X291200Y603199D01*
X291450Y603366D01*
X291783Y603449D01*
X292075Y603366D01*
X292283Y603199D01*
X292450Y602949D01*
X292492Y602658D01*
X292450Y602408D01*
X292283Y602158D01*
X292033Y601949D01*
X291742Y601866D01*
X291408Y601949D01*
X291117Y602199D01*
X290950Y602574D01*
X290908Y602991D01*
X290992Y603533D01*
X291117Y603824D01*
X291325Y604116D01*
X291617Y604324D01*
X291908Y604366D01*
X292200Y604283D01*
X292408Y604074D01*
G01X337908Y635267D02*
X337783Y635017D01*
X337700Y634725D01*
Y634392D01*
X337825Y634017D01*
X338033Y633725D01*
X338283Y633517D01*
X338700Y633350D01*
X339075Y633308D01*
X339450Y633392D01*
X339700Y633517D01*
X339950Y633767D01*
X340117Y634058D01*
X340200Y634350D01*
Y634642D01*
X340117Y634933D01*
X339992Y635183D01*
X339825Y635392D01*
G01X338117Y636658D02*
X337867Y636908D01*
X337742Y637200D01*
X337700Y637533D01*
X337783Y637950D01*
X337992Y638242D01*
X338242Y638325D01*
X338492Y638283D01*
X338700Y638117D01*
X339117Y637283D01*
X339408Y636908D01*
X339825Y636658D01*
X340200Y636575D01*
Y638325D01*
G01X339700Y639633D02*
X339992Y639883D01*
X340158Y640217D01*
X340200Y640592D01*
X340158Y640925D01*
X339950Y641258D01*
X339700Y641467D01*
X339450Y641508D01*
X339158Y641425D01*
X338950Y641133D01*
X338867Y640842D01*
Y640467D01*
G01Y640842D02*
X338742Y641092D01*
X338533Y641300D01*
X338283Y641383D01*
X338033Y641300D01*
X337825Y641092D01*
X337700Y640717D01*
X337742Y640342D01*
X337908Y639967D01*
G01X339825Y642733D02*
X340033Y642983D01*
X340158Y643275D01*
X340200Y643650D01*
X340117Y644025D01*
X339950Y644317D01*
X339658Y644525D01*
X339325Y644567D01*
X338992Y644483D01*
X338783Y644275D01*
X338617Y643983D01*
X338575Y643692D01*
X338617Y643400D01*
X338783Y643025D01*
X337700Y643150D01*
Y644275D01*
G01X337467Y600792D02*
X337217Y600917D01*
X336925Y601000D01*
X336592D01*
X336217Y600875D01*
X335925Y600667D01*
X335717Y600417D01*
X335550Y600000D01*
X335508Y599625D01*
X335592Y599250D01*
X335717Y599000D01*
X335967Y598750D01*
X336258Y598583D01*
X336550Y598500D01*
X336842D01*
X337133Y598583D01*
X337383Y598708D01*
X337592Y598875D01*
G01X338858Y600583D02*
X339108Y600833D01*
X339400Y600958D01*
X339733Y601000D01*
X340150Y600917D01*
X340442Y600708D01*
X340525Y600458D01*
X340483Y600208D01*
X340317Y600000D01*
X339483Y599583D01*
X339108Y599292D01*
X338858Y598875D01*
X338775Y598500D01*
X340525D01*
G01X341833Y599000D02*
X342083Y598708D01*
X342417Y598542D01*
X342792Y598500D01*
X343125Y598542D01*
X343458Y598750D01*
X343667Y599000D01*
X343708Y599250D01*
X343625Y599542D01*
X343333Y599750D01*
X343042Y599833D01*
X342667D01*
G01X343042D02*
X343292Y599958D01*
X343500Y600167D01*
X343583Y600417D01*
X343500Y600667D01*
X343292Y600875D01*
X342917Y601000D01*
X342542Y600958D01*
X342167Y600792D01*
G01X345058Y599542D02*
X345350Y599833D01*
X345600Y600000D01*
X345933Y600083D01*
X346225Y600000D01*
X346433Y599833D01*
X346600Y599583D01*
X346642Y599292D01*
X346600Y599042D01*
X346433Y598792D01*
X346183Y598583D01*
X345892Y598500D01*
X345558Y598583D01*
X345267Y598833D01*
X345100Y599208D01*
X345058Y599625D01*
X345142Y600167D01*
X345267Y600458D01*
X345475Y600750D01*
X345767Y600958D01*
X346058Y601000D01*
X346350Y600917D01*
X346558Y600708D01*
G01X337708Y620467D02*
X337583Y620217D01*
X337500Y619925D01*
Y619592D01*
X337625Y619217D01*
X337833Y618925D01*
X338083Y618717D01*
X338500Y618550D01*
X338875Y618508D01*
X339250Y618592D01*
X339500Y618717D01*
X339750Y618967D01*
X339917Y619258D01*
X340000Y619550D01*
Y619842D01*
X339917Y620133D01*
X339792Y620383D01*
X339625Y620592D01*
G01X337917Y621858D02*
X337667Y622108D01*
X337542Y622400D01*
X337500Y622733D01*
X337583Y623150D01*
X337792Y623442D01*
X338042Y623525D01*
X338292Y623483D01*
X338500Y623317D01*
X338917Y622483D01*
X339208Y622108D01*
X339625Y621858D01*
X340000Y621775D01*
Y623525D01*
G01X339500Y624833D02*
X339792Y625083D01*
X339958Y625417D01*
X340000Y625792D01*
X339958Y626125D01*
X339750Y626458D01*
X339500Y626667D01*
X339250Y626708D01*
X338958Y626625D01*
X338750Y626333D01*
X338667Y626042D01*
Y625667D01*
G01Y626042D02*
X338542Y626292D01*
X338333Y626500D01*
X338083Y626583D01*
X337833Y626500D01*
X337625Y626292D01*
X337500Y625917D01*
X337542Y625542D01*
X337708Y625167D01*
G01X340000Y628850D02*
X339958Y629142D01*
X339833Y629475D01*
X339625Y629683D01*
X339333Y629767D01*
X339042Y629683D01*
X338792Y629433D01*
X338667Y629058D01*
Y628642D01*
X338583Y628392D01*
X338375Y628183D01*
X338083Y628100D01*
X337792Y628225D01*
X337583Y628517D01*
X337500Y628850D01*
X337583Y629183D01*
X337792Y629475D01*
X338083Y629600D01*
X338375Y629517D01*
X338583Y629308D01*
X338667Y629058D01*
Y628642D01*
X338792Y628267D01*
X339042Y628017D01*
X339333Y627933D01*
X339625Y628017D01*
X339833Y628225D01*
X339958Y628558D01*
X340000Y628850D01*
G01X287617Y620200D02*
Y622700D01*
X288658D01*
X288992Y622575D01*
X289200Y622408D01*
X289283Y622075D01*
X289200Y621742D01*
X288950Y621533D01*
X288658Y621408D01*
X287617D01*
G01X288658D02*
X289283Y620200D01*
G01X290633Y620700D02*
X290883Y620408D01*
X291217Y620242D01*
X291592Y620200D01*
X291925Y620242D01*
X292258Y620450D01*
X292467Y620700D01*
X292508Y620950D01*
X292425Y621242D01*
X292133Y621450D01*
X291842Y621533D01*
X291467D01*
G01X291842D02*
X292092Y621658D01*
X292300Y621867D01*
X292383Y622117D01*
X292300Y622367D01*
X292092Y622575D01*
X291717Y622700D01*
X291342Y622658D01*
X290967Y622492D01*
G01X294650Y622700D02*
X294317Y622617D01*
X294067Y622408D01*
X293900Y622158D01*
X293775Y621825D01*
X293733Y621450D01*
X293775Y621075D01*
X293900Y620742D01*
X294067Y620492D01*
X294317Y620283D01*
X294650Y620200D01*
X294983Y620283D01*
X295233Y620492D01*
X295400Y620742D01*
X295525Y621075D01*
X295567Y621450D01*
X295525Y621825D01*
X295400Y622158D01*
X295233Y622408D01*
X294983Y622617D01*
X294650Y622700D01*
G01X296833Y620575D02*
X297083Y620367D01*
X297375Y620242D01*
X297750Y620200D01*
X298125Y620283D01*
X298417Y620450D01*
X298625Y620742D01*
X298667Y621075D01*
X298583Y621408D01*
X298375Y621617D01*
X298083Y621783D01*
X297792Y621825D01*
X297500Y621783D01*
X297125Y621617D01*
X297250Y622700D01*
X298375D01*
G01X293000Y615000D02*
Y619000D01*
X285600D01*
G01X288317Y609367D02*
Y611867D01*
X289358D01*
X289692Y611742D01*
X289900Y611575D01*
X289983Y611242D01*
X289900Y610909D01*
X289650Y610700D01*
X289358Y610575D01*
X288317D01*
G01X289358D02*
X289983Y609367D01*
G01X291333Y609742D02*
X291583Y609534D01*
X291875Y609409D01*
X292250Y609367D01*
X292625Y609450D01*
X292917Y609617D01*
X293125Y609909D01*
X293167Y610242D01*
X293083Y610575D01*
X292875Y610784D01*
X292583Y610950D01*
X292292Y610992D01*
X292000Y610950D01*
X291625Y610784D01*
X291750Y611867D01*
X292875D01*
G01X294433Y609867D02*
X294683Y609575D01*
X295017Y609409D01*
X295392Y609367D01*
X295725Y609409D01*
X296058Y609617D01*
X296267Y609867D01*
X296308Y610117D01*
X296225Y610409D01*
X295933Y610617D01*
X295642Y610700D01*
X295267D01*
G01X295642D02*
X295892Y610825D01*
X296100Y611034D01*
X296183Y611284D01*
X296100Y611534D01*
X295892Y611742D01*
X295517Y611867D01*
X295142Y611825D01*
X294767Y611659D01*
G01X298367Y609367D02*
X298450Y609909D01*
X298575Y610367D01*
X298742Y610784D01*
X298950Y611242D01*
X299283Y611867D01*
X297617D01*
G01X307400Y614384D02*
Y618384D01*
X300000D01*
G01X308717Y616767D02*
Y619267D01*
X309758D01*
X310092Y619142D01*
X310300Y618975D01*
X310383Y618642D01*
X310300Y618309D01*
X310050Y618100D01*
X309758Y617975D01*
X308717D01*
G01X309758D02*
X310383Y616767D01*
G01X311733Y617142D02*
X311983Y616934D01*
X312275Y616809D01*
X312650Y616767D01*
X313025Y616850D01*
X313317Y617017D01*
X313525Y617309D01*
X313567Y617642D01*
X313483Y617975D01*
X313275Y618184D01*
X312983Y618350D01*
X312692Y618392D01*
X312400Y618350D01*
X312025Y618184D01*
X312150Y619267D01*
X313275D01*
G01X314833Y617267D02*
X315083Y616975D01*
X315417Y616809D01*
X315792Y616767D01*
X316125Y616809D01*
X316458Y617017D01*
X316667Y617267D01*
X316708Y617517D01*
X316625Y617809D01*
X316333Y618017D01*
X316042Y618100D01*
X315667D01*
G01X316042D02*
X316292Y618225D01*
X316500Y618434D01*
X316583Y618684D01*
X316500Y618934D01*
X316292Y619142D01*
X315917Y619267D01*
X315542Y619225D01*
X315167Y619059D01*
G01X318850Y616767D02*
X319142Y616809D01*
X319475Y616934D01*
X319683Y617142D01*
X319767Y617434D01*
X319683Y617725D01*
X319433Y617975D01*
X319058Y618100D01*
X318642D01*
X318392Y618184D01*
X318183Y618392D01*
X318100Y618684D01*
X318225Y618975D01*
X318517Y619184D01*
X318850Y619267D01*
X319183Y619184D01*
X319475Y618975D01*
X319600Y618684D01*
X319517Y618392D01*
X319308Y618184D01*
X319058Y618100D01*
X318642D01*
X318267Y617975D01*
X318017Y617725D01*
X317933Y617434D01*
X318017Y617142D01*
X318225Y616934D01*
X318558Y616809D01*
X318850Y616767D01*
G01X300048Y622477D02*
Y618477D01*
X307448D01*
G01X307100Y663500D02*
X303100D01*
Y656100D01*
G01X279207Y632167D02*
Y634667D01*
X280248D01*
X280582Y634542D01*
X280790Y634375D01*
X280873Y634042D01*
X280790Y633709D01*
X280540Y633500D01*
X280248Y633375D01*
X279207D01*
G01X280248D02*
X280873Y632167D01*
G01X282223Y632542D02*
X282473Y632334D01*
X282765Y632209D01*
X283140Y632167D01*
X283515Y632250D01*
X283807Y632417D01*
X284015Y632709D01*
X284057Y633042D01*
X283973Y633375D01*
X283765Y633584D01*
X283473Y633750D01*
X283182Y633792D01*
X282890Y633750D01*
X282515Y633584D01*
X282640Y634667D01*
X283765D01*
G01X286740Y632167D02*
Y634667D01*
X285198Y632875D01*
X287282D01*
G01X289340Y632167D02*
Y634667D01*
X288840Y634167D01*
G01Y632167D02*
X289840D01*
G01X279960Y649950D02*
Y645950D01*
X287360D01*
G01X275977Y654867D02*
Y657367D01*
X277018D01*
X277352Y657242D01*
X277560Y657075D01*
X277643Y656742D01*
X277560Y656409D01*
X277310Y656200D01*
X277018Y656075D01*
X275977D01*
G01X277018D02*
X277643Y654867D01*
G01X278993Y655242D02*
X279243Y655034D01*
X279535Y654909D01*
X279910Y654867D01*
X280285Y654950D01*
X280577Y655117D01*
X280785Y655409D01*
X280827Y655742D01*
X280743Y656075D01*
X280535Y656284D01*
X280243Y656450D01*
X279952Y656492D01*
X279660Y656450D01*
X279285Y656284D01*
X279410Y657367D01*
X280535D01*
G01X283510Y654867D02*
Y657367D01*
X281968Y655575D01*
X284052D01*
G01X285318Y656950D02*
X285568Y657200D01*
X285860Y657325D01*
X286193Y657367D01*
X286610Y657284D01*
X286902Y657075D01*
X286985Y656825D01*
X286943Y656575D01*
X286777Y656367D01*
X285943Y655950D01*
X285568Y655659D01*
X285318Y655242D01*
X285235Y654867D01*
X286985D01*
G01X279960Y654100D02*
Y650100D01*
X287360D01*
G01X278133Y640867D02*
X275633D01*
Y641908D01*
X275758Y642242D01*
X275925Y642450D01*
X276258Y642533D01*
X276591Y642450D01*
X276800Y642200D01*
X276925Y641908D01*
Y640867D01*
G01Y641908D02*
X278133Y642533D01*
G01Y644717D02*
X277591Y644800D01*
X277133Y644925D01*
X276716Y645092D01*
X276258Y645300D01*
X275633Y645633D01*
Y643967D01*
G01X277633Y646983D02*
X277925Y647233D01*
X278091Y647567D01*
X278133Y647942D01*
X278091Y648275D01*
X277883Y648608D01*
X277633Y648817D01*
X277383Y648858D01*
X277091Y648775D01*
X276883Y648483D01*
X276800Y648192D01*
Y647817D01*
G01Y648192D02*
X276675Y648442D01*
X276466Y648650D01*
X276216Y648733D01*
X275966Y648650D01*
X275758Y648442D01*
X275633Y648067D01*
X275675Y647692D01*
X275841Y647317D01*
G01X307034Y598717D02*
X304534D01*
Y599758D01*
X304659Y600092D01*
X304826Y600300D01*
X305159Y600383D01*
X305492Y600300D01*
X305701Y600050D01*
X305826Y599758D01*
Y598717D01*
G01Y599758D02*
X307034Y600383D01*
G01Y602567D02*
X306492Y602650D01*
X306034Y602775D01*
X305617Y602942D01*
X305159Y603150D01*
X304534Y603483D01*
Y601817D01*
G01X307034Y605750D02*
X304534D01*
X305034Y605250D01*
G01X307034D02*
Y606250D01*
G01Y608767D02*
X306492Y608850D01*
X306034Y608975D01*
X305617Y609142D01*
X305159Y609350D01*
X304534Y609683D01*
Y608017D01*
G01X322100Y596217D02*
X319600D01*
Y597258D01*
X319725Y597592D01*
X319892Y597800D01*
X320225Y597883D01*
X320558Y597800D01*
X320767Y597550D01*
X320892Y597258D01*
Y596217D01*
G01Y597258D02*
X322100Y597883D01*
G01X321725Y599233D02*
X321933Y599483D01*
X322058Y599775D01*
X322100Y600150D01*
X322017Y600525D01*
X321850Y600817D01*
X321558Y601025D01*
X321225Y601067D01*
X320892Y600983D01*
X320683Y600775D01*
X320517Y600483D01*
X320475Y600192D01*
X320517Y599900D01*
X320683Y599525D01*
X319600Y599650D01*
Y600775D01*
G01X321808Y602542D02*
X322017Y602833D01*
X322100Y603167D01*
X322017Y603500D01*
X321767Y603792D01*
X321392Y604000D01*
X321017Y604083D01*
X320558D01*
X320183Y604000D01*
X319850Y603792D01*
X319683Y603542D01*
X319600Y603250D01*
X319683Y602917D01*
X319850Y602667D01*
X320100Y602500D01*
X320433Y602417D01*
X320725Y602500D01*
X321017Y602708D01*
X321183Y602958D01*
X321225Y603250D01*
X321142Y603583D01*
X320933Y603833D01*
X320558Y604083D01*
G01X321058Y605558D02*
X320767Y605850D01*
X320600Y606100D01*
X320517Y606433D01*
X320600Y606725D01*
X320767Y606933D01*
X321017Y607100D01*
X321308Y607142D01*
X321558Y607100D01*
X321808Y606933D01*
X322017Y606683D01*
X322100Y606392D01*
X322017Y606058D01*
X321767Y605767D01*
X321392Y605600D01*
X320975Y605558D01*
X320433Y605642D01*
X320142Y605767D01*
X319850Y605975D01*
X319642Y606267D01*
X319600Y606558D01*
X319683Y606850D01*
X319892Y607058D01*
G01X279600Y600200D02*
X277800Y598100D01*
X275600Y600200D01*
G01X317300Y594500D02*
X330700D01*
G01X324936Y667230D02*
Y653230D01*
G01X337936D02*
Y667230D01*
G01X324936Y653230D02*
X337936D01*
G01X325900Y596117D02*
X323400D01*
Y597158D01*
X323525Y597492D01*
X323692Y597700D01*
X324025Y597783D01*
X324358Y597700D01*
X324567Y597450D01*
X324692Y597158D01*
Y596117D01*
G01Y597158D02*
X325900Y597783D01*
G01X325525Y599133D02*
X325733Y599383D01*
X325858Y599675D01*
X325900Y600050D01*
X325817Y600425D01*
X325650Y600717D01*
X325358Y600925D01*
X325025Y600967D01*
X324692Y600883D01*
X324483Y600675D01*
X324317Y600383D01*
X324275Y600092D01*
X324317Y599800D01*
X324483Y599425D01*
X323400Y599550D01*
Y600675D01*
G01X325400Y602233D02*
X325692Y602483D01*
X325858Y602817D01*
X325900Y603192D01*
X325858Y603525D01*
X325650Y603858D01*
X325400Y604067D01*
X325150Y604108D01*
X324858Y604025D01*
X324650Y603733D01*
X324567Y603442D01*
Y603067D01*
G01Y603442D02*
X324442Y603692D01*
X324233Y603900D01*
X323983Y603983D01*
X323733Y603900D01*
X323525Y603692D01*
X323400Y603317D01*
X323442Y602942D01*
X323608Y602567D01*
G01X324858Y605458D02*
X324567Y605750D01*
X324400Y606000D01*
X324317Y606333D01*
X324400Y606625D01*
X324567Y606833D01*
X324817Y607000D01*
X325108Y607042D01*
X325358Y607000D01*
X325608Y606833D01*
X325817Y606583D01*
X325900Y606292D01*
X325817Y605958D01*
X325567Y605667D01*
X325192Y605500D01*
X324775Y605458D01*
X324233Y605542D01*
X323942Y605667D01*
X323650Y605875D01*
X323442Y606167D01*
X323400Y606458D01*
X323483Y606750D01*
X323692Y606958D01*
G01X308436Y598596D02*
Y603796D01*
G01X315436Y598596D02*
Y606396D01*
G01X308436Y598596D02*
X315436D01*
G01X308436Y611996D02*
Y603296D01*
G01X315436Y611996D02*
X308436D01*
G01X315436Y605596D02*
Y611996D01*
G01X291234Y636717D02*
X288734D01*
Y637717D01*
X288859Y638050D01*
X289151Y638300D01*
X289484Y638383D01*
X289817Y638300D01*
X290067Y638092D01*
X290192Y637717D01*
Y636717D01*
G01X288734Y639733D02*
X290526D01*
X290901Y639900D01*
X291151Y640233D01*
X291234Y640650D01*
X291151Y641067D01*
X290901Y641400D01*
X290526Y641567D01*
X288734D01*
G01X291234Y643750D02*
X288734D01*
X289234Y643250D01*
G01X291234D02*
Y644250D01*
G01Y646850D02*
X288734D01*
X289234Y646350D01*
G01X291234D02*
Y647350D01*
G01X292450Y629750D02*
Y624750D01*
X297450D01*
G01Y652450D02*
X292450D01*
Y647450D01*
G01X320150D02*
Y652450D01*
X315150D01*
G01X311418Y626157D02*
Y623157D01*
G01X301182Y651043D02*
Y654043D01*
G01X293857Y633482D02*
X291857D01*
G01X318743Y643718D02*
X320743D01*
G01X276975Y605717D02*
X278725Y608217D01*
G01X276975D02*
X278725Y605717D01*
G01X280158Y607800D02*
X280408Y608050D01*
X280700Y608175D01*
X281033Y608217D01*
X281450Y608134D01*
X281742Y607925D01*
X281825Y607675D01*
X281783Y607425D01*
X281617Y607217D01*
X280783Y606800D01*
X280408Y606509D01*
X280158Y606092D01*
X280075Y605717D01*
X281825D01*
G01X341967Y706950D02*
X336967Y710450D01*
G01Y706950D02*
X341967Y710450D01*
G01Y714300D02*
X336967D01*
X337967Y713300D01*
G01X341967D02*
Y715300D01*
G01X342134Y719900D02*
X342050Y719733D01*
X341884D01*
X341800Y719900D01*
X341884Y720067D01*
X342050D01*
X342134Y719900D01*
G01X339884D02*
X339800Y719733D01*
X339634D01*
X339550Y719900D01*
X339634Y720067D01*
X339800D01*
X339884Y719900D01*
G01X337800Y723917D02*
X337300Y724417D01*
X337050Y725000D01*
X336967Y725667D01*
X337134Y726500D01*
X337550Y727083D01*
X338050Y727250D01*
X338550Y727167D01*
X338967Y726833D01*
X339800Y725167D01*
X340384Y724417D01*
X341217Y723917D01*
X341967Y723750D01*
Y727250D01*
G01Y732100D02*
X336967D01*
X340550Y729017D01*
Y733183D01*
G01X341967Y734533D02*
X336967D01*
X341134Y736700D01*
X336967Y738867D01*
X341967D01*
G01Y740550D02*
X336967D01*
G01Y744050D02*
X341967D01*
G01X339467D02*
Y740550D01*
G01X336967Y746317D02*
Y749483D01*
X341967Y746317D01*
Y749483D01*
G01X288267Y677359D02*
X288017Y677484D01*
X287725Y677567D01*
X287392D01*
X287017Y677442D01*
X286725Y677234D01*
X286517Y676984D01*
X286350Y676567D01*
X286308Y676192D01*
X286392Y675817D01*
X286517Y675567D01*
X286767Y675317D01*
X287058Y675150D01*
X287350Y675067D01*
X287642D01*
X287933Y675150D01*
X288183Y675275D01*
X288392Y675442D01*
G01X290450Y675067D02*
Y677567D01*
X289950Y677067D01*
G01Y675067D02*
X290950D01*
G01X292842Y675359D02*
X293133Y675150D01*
X293467Y675067D01*
X293800Y675150D01*
X294092Y675400D01*
X294300Y675775D01*
X294383Y676150D01*
Y676609D01*
X294300Y676984D01*
X294092Y677317D01*
X293842Y677484D01*
X293550Y677567D01*
X293217Y677484D01*
X292967Y677317D01*
X292800Y677067D01*
X292717Y676734D01*
X292800Y676442D01*
X293008Y676150D01*
X293258Y675984D01*
X293550Y675942D01*
X293883Y676025D01*
X294133Y676234D01*
X294383Y676609D01*
G01X296650Y677567D02*
X296317Y677484D01*
X296067Y677275D01*
X295900Y677025D01*
X295775Y676692D01*
X295733Y676317D01*
X295775Y675942D01*
X295900Y675609D01*
X296067Y675359D01*
X296317Y675150D01*
X296650Y675067D01*
X296983Y675150D01*
X297233Y675359D01*
X297400Y675609D01*
X297525Y675942D01*
X297567Y676317D01*
X297525Y676692D01*
X297400Y677025D01*
X297233Y677275D01*
X296983Y677484D01*
X296650Y677567D01*
G01X302208Y679767D02*
X302083Y679517D01*
X302000Y679225D01*
Y678892D01*
X302125Y678517D01*
X302333Y678225D01*
X302583Y678017D01*
X303000Y677850D01*
X303375Y677808D01*
X303750Y677892D01*
X304000Y678017D01*
X304250Y678267D01*
X304417Y678558D01*
X304500Y678850D01*
Y679142D01*
X304417Y679433D01*
X304292Y679683D01*
X304125Y679892D01*
G01X304500Y681950D02*
X302000D01*
X302500Y681450D01*
G01X304500D02*
Y682450D01*
G01X304208Y684342D02*
X304417Y684633D01*
X304500Y684967D01*
X304417Y685300D01*
X304167Y685592D01*
X303792Y685800D01*
X303417Y685883D01*
X302958D01*
X302583Y685800D01*
X302250Y685592D01*
X302083Y685342D01*
X302000Y685050D01*
X302083Y684717D01*
X302250Y684467D01*
X302500Y684300D01*
X302833Y684217D01*
X303125Y684300D01*
X303417Y684508D01*
X303583Y684758D01*
X303625Y685050D01*
X303542Y685383D01*
X303333Y685633D01*
X302958Y685883D01*
G01X304125Y687233D02*
X304333Y687483D01*
X304458Y687775D01*
X304500Y688150D01*
X304417Y688525D01*
X304250Y688817D01*
X303958Y689025D01*
X303625Y689067D01*
X303292Y688983D01*
X303083Y688775D01*
X302917Y688483D01*
X302875Y688192D01*
X302917Y687900D01*
X303083Y687525D01*
X302000Y687650D01*
Y688775D01*
G01X332742Y715667D02*
X332617Y715417D01*
X332534Y715125D01*
Y714792D01*
X332659Y714417D01*
X332867Y714125D01*
X333117Y713917D01*
X333534Y713750D01*
X333909Y713708D01*
X334284Y713792D01*
X334534Y713917D01*
X334784Y714167D01*
X334951Y714458D01*
X335034Y714750D01*
Y715042D01*
X334951Y715333D01*
X334826Y715583D01*
X334659Y715792D01*
G01X332951Y717058D02*
X332701Y717308D01*
X332576Y717600D01*
X332534Y717933D01*
X332617Y718350D01*
X332826Y718642D01*
X333076Y718725D01*
X333326Y718683D01*
X333534Y718517D01*
X333951Y717683D01*
X334242Y717308D01*
X334659Y717058D01*
X335034Y716975D01*
Y718725D01*
G01Y721450D02*
X332534D01*
X334326Y719908D01*
Y721992D01*
G01X334534Y723133D02*
X334826Y723383D01*
X334992Y723717D01*
X335034Y724092D01*
X334992Y724425D01*
X334784Y724758D01*
X334534Y724967D01*
X334284Y725008D01*
X333992Y724925D01*
X333784Y724633D01*
X333701Y724342D01*
Y723967D01*
G01Y724342D02*
X333576Y724592D01*
X333367Y724800D01*
X333117Y724883D01*
X332867Y724800D01*
X332659Y724592D01*
X332534Y724217D01*
X332576Y723842D01*
X332742Y723467D01*
G01X328842Y715467D02*
X328717Y715217D01*
X328634Y714925D01*
Y714592D01*
X328759Y714217D01*
X328967Y713925D01*
X329217Y713717D01*
X329634Y713550D01*
X330009Y713508D01*
X330384Y713592D01*
X330634Y713717D01*
X330884Y713967D01*
X331051Y714258D01*
X331134Y714550D01*
Y714842D01*
X331051Y715133D01*
X330926Y715383D01*
X330759Y715592D01*
G01X329051Y716858D02*
X328801Y717108D01*
X328676Y717400D01*
X328634Y717733D01*
X328717Y718150D01*
X328926Y718442D01*
X329176Y718525D01*
X329426Y718483D01*
X329634Y718317D01*
X330051Y717483D01*
X330342Y717108D01*
X330759Y716858D01*
X331134Y716775D01*
Y718525D01*
G01Y721250D02*
X328634D01*
X330426Y719708D01*
Y721792D01*
G01X331134Y724350D02*
X328634D01*
X330426Y722808D01*
Y724892D01*
G01X286417Y671267D02*
Y673767D01*
X287458D01*
X287792Y673642D01*
X288000Y673475D01*
X288083Y673142D01*
X288000Y672809D01*
X287750Y672600D01*
X287458Y672475D01*
X286417D01*
G01X287458D02*
X288083Y671267D01*
G01X289433Y671642D02*
X289683Y671434D01*
X289975Y671309D01*
X290350Y671267D01*
X290725Y671350D01*
X291017Y671517D01*
X291225Y671809D01*
X291267Y672142D01*
X291183Y672475D01*
X290975Y672684D01*
X290683Y672850D01*
X290392Y672892D01*
X290100Y672850D01*
X289725Y672684D01*
X289850Y673767D01*
X290975D01*
G01X293450D02*
X293117Y673684D01*
X292867Y673475D01*
X292700Y673225D01*
X292575Y672892D01*
X292533Y672517D01*
X292575Y672142D01*
X292700Y671809D01*
X292867Y671559D01*
X293117Y671350D01*
X293450Y671267D01*
X293783Y671350D01*
X294033Y671559D01*
X294200Y671809D01*
X294325Y672142D01*
X294367Y672517D01*
X294325Y672892D01*
X294200Y673225D01*
X294033Y673475D01*
X293783Y673684D01*
X293450Y673767D01*
G01X295633Y671642D02*
X295883Y671434D01*
X296175Y671309D01*
X296550Y671267D01*
X296925Y671350D01*
X297217Y671517D01*
X297425Y671809D01*
X297467Y672142D01*
X297383Y672475D01*
X297175Y672684D01*
X296883Y672850D01*
X296592Y672892D01*
X296300Y672850D01*
X295925Y672684D01*
X296050Y673767D01*
X297175D01*
G01X296718Y682153D02*
Y686153D01*
X289318D01*
G01X286417Y678667D02*
Y681167D01*
X287458D01*
X287792Y681042D01*
X288000Y680875D01*
X288083Y680542D01*
X288000Y680209D01*
X287750Y680000D01*
X287458Y679875D01*
X286417D01*
G01X287458D02*
X288083Y678667D01*
G01X289433Y679042D02*
X289683Y678834D01*
X289975Y678709D01*
X290350Y678667D01*
X290725Y678750D01*
X291017Y678917D01*
X291225Y679209D01*
X291267Y679542D01*
X291183Y679875D01*
X290975Y680084D01*
X290683Y680250D01*
X290392Y680292D01*
X290100Y680250D01*
X289725Y680084D01*
X289850Y681167D01*
X290975D01*
G01X293450D02*
X293117Y681084D01*
X292867Y680875D01*
X292700Y680625D01*
X292575Y680292D01*
X292533Y679917D01*
X292575Y679542D01*
X292700Y679209D01*
X292867Y678959D01*
X293117Y678750D01*
X293450Y678667D01*
X293783Y678750D01*
X294033Y678959D01*
X294200Y679209D01*
X294325Y679542D01*
X294367Y679917D01*
X294325Y680292D01*
X294200Y680625D01*
X294033Y680875D01*
X293783Y681084D01*
X293450Y681167D01*
G01X295758Y679709D02*
X296050Y680000D01*
X296300Y680167D01*
X296633Y680250D01*
X296925Y680167D01*
X297133Y680000D01*
X297300Y679750D01*
X297342Y679459D01*
X297300Y679209D01*
X297133Y678959D01*
X296883Y678750D01*
X296592Y678667D01*
X296258Y678750D01*
X295967Y679000D01*
X295800Y679375D01*
X295758Y679792D01*
X295842Y680334D01*
X295967Y680625D01*
X296175Y680917D01*
X296467Y681125D01*
X296758Y681167D01*
X297050Y681084D01*
X297258Y680875D01*
G01X289382Y693947D02*
Y689947D01*
X296782D01*
G01X327434Y714017D02*
X324934D01*
Y715058D01*
X325059Y715392D01*
X325226Y715600D01*
X325559Y715683D01*
X325892Y715600D01*
X326101Y715350D01*
X326226Y715058D01*
Y714017D01*
G01Y715058D02*
X327434Y715683D01*
G01X327059Y717033D02*
X327267Y717283D01*
X327392Y717575D01*
X327434Y717950D01*
X327351Y718325D01*
X327184Y718617D01*
X326892Y718825D01*
X326559Y718867D01*
X326226Y718783D01*
X326017Y718575D01*
X325851Y718283D01*
X325809Y717992D01*
X325851Y717700D01*
X326017Y717325D01*
X324934Y717450D01*
Y718575D01*
G01X326934Y720133D02*
X327226Y720383D01*
X327392Y720717D01*
X327434Y721092D01*
X327392Y721425D01*
X327184Y721758D01*
X326934Y721967D01*
X326684Y722008D01*
X326392Y721925D01*
X326184Y721633D01*
X326101Y721342D01*
Y720967D01*
G01Y721342D02*
X325976Y721592D01*
X325767Y721800D01*
X325517Y721883D01*
X325267Y721800D01*
X325059Y721592D01*
X324934Y721217D01*
X324976Y720842D01*
X325142Y720467D01*
G01X327142Y723442D02*
X327351Y723733D01*
X327434Y724067D01*
X327351Y724400D01*
X327101Y724692D01*
X326726Y724900D01*
X326351Y724983D01*
X325892D01*
X325517Y724900D01*
X325184Y724692D01*
X325017Y724442D01*
X324934Y724150D01*
X325017Y723817D01*
X325184Y723567D01*
X325434Y723400D01*
X325767Y723317D01*
X326059Y723400D01*
X326351Y723608D01*
X326517Y723858D01*
X326559Y724150D01*
X326476Y724483D01*
X326267Y724733D01*
X325892Y724983D01*
G01X316234Y714217D02*
X313734D01*
Y715258D01*
X313859Y715592D01*
X314026Y715800D01*
X314359Y715883D01*
X314692Y715800D01*
X314901Y715550D01*
X315026Y715258D01*
Y714217D01*
G01Y715258D02*
X316234Y715883D01*
G01X315859Y717233D02*
X316067Y717483D01*
X316192Y717775D01*
X316234Y718150D01*
X316151Y718525D01*
X315984Y718817D01*
X315692Y719025D01*
X315359Y719067D01*
X315026Y718983D01*
X314817Y718775D01*
X314651Y718483D01*
X314609Y718192D01*
X314651Y717900D01*
X314817Y717525D01*
X313734Y717650D01*
Y718775D01*
G01X316234Y721750D02*
X313734D01*
X315526Y720208D01*
Y722292D01*
G01X313734Y724350D02*
X313817Y724017D01*
X314026Y723767D01*
X314276Y723600D01*
X314609Y723475D01*
X314984Y723433D01*
X315359Y723475D01*
X315692Y723600D01*
X315942Y723767D01*
X316151Y724017D01*
X316234Y724350D01*
X316151Y724683D01*
X315942Y724933D01*
X315692Y725100D01*
X315359Y725225D01*
X314984Y725267D01*
X314609Y725225D01*
X314276Y725100D01*
X314026Y724933D01*
X313817Y724683D01*
X313734Y724350D01*
G01X291800Y665900D02*
X287800D01*
Y658500D01*
G01X279634Y671017D02*
X277134D01*
Y672058D01*
X277259Y672392D01*
X277426Y672600D01*
X277759Y672683D01*
X278092Y672600D01*
X278301Y672350D01*
X278426Y672058D01*
Y671017D01*
G01Y672058D02*
X279634Y672683D01*
G01X279134Y674033D02*
X279426Y674283D01*
X279592Y674617D01*
X279634Y674992D01*
X279592Y675325D01*
X279384Y675658D01*
X279134Y675867D01*
X278884Y675908D01*
X278592Y675825D01*
X278384Y675533D01*
X278301Y675242D01*
Y674867D01*
G01Y675242D02*
X278176Y675492D01*
X277967Y675700D01*
X277717Y675783D01*
X277467Y675700D01*
X277259Y675492D01*
X277134Y675117D01*
X277176Y674742D01*
X277342Y674367D01*
G01X279134Y677133D02*
X279426Y677383D01*
X279592Y677717D01*
X279634Y678092D01*
X279592Y678425D01*
X279384Y678758D01*
X279134Y678967D01*
X278884Y679008D01*
X278592Y678925D01*
X278384Y678633D01*
X278301Y678342D01*
Y677967D01*
G01Y678342D02*
X278176Y678592D01*
X277967Y678800D01*
X277717Y678883D01*
X277467Y678800D01*
X277259Y678592D01*
X277134Y678217D01*
X277176Y677842D01*
X277342Y677467D01*
G01X277551Y680358D02*
X277301Y680608D01*
X277176Y680900D01*
X277134Y681233D01*
X277217Y681650D01*
X277426Y681942D01*
X277676Y682025D01*
X277926Y681983D01*
X278134Y681817D01*
X278551Y680983D01*
X278842Y680608D01*
X279259Y680358D01*
X279634Y680275D01*
Y682025D01*
G01X330000Y675300D02*
X326000D01*
Y667900D01*
G01X334500Y668100D02*
X338500D01*
Y675500D01*
G01X278800Y696300D02*
Y682900D01*
G01X337936Y667230D02*
X324936D01*
G01X317542Y715967D02*
X317417Y715717D01*
X317334Y715425D01*
Y715092D01*
X317459Y714717D01*
X317667Y714425D01*
X317917Y714217D01*
X318334Y714050D01*
X318709Y714008D01*
X319084Y714092D01*
X319334Y714217D01*
X319584Y714467D01*
X319751Y714758D01*
X319834Y715050D01*
Y715342D01*
X319751Y715633D01*
X319626Y715883D01*
X319459Y716092D01*
G01X317751Y717358D02*
X317501Y717608D01*
X317376Y717900D01*
X317334Y718233D01*
X317417Y718650D01*
X317626Y718942D01*
X317876Y719025D01*
X318126Y718983D01*
X318334Y718817D01*
X318751Y717983D01*
X319042Y717608D01*
X319459Y717358D01*
X319834Y717275D01*
Y719025D01*
G01Y721750D02*
X317334D01*
X319126Y720208D01*
Y722292D01*
G01X319834Y724350D02*
X317334D01*
X317834Y723850D01*
G01X319834D02*
Y724850D01*
G01X321442Y715667D02*
X321317Y715417D01*
X321234Y715125D01*
Y714792D01*
X321359Y714417D01*
X321567Y714125D01*
X321817Y713917D01*
X322234Y713750D01*
X322609Y713708D01*
X322984Y713792D01*
X323234Y713917D01*
X323484Y714167D01*
X323651Y714458D01*
X323734Y714750D01*
Y715042D01*
X323651Y715333D01*
X323526Y715583D01*
X323359Y715792D01*
G01Y716933D02*
X323567Y717183D01*
X323692Y717475D01*
X323734Y717850D01*
X323651Y718225D01*
X323484Y718517D01*
X323192Y718725D01*
X322859Y718767D01*
X322526Y718683D01*
X322317Y718475D01*
X322151Y718183D01*
X322109Y717892D01*
X322151Y717600D01*
X322317Y717225D01*
X321234Y717350D01*
Y718475D01*
G01X321651Y720158D02*
X321401Y720408D01*
X321276Y720700D01*
X321234Y721033D01*
X321317Y721450D01*
X321526Y721742D01*
X321776Y721825D01*
X322026Y721783D01*
X322234Y721617D01*
X322651Y720783D01*
X322942Y720408D01*
X323359Y720158D01*
X323734Y720075D01*
Y721825D01*
G01Y724550D02*
X321234D01*
X323026Y723008D01*
Y725092D01*
G01X300500Y682517D02*
X298000D01*
Y683558D01*
X298125Y683892D01*
X298292Y684100D01*
X298625Y684183D01*
X298958Y684100D01*
X299167Y683850D01*
X299292Y683558D01*
Y682517D01*
G01Y683558D02*
X300500Y684183D01*
G01X300125Y685533D02*
X300333Y685783D01*
X300458Y686075D01*
X300500Y686450D01*
X300417Y686825D01*
X300250Y687117D01*
X299958Y687325D01*
X299625Y687367D01*
X299292Y687283D01*
X299083Y687075D01*
X298917Y686783D01*
X298875Y686492D01*
X298917Y686200D01*
X299083Y685825D01*
X298000Y685950D01*
Y687075D01*
G01Y689550D02*
X298083Y689217D01*
X298292Y688967D01*
X298542Y688800D01*
X298875Y688675D01*
X299250Y688633D01*
X299625Y688675D01*
X299958Y688800D01*
X300208Y688967D01*
X300417Y689217D01*
X300500Y689550D01*
X300417Y689883D01*
X300208Y690133D01*
X299958Y690300D01*
X299625Y690425D01*
X299250Y690467D01*
X298875Y690425D01*
X298542Y690300D01*
X298292Y690133D01*
X298083Y689883D01*
X298000Y689550D01*
G01X300500Y693150D02*
X298000D01*
X299792Y691608D01*
Y693692D01*
G01X305800Y672600D02*
Y677800D01*
G01X312800Y672600D02*
Y680400D01*
G01X305800Y672600D02*
X312800D01*
G01X305800Y686000D02*
Y677300D01*
G01X312800Y686000D02*
X305800D01*
G01X312800Y679600D02*
Y686000D01*
G01X281784Y701220D02*
Y696220D01*
X286784D01*
G01Y723920D02*
X281784D01*
Y718920D01*
G01X309484D02*
Y723920D01*
X304484D01*
G01X300752Y697627D02*
Y694627D01*
G01X290516Y722513D02*
Y725513D01*
G01X283191Y704952D02*
X281191D01*
G01X308077Y715188D02*
X310077D01*
G01X336733Y689867D02*
Y688075D01*
X336900Y687700D01*
X337233Y687450D01*
X337650Y687367D01*
X338067Y687450D01*
X338400Y687700D01*
X338567Y688075D01*
Y689867D01*
G01X340750Y687367D02*
Y689867D01*
X340250Y689367D01*
G01Y687367D02*
X341250D01*
G01X343850Y689867D02*
X343517Y689784D01*
X343267Y689575D01*
X343100Y689325D01*
X342975Y688992D01*
X342933Y688617D01*
X342975Y688242D01*
X343100Y687909D01*
X343267Y687659D01*
X343517Y687450D01*
X343850Y687367D01*
X344183Y687450D01*
X344433Y687659D01*
X344600Y687909D01*
X344725Y688242D01*
X344767Y688617D01*
X344725Y688992D01*
X344600Y689325D01*
X344433Y689575D01*
X344183Y689784D01*
X343850Y689867D01*
G01X346867Y687367D02*
X346950Y687909D01*
X347075Y688367D01*
X347242Y688784D01*
X347450Y689242D01*
X347783Y689867D01*
X346117D01*
G01X288183Y667767D02*
Y670267D01*
X289017D01*
X289350Y670142D01*
X289600Y669975D01*
X289808Y669725D01*
X289975Y669434D01*
X290017Y669017D01*
X289975Y668600D01*
X289808Y668309D01*
X289600Y668059D01*
X289350Y667892D01*
X289017Y667767D01*
X288183D01*
G01X292200D02*
Y670267D01*
X291700Y669767D01*
G01Y667767D02*
X292700D01*
G01X295300D02*
Y670267D01*
X294800Y669767D01*
G01Y667767D02*
X295800D01*
G01X286300Y667100D02*
Y660100D01*
G01X312267Y750158D02*
X312017Y750283D01*
X311725Y750366D01*
X311392D01*
X311017Y750241D01*
X310725Y750033D01*
X310517Y749783D01*
X310350Y749366D01*
X310308Y748991D01*
X310392Y748616D01*
X310517Y748366D01*
X310767Y748116D01*
X311058Y747949D01*
X311350Y747866D01*
X311642D01*
X311933Y747949D01*
X312183Y748074D01*
X312392Y748241D01*
G01X314450Y747866D02*
Y750366D01*
X313950Y749866D01*
G01Y747866D02*
X314950D01*
G01X316842Y748158D02*
X317133Y747949D01*
X317467Y747866D01*
X317800Y747949D01*
X318092Y748199D01*
X318300Y748574D01*
X318383Y748949D01*
Y749408D01*
X318300Y749783D01*
X318092Y750116D01*
X317842Y750283D01*
X317550Y750366D01*
X317217Y750283D01*
X316967Y750116D01*
X316800Y749866D01*
X316717Y749533D01*
X316800Y749241D01*
X317008Y748949D01*
X317258Y748783D01*
X317550Y748741D01*
X317883Y748824D01*
X318133Y749033D01*
X318383Y749408D01*
G01X320650Y747866D02*
X320942Y747908D01*
X321275Y748033D01*
X321483Y748241D01*
X321567Y748533D01*
X321483Y748824D01*
X321233Y749074D01*
X320858Y749199D01*
X320442D01*
X320192Y749283D01*
X319983Y749491D01*
X319900Y749783D01*
X320025Y750074D01*
X320317Y750283D01*
X320650Y750366D01*
X320983Y750283D01*
X321275Y750074D01*
X321400Y749783D01*
X321317Y749491D01*
X321108Y749283D01*
X320858Y749199D01*
X320442D01*
X320067Y749074D01*
X319817Y748824D01*
X319733Y748533D01*
X319817Y748241D01*
X320025Y748033D01*
X320358Y747908D01*
X320650Y747866D01*
G01X315667Y733059D02*
X315417Y733184D01*
X315125Y733267D01*
X314792D01*
X314417Y733142D01*
X314125Y732934D01*
X313917Y732684D01*
X313750Y732267D01*
X313708Y731892D01*
X313792Y731517D01*
X313917Y731267D01*
X314167Y731017D01*
X314458Y730850D01*
X314750Y730767D01*
X315042D01*
X315333Y730850D01*
X315583Y730975D01*
X315792Y731142D01*
G01X317850Y730767D02*
Y733267D01*
X317350Y732767D01*
G01Y730767D02*
X318350D01*
G01X320242Y731059D02*
X320533Y730850D01*
X320867Y730767D01*
X321200Y730850D01*
X321492Y731100D01*
X321700Y731475D01*
X321783Y731850D01*
Y732309D01*
X321700Y732684D01*
X321492Y733017D01*
X321242Y733184D01*
X320950Y733267D01*
X320617Y733184D01*
X320367Y733017D01*
X320200Y732767D01*
X320117Y732434D01*
X320200Y732142D01*
X320408Y731850D01*
X320658Y731684D01*
X320950Y731642D01*
X321283Y731725D01*
X321533Y731934D01*
X321783Y732309D01*
G01X324050Y730767D02*
Y733267D01*
X323550Y732767D01*
G01Y730767D02*
X324550D01*
G01X314842Y737067D02*
X314717Y736817D01*
X314634Y736525D01*
Y736192D01*
X314759Y735817D01*
X314967Y735525D01*
X315217Y735317D01*
X315634Y735150D01*
X316009Y735108D01*
X316384Y735192D01*
X316634Y735317D01*
X316884Y735567D01*
X317051Y735858D01*
X317134Y736150D01*
Y736442D01*
X317051Y736733D01*
X316926Y736983D01*
X316759Y737192D01*
G01X317134Y739250D02*
X314634D01*
X315134Y738750D01*
G01X317134D02*
Y739750D01*
G01X316842Y741642D02*
X317051Y741933D01*
X317134Y742267D01*
X317051Y742600D01*
X316801Y742892D01*
X316426Y743100D01*
X316051Y743183D01*
X315592D01*
X315217Y743100D01*
X314884Y742892D01*
X314717Y742642D01*
X314634Y742350D01*
X314717Y742017D01*
X314884Y741767D01*
X315134Y741600D01*
X315467Y741517D01*
X315759Y741600D01*
X316051Y741808D01*
X316217Y742058D01*
X316259Y742350D01*
X316176Y742683D01*
X315967Y742933D01*
X315592Y743183D01*
G01X315051Y744658D02*
X314801Y744908D01*
X314676Y745200D01*
X314634Y745533D01*
X314717Y745950D01*
X314926Y746242D01*
X315176Y746325D01*
X315426Y746283D01*
X315634Y746117D01*
X316051Y745283D01*
X316342Y744908D01*
X316759Y744658D01*
X317134Y744575D01*
Y746325D01*
G01X310642Y737067D02*
X310517Y736817D01*
X310434Y736525D01*
Y736192D01*
X310559Y735817D01*
X310767Y735525D01*
X311017Y735317D01*
X311434Y735150D01*
X311809Y735108D01*
X312184Y735192D01*
X312434Y735317D01*
X312684Y735567D01*
X312851Y735858D01*
X312934Y736150D01*
Y736442D01*
X312851Y736733D01*
X312726Y736983D01*
X312559Y737192D01*
G01X312934Y739250D02*
X310434D01*
X310934Y738750D01*
G01X312934D02*
Y739750D01*
G01X312642Y741642D02*
X312851Y741933D01*
X312934Y742267D01*
X312851Y742600D01*
X312601Y742892D01*
X312226Y743100D01*
X311851Y743183D01*
X311392D01*
X311017Y743100D01*
X310684Y742892D01*
X310517Y742642D01*
X310434Y742350D01*
X310517Y742017D01*
X310684Y741767D01*
X310934Y741600D01*
X311267Y741517D01*
X311559Y741600D01*
X311851Y741808D01*
X312017Y742058D01*
X312059Y742350D01*
X311976Y742683D01*
X311767Y742933D01*
X311392Y743183D01*
G01X312434Y744533D02*
X312726Y744783D01*
X312892Y745117D01*
X312934Y745492D01*
X312892Y745825D01*
X312684Y746158D01*
X312434Y746367D01*
X312184Y746408D01*
X311892Y746325D01*
X311684Y746033D01*
X311601Y745742D01*
Y745367D01*
G01Y745742D02*
X311476Y745992D01*
X311267Y746200D01*
X311017Y746283D01*
X310767Y746200D01*
X310559Y745992D01*
X310434Y745617D01*
X310476Y745242D01*
X310642Y744867D01*
G01X315467Y728559D02*
X315217Y728684D01*
X314925Y728767D01*
X314592D01*
X314217Y728642D01*
X313925Y728434D01*
X313717Y728184D01*
X313550Y727767D01*
X313508Y727392D01*
X313592Y727017D01*
X313717Y726767D01*
X313967Y726517D01*
X314258Y726350D01*
X314550Y726267D01*
X314842D01*
X315133Y726350D01*
X315383Y726475D01*
X315592Y726642D01*
G01X317650Y726267D02*
Y728767D01*
X317150Y728267D01*
G01Y726267D02*
X318150D01*
G01X320042Y726559D02*
X320333Y726350D01*
X320667Y726267D01*
X321000Y726350D01*
X321292Y726600D01*
X321500Y726975D01*
X321583Y727350D01*
Y727809D01*
X321500Y728184D01*
X321292Y728517D01*
X321042Y728684D01*
X320750Y728767D01*
X320417Y728684D01*
X320167Y728517D01*
X320000Y728267D01*
X319917Y727934D01*
X320000Y727642D01*
X320208Y727350D01*
X320458Y727184D01*
X320750Y727142D01*
X321083Y727225D01*
X321333Y727434D01*
X321583Y727809D01*
G01X324350Y726267D02*
Y728767D01*
X322808Y726975D01*
X324892D01*
G01X290342Y740267D02*
X290217Y740017D01*
X290134Y739725D01*
Y739392D01*
X290259Y739017D01*
X290467Y738725D01*
X290717Y738517D01*
X291134Y738350D01*
X291509Y738308D01*
X291884Y738392D01*
X292134Y738517D01*
X292384Y738767D01*
X292551Y739058D01*
X292634Y739350D01*
Y739642D01*
X292551Y739933D01*
X292426Y740183D01*
X292259Y740392D01*
G01X292634Y742450D02*
X290134D01*
X290634Y741950D01*
G01X292634D02*
Y742950D01*
G01X292342Y744842D02*
X292551Y745133D01*
X292634Y745467D01*
X292551Y745800D01*
X292301Y746092D01*
X291926Y746300D01*
X291551Y746383D01*
X291092D01*
X290717Y746300D01*
X290384Y746092D01*
X290217Y745842D01*
X290134Y745550D01*
X290217Y745217D01*
X290384Y744967D01*
X290634Y744800D01*
X290967Y744717D01*
X291259Y744800D01*
X291551Y745008D01*
X291717Y745258D01*
X291759Y745550D01*
X291676Y745883D01*
X291467Y746133D01*
X291092Y746383D01*
G01X292342Y747942D02*
X292551Y748233D01*
X292634Y748567D01*
X292551Y748900D01*
X292301Y749192D01*
X291926Y749400D01*
X291551Y749483D01*
X291092D01*
X290717Y749400D01*
X290384Y749192D01*
X290217Y748942D01*
X290134Y748650D01*
X290217Y748317D01*
X290384Y748067D01*
X290634Y747900D01*
X290967Y747817D01*
X291259Y747900D01*
X291551Y748108D01*
X291717Y748358D01*
X291759Y748650D01*
X291676Y748983D01*
X291467Y749233D01*
X291092Y749483D01*
G01X294642Y744367D02*
X294517Y744117D01*
X294434Y743825D01*
Y743492D01*
X294559Y743117D01*
X294767Y742825D01*
X295017Y742617D01*
X295434Y742450D01*
X295809Y742408D01*
X296184Y742492D01*
X296434Y742617D01*
X296684Y742867D01*
X296851Y743158D01*
X296934Y743450D01*
Y743742D01*
X296851Y744033D01*
X296726Y744283D01*
X296559Y744492D01*
G01X294851Y745758D02*
X294601Y746008D01*
X294476Y746300D01*
X294434Y746633D01*
X294517Y747050D01*
X294726Y747342D01*
X294976Y747425D01*
X295226Y747383D01*
X295434Y747217D01*
X295851Y746383D01*
X296142Y746008D01*
X296559Y745758D01*
X296934Y745675D01*
Y747425D01*
G01X294434Y749650D02*
X294517Y749317D01*
X294726Y749067D01*
X294976Y748900D01*
X295309Y748775D01*
X295684Y748733D01*
X296059Y748775D01*
X296392Y748900D01*
X296642Y749067D01*
X296851Y749317D01*
X296934Y749650D01*
X296851Y749983D01*
X296642Y750233D01*
X296392Y750400D01*
X296059Y750525D01*
X295684Y750567D01*
X295309Y750525D01*
X294976Y750400D01*
X294726Y750233D01*
X294517Y749983D01*
X294434Y749650D01*
G01Y752750D02*
X294517Y752417D01*
X294726Y752167D01*
X294976Y752000D01*
X295309Y751875D01*
X295684Y751833D01*
X296059Y751875D01*
X296392Y752000D01*
X296642Y752167D01*
X296851Y752417D01*
X296934Y752750D01*
X296851Y753083D01*
X296642Y753333D01*
X296392Y753500D01*
X296059Y753625D01*
X295684Y753667D01*
X295309Y753625D01*
X294976Y753500D01*
X294726Y753333D01*
X294517Y753083D01*
X294434Y752750D01*
G01X288734Y738617D02*
X286234D01*
Y739658D01*
X286359Y739992D01*
X286526Y740200D01*
X286859Y740283D01*
X287192Y740200D01*
X287401Y739950D01*
X287526Y739658D01*
Y738617D01*
G01Y739658D02*
X288734Y740283D01*
G01X288359Y741633D02*
X288567Y741883D01*
X288692Y742175D01*
X288734Y742550D01*
X288651Y742925D01*
X288484Y743217D01*
X288192Y743425D01*
X287859Y743467D01*
X287526Y743383D01*
X287317Y743175D01*
X287151Y742883D01*
X287109Y742592D01*
X287151Y742300D01*
X287317Y741925D01*
X286234Y742050D01*
Y743175D01*
G01Y745650D02*
X286317Y745317D01*
X286526Y745067D01*
X286776Y744900D01*
X287109Y744775D01*
X287484Y744733D01*
X287859Y744775D01*
X288192Y744900D01*
X288442Y745067D01*
X288651Y745317D01*
X288734Y745650D01*
X288651Y745983D01*
X288442Y746233D01*
X288192Y746400D01*
X287859Y746525D01*
X287484Y746567D01*
X287109Y746525D01*
X286776Y746400D01*
X286526Y746233D01*
X286317Y745983D01*
X286234Y745650D01*
G01X288734Y748667D02*
X288192Y748750D01*
X287734Y748875D01*
X287317Y749042D01*
X286859Y749250D01*
X286234Y749583D01*
Y747917D01*
G01X293700Y735600D02*
X289700D01*
Y728200D01*
G01X284734Y738617D02*
X282234D01*
Y739658D01*
X282359Y739992D01*
X282526Y740200D01*
X282859Y740283D01*
X283192Y740200D01*
X283401Y739950D01*
X283526Y739658D01*
Y738617D01*
G01Y739658D02*
X284734Y740283D01*
G01X284359Y741633D02*
X284567Y741883D01*
X284692Y742175D01*
X284734Y742550D01*
X284651Y742925D01*
X284484Y743217D01*
X284192Y743425D01*
X283859Y743467D01*
X283526Y743383D01*
X283317Y743175D01*
X283151Y742883D01*
X283109Y742592D01*
X283151Y742300D01*
X283317Y741925D01*
X282234Y742050D01*
Y743175D01*
G01Y745650D02*
X282317Y745317D01*
X282526Y745067D01*
X282776Y744900D01*
X283109Y744775D01*
X283484Y744733D01*
X283859Y744775D01*
X284192Y744900D01*
X284442Y745067D01*
X284651Y745317D01*
X284734Y745650D01*
X284651Y745983D01*
X284442Y746233D01*
X284192Y746400D01*
X283859Y746525D01*
X283484Y746567D01*
X283109Y746525D01*
X282776Y746400D01*
X282526Y746233D01*
X282317Y745983D01*
X282234Y745650D01*
G01X284734Y748750D02*
X284692Y749042D01*
X284567Y749375D01*
X284359Y749583D01*
X284067Y749667D01*
X283776Y749583D01*
X283526Y749333D01*
X283401Y748958D01*
Y748542D01*
X283317Y748292D01*
X283109Y748083D01*
X282817Y748000D01*
X282526Y748125D01*
X282317Y748417D01*
X282234Y748750D01*
X282317Y749083D01*
X282526Y749375D01*
X282817Y749500D01*
X283109Y749417D01*
X283317Y749208D01*
X283401Y748958D01*
Y748542D01*
X283526Y748167D01*
X283776Y747917D01*
X284067Y747833D01*
X284359Y747917D01*
X284567Y748125D01*
X284692Y748458D01*
X284734Y748750D01*
G01X289620Y735620D02*
X285620D01*
Y728220D01*
G01X293567Y724667D02*
Y727167D01*
X294567D01*
X294900Y727042D01*
X295150Y726750D01*
X295233Y726417D01*
X295150Y726084D01*
X294942Y725834D01*
X294567Y725709D01*
X293567D01*
G01X296583Y727167D02*
Y725375D01*
X296750Y725000D01*
X297083Y724750D01*
X297500Y724667D01*
X297917Y724750D01*
X298250Y725000D01*
X298417Y725375D01*
Y727167D01*
G01X299892Y724959D02*
X300183Y724750D01*
X300517Y724667D01*
X300850Y724750D01*
X301142Y725000D01*
X301350Y725375D01*
X301433Y725750D01*
Y726209D01*
X301350Y726584D01*
X301142Y726917D01*
X300892Y727084D01*
X300600Y727167D01*
X300267Y727084D01*
X300017Y726917D01*
X299850Y726667D01*
X299767Y726334D01*
X299850Y726042D01*
X300058Y725750D01*
X300308Y725584D01*
X300600Y725542D01*
X300933Y725625D01*
X301183Y725834D01*
X301433Y726209D01*
G01X403434Y67267D02*
X400934D01*
Y68308D01*
X401059Y68642D01*
X401226Y68850D01*
X401559Y68933D01*
X401892Y68850D01*
X402101Y68600D01*
X402226Y68308D01*
Y67267D01*
G01Y68308D02*
X403434Y68933D01*
G01X402934Y70283D02*
X403226Y70533D01*
X403392Y70867D01*
X403434Y71242D01*
X403392Y71575D01*
X403184Y71908D01*
X402934Y72117D01*
X402684Y72158D01*
X402392Y72075D01*
X402184Y71783D01*
X402101Y71492D01*
Y71117D01*
G01Y71492D02*
X401976Y71742D01*
X401767Y71950D01*
X401517Y72033D01*
X401267Y71950D01*
X401059Y71742D01*
X400934Y71367D01*
X400976Y70992D01*
X401142Y70617D01*
G01X403434Y74300D02*
X403392Y74592D01*
X403267Y74925D01*
X403059Y75133D01*
X402767Y75217D01*
X402476Y75133D01*
X402226Y74883D01*
X402101Y74508D01*
Y74092D01*
X402017Y73842D01*
X401809Y73633D01*
X401517Y73550D01*
X401226Y73675D01*
X401017Y73967D01*
X400934Y74300D01*
X401017Y74633D01*
X401226Y74925D01*
X401517Y75050D01*
X401809Y74967D01*
X402017Y74758D01*
X402101Y74508D01*
Y74092D01*
X402226Y73717D01*
X402476Y73467D01*
X402767Y73383D01*
X403059Y73467D01*
X403267Y73675D01*
X403392Y74008D01*
X403434Y74300D01*
G01X389262Y66871D02*
X393262D01*
Y74271D01*
G01X399234Y67367D02*
X396734D01*
Y68408D01*
X396859Y68742D01*
X397026Y68950D01*
X397359Y69033D01*
X397692Y68950D01*
X397901Y68700D01*
X398026Y68408D01*
Y67367D01*
G01Y68408D02*
X399234Y69033D01*
G01Y71800D02*
X396734D01*
X398526Y70258D01*
Y72342D01*
G01X398192Y73608D02*
X397901Y73900D01*
X397734Y74150D01*
X397651Y74483D01*
X397734Y74775D01*
X397901Y74983D01*
X398151Y75150D01*
X398442Y75192D01*
X398692Y75150D01*
X398942Y74983D01*
X399151Y74733D01*
X399234Y74442D01*
X399151Y74108D01*
X398901Y73817D01*
X398526Y73650D01*
X398109Y73608D01*
X397567Y73692D01*
X397276Y73817D01*
X396984Y74025D01*
X396776Y74317D01*
X396734Y74608D01*
X396817Y74900D01*
X397026Y75108D01*
G01X384027Y66840D02*
X388027D01*
Y74240D01*
G01X392827Y64390D02*
X384427D01*
Y76590D01*
X392827D01*
Y64390D01*
G01X369056Y40682D02*
Y43182D01*
X369890D01*
X370223Y43057D01*
X370473Y42890D01*
X370681Y42640D01*
X370848Y42349D01*
X370890Y41932D01*
X370848Y41515D01*
X370681Y41224D01*
X370473Y40974D01*
X370223Y40807D01*
X369890Y40682D01*
X369056D01*
G01X373073D02*
Y43182D01*
X372573Y42682D01*
G01Y40682D02*
X373573D01*
G01X375256Y41057D02*
X375506Y40849D01*
X375798Y40724D01*
X376173Y40682D01*
X376548Y40765D01*
X376840Y40932D01*
X377048Y41224D01*
X377090Y41557D01*
X377006Y41890D01*
X376798Y42099D01*
X376506Y42265D01*
X376215Y42307D01*
X375923Y42265D01*
X375548Y42099D01*
X375673Y43182D01*
X376798D01*
G01X368556Y36282D02*
Y38782D01*
X369390D01*
X369723Y38657D01*
X369973Y38490D01*
X370181Y38240D01*
X370348Y37949D01*
X370390Y37532D01*
X370348Y37115D01*
X370181Y36824D01*
X369973Y36574D01*
X369723Y36407D01*
X369390Y36282D01*
X368556D01*
G01X372573D02*
Y38782D01*
X372073Y38282D01*
G01Y36282D02*
X373073D01*
G01X376173D02*
Y38782D01*
X374631Y36990D01*
X376715D01*
G01X378500Y56683D02*
X376000D01*
Y57517D01*
X376125Y57850D01*
X376292Y58100D01*
X376542Y58308D01*
X376833Y58475D01*
X377250Y58517D01*
X377667Y58475D01*
X377958Y58308D01*
X378208Y58100D01*
X378375Y57850D01*
X378500Y57517D01*
Y56683D01*
G01Y60700D02*
X376000D01*
X376500Y60200D01*
G01X378500D02*
Y61200D01*
G01Y63800D02*
X378458Y64092D01*
X378333Y64425D01*
X378125Y64633D01*
X377833Y64717D01*
X377542Y64633D01*
X377292Y64383D01*
X377167Y64008D01*
Y63592D01*
X377083Y63342D01*
X376875Y63133D01*
X376583Y63050D01*
X376292Y63175D01*
X376083Y63467D01*
X376000Y63800D01*
X376083Y64133D01*
X376292Y64425D01*
X376583Y64550D01*
X376875Y64467D01*
X377083Y64258D01*
X377167Y64008D01*
Y63592D01*
X377292Y63217D01*
X377542Y62967D01*
X377833Y62883D01*
X378125Y62967D01*
X378333Y63175D01*
X378458Y63508D01*
X378500Y63800D01*
G01X380817Y113092D02*
X380567Y113217D01*
X380275Y113300D01*
X379942D01*
X379567Y113175D01*
X379275Y112967D01*
X379067Y112717D01*
X378900Y112300D01*
X378858Y111925D01*
X378942Y111550D01*
X379067Y111300D01*
X379317Y111050D01*
X379608Y110883D01*
X379900Y110800D01*
X380192D01*
X380483Y110883D01*
X380733Y111008D01*
X380942Y111175D01*
G01X382208Y112883D02*
X382458Y113133D01*
X382750Y113258D01*
X383083Y113300D01*
X383500Y113217D01*
X383792Y113008D01*
X383875Y112758D01*
X383833Y112508D01*
X383667Y112300D01*
X382833Y111883D01*
X382458Y111592D01*
X382208Y111175D01*
X382125Y110800D01*
X383875D01*
G01X380817Y116792D02*
X380567Y116917D01*
X380275Y117000D01*
X379942D01*
X379567Y116875D01*
X379275Y116667D01*
X379067Y116417D01*
X378900Y116000D01*
X378858Y115625D01*
X378942Y115250D01*
X379067Y115000D01*
X379317Y114750D01*
X379608Y114583D01*
X379900Y114500D01*
X380192D01*
X380483Y114583D01*
X380733Y114708D01*
X380942Y114875D01*
G01X382208Y116583D02*
X382458Y116833D01*
X382750Y116958D01*
X383083Y117000D01*
X383500Y116917D01*
X383792Y116708D01*
X383875Y116458D01*
X383833Y116208D01*
X383667Y116000D01*
X382833Y115583D01*
X382458Y115292D01*
X382208Y114875D01*
X382125Y114500D01*
X383875D01*
G01X386100D02*
Y117000D01*
X385600Y116500D01*
G01Y114500D02*
X386600D01*
G01X380817Y120492D02*
X380567Y120617D01*
X380275Y120700D01*
X379942D01*
X379567Y120575D01*
X379275Y120367D01*
X379067Y120117D01*
X378900Y119700D01*
X378858Y119325D01*
X378942Y118950D01*
X379067Y118700D01*
X379317Y118450D01*
X379608Y118283D01*
X379900Y118200D01*
X380192D01*
X380483Y118283D01*
X380733Y118408D01*
X380942Y118575D01*
G01X382208Y120283D02*
X382458Y120533D01*
X382750Y120658D01*
X383083Y120700D01*
X383500Y120617D01*
X383792Y120408D01*
X383875Y120158D01*
X383833Y119908D01*
X383667Y119700D01*
X382833Y119283D01*
X382458Y118992D01*
X382208Y118575D01*
X382125Y118200D01*
X383875D01*
G01X385308Y120283D02*
X385558Y120533D01*
X385850Y120658D01*
X386183Y120700D01*
X386600Y120617D01*
X386892Y120408D01*
X386975Y120158D01*
X386933Y119908D01*
X386767Y119700D01*
X385933Y119283D01*
X385558Y118992D01*
X385308Y118575D01*
X385225Y118200D01*
X386975D01*
G01X362700Y109300D02*
X349300D01*
G01X362700Y102100D02*
Y109300D01*
G01X349300Y102100D02*
X362700D01*
G01X349300Y109300D02*
Y102100D01*
G01X395247Y80323D02*
Y77823D01*
X396913D01*
G01X399180D02*
Y80323D01*
X398680Y79823D01*
G01Y77823D02*
X399680D01*
G01X365000Y115700D02*
Y123700D01*
G01Y109700D02*
Y115700D01*
G01Y109700D02*
Y123700D01*
G01X347000Y109700D02*
X365000D01*
G01X347000Y123700D02*
Y109700D01*
G01X365000Y123700D02*
X347000D01*
G01X376762Y124201D02*
Y135401D01*
G01X358762Y124201D02*
X376762D01*
G01X358762Y135401D02*
Y124201D01*
G01X368728Y96656D02*
Y99156D01*
X369562D01*
X369895Y99031D01*
X370145Y98864D01*
X370353Y98614D01*
X370520Y98323D01*
X370562Y97906D01*
X370520Y97489D01*
X370353Y97198D01*
X370145Y96948D01*
X369895Y96781D01*
X369562Y96656D01*
X368728D01*
G01X372745D02*
Y99156D01*
X372245Y98656D01*
G01Y96656D02*
X373245D01*
G01X375762D02*
X375845Y97198D01*
X375970Y97656D01*
X376137Y98073D01*
X376345Y98531D01*
X376678Y99156D01*
X375012D01*
G01X368628Y91456D02*
Y93956D01*
X369462D01*
X369795Y93831D01*
X370045Y93664D01*
X370253Y93414D01*
X370420Y93123D01*
X370462Y92706D01*
X370420Y92289D01*
X370253Y91998D01*
X370045Y91748D01*
X369795Y91581D01*
X369462Y91456D01*
X368628D01*
G01X372645D02*
Y93956D01*
X372145Y93456D01*
G01Y91456D02*
X373145D01*
G01X374953Y92498D02*
X375245Y92789D01*
X375495Y92956D01*
X375828Y93039D01*
X376120Y92956D01*
X376328Y92789D01*
X376495Y92539D01*
X376537Y92248D01*
X376495Y91998D01*
X376328Y91748D01*
X376078Y91539D01*
X375787Y91456D01*
X375453Y91539D01*
X375162Y91789D01*
X374995Y92164D01*
X374953Y92581D01*
X375037Y93123D01*
X375162Y93414D01*
X375370Y93706D01*
X375662Y93914D01*
X375953Y93956D01*
X376245Y93873D01*
X376453Y93664D01*
G01X378400Y69683D02*
X375900D01*
Y70517D01*
X376025Y70850D01*
X376192Y71100D01*
X376442Y71308D01*
X376733Y71475D01*
X377150Y71517D01*
X377567Y71475D01*
X377858Y71308D01*
X378108Y71100D01*
X378275Y70850D01*
X378400Y70517D01*
Y69683D01*
G01Y73700D02*
X375900D01*
X376400Y73200D01*
G01X378400D02*
Y74200D01*
G01X378108Y76092D02*
X378317Y76383D01*
X378400Y76717D01*
X378317Y77050D01*
X378067Y77342D01*
X377692Y77550D01*
X377317Y77633D01*
X376858D01*
X376483Y77550D01*
X376150Y77342D01*
X375983Y77092D01*
X375900Y76800D01*
X375983Y76467D01*
X376150Y76217D01*
X376400Y76050D01*
X376733Y75967D01*
X377025Y76050D01*
X377317Y76258D01*
X377483Y76508D01*
X377525Y76800D01*
X377442Y77133D01*
X377233Y77383D01*
X376858Y77633D01*
G01X382340Y193871D02*
X382215Y193621D01*
X382132Y193329D01*
Y192996D01*
X382257Y192621D01*
X382465Y192329D01*
X382715Y192121D01*
X383132Y191954D01*
X383507Y191912D01*
X383882Y191996D01*
X384132Y192121D01*
X384382Y192371D01*
X384549Y192662D01*
X384632Y192954D01*
Y193246D01*
X384549Y193537D01*
X384424Y193787D01*
X384257Y193996D01*
G01Y195137D02*
X384465Y195387D01*
X384590Y195679D01*
X384632Y196054D01*
X384549Y196429D01*
X384382Y196721D01*
X384090Y196929D01*
X383757Y196971D01*
X383424Y196887D01*
X383215Y196679D01*
X383049Y196387D01*
X383007Y196096D01*
X383049Y195804D01*
X383215Y195429D01*
X382132Y195554D01*
Y196679D01*
G01Y199154D02*
X382215Y198821D01*
X382424Y198571D01*
X382674Y198404D01*
X383007Y198279D01*
X383382Y198237D01*
X383757Y198279D01*
X384090Y198404D01*
X384340Y198571D01*
X384549Y198821D01*
X384632Y199154D01*
X384549Y199487D01*
X384340Y199737D01*
X384090Y199904D01*
X383757Y200029D01*
X383382Y200071D01*
X383007Y200029D01*
X382674Y199904D01*
X382424Y199737D01*
X382215Y199487D01*
X382132Y199154D01*
G01X384632Y202171D02*
X384090Y202254D01*
X383632Y202379D01*
X383215Y202546D01*
X382757Y202754D01*
X382132Y203087D01*
Y201421D01*
G01X388682Y192091D02*
X386182D01*
Y193132D01*
X386307Y193466D01*
X386474Y193674D01*
X386807Y193757D01*
X387140Y193674D01*
X387349Y193424D01*
X387474Y193132D01*
Y192091D01*
G01Y193132D02*
X388682Y193757D01*
G01X388307Y195107D02*
X388515Y195357D01*
X388640Y195649D01*
X388682Y196024D01*
X388599Y196399D01*
X388432Y196691D01*
X388140Y196899D01*
X387807Y196941D01*
X387474Y196857D01*
X387265Y196649D01*
X387099Y196357D01*
X387057Y196066D01*
X387099Y195774D01*
X387265Y195399D01*
X386182Y195524D01*
Y196649D01*
G01Y199124D02*
X386265Y198791D01*
X386474Y198541D01*
X386724Y198374D01*
X387057Y198249D01*
X387432Y198207D01*
X387807Y198249D01*
X388140Y198374D01*
X388390Y198541D01*
X388599Y198791D01*
X388682Y199124D01*
X388599Y199457D01*
X388390Y199707D01*
X388140Y199874D01*
X387807Y199999D01*
X387432Y200041D01*
X387057Y199999D01*
X386724Y199874D01*
X386474Y199707D01*
X386265Y199457D01*
X386182Y199124D01*
G01Y202224D02*
X386265Y201891D01*
X386474Y201641D01*
X386724Y201474D01*
X387057Y201349D01*
X387432Y201307D01*
X387807Y201349D01*
X388140Y201474D01*
X388390Y201641D01*
X388599Y201891D01*
X388682Y202224D01*
X388599Y202557D01*
X388390Y202807D01*
X388140Y202974D01*
X387807Y203099D01*
X387432Y203141D01*
X387057Y203099D01*
X386724Y202974D01*
X386474Y202807D01*
X386265Y202557D01*
X386182Y202224D01*
G01X372682Y198274D02*
X368682D01*
Y190874D01*
G01X380300Y191991D02*
X377800D01*
Y193032D01*
X377925Y193366D01*
X378092Y193574D01*
X378425Y193657D01*
X378758Y193574D01*
X378967Y193324D01*
X379092Y193032D01*
Y191991D01*
G01Y193032D02*
X380300Y193657D01*
G01X379925Y195007D02*
X380133Y195257D01*
X380258Y195549D01*
X380300Y195924D01*
X380217Y196299D01*
X380050Y196591D01*
X379758Y196799D01*
X379425Y196841D01*
X379092Y196757D01*
X378883Y196549D01*
X378717Y196257D01*
X378675Y195966D01*
X378717Y195674D01*
X378883Y195299D01*
X377800Y195424D01*
Y196549D01*
G01Y199024D02*
X377883Y198691D01*
X378092Y198441D01*
X378342Y198274D01*
X378675Y198149D01*
X379050Y198107D01*
X379425Y198149D01*
X379758Y198274D01*
X380008Y198441D01*
X380217Y198691D01*
X380300Y199024D01*
X380217Y199357D01*
X380008Y199607D01*
X379758Y199774D01*
X379425Y199899D01*
X379050Y199941D01*
X378675Y199899D01*
X378342Y199774D01*
X378092Y199607D01*
X377883Y199357D01*
X377800Y199024D01*
G01X378217Y201332D02*
X377967Y201582D01*
X377842Y201874D01*
X377800Y202207D01*
X377883Y202624D01*
X378092Y202916D01*
X378342Y202999D01*
X378592Y202957D01*
X378800Y202791D01*
X379217Y201957D01*
X379508Y201582D01*
X379925Y201332D01*
X380300Y201249D01*
Y202999D01*
G01X360484Y194719D02*
X364484D01*
Y202119D01*
G01X349804Y168097D02*
X347304D01*
Y169138D01*
X347429Y169472D01*
X347596Y169680D01*
X347929Y169763D01*
X348262Y169680D01*
X348471Y169430D01*
X348596Y169138D01*
Y168097D01*
G01Y169138D02*
X349804Y169763D01*
G01Y172030D02*
X347304D01*
X347804Y171530D01*
G01X349804D02*
Y172530D01*
G01X347304Y175130D02*
X347387Y174797D01*
X347596Y174547D01*
X347846Y174380D01*
X348179Y174255D01*
X348554Y174213D01*
X348929Y174255D01*
X349262Y174380D01*
X349512Y174547D01*
X349721Y174797D01*
X349804Y175130D01*
X349721Y175463D01*
X349512Y175713D01*
X349262Y175880D01*
X348929Y176005D01*
X348554Y176047D01*
X348179Y176005D01*
X347846Y175880D01*
X347596Y175713D01*
X347387Y175463D01*
X347304Y175130D01*
G01X347004Y177630D02*
X351004D01*
Y185030D01*
G01X374883Y176804D02*
X372383D01*
Y177804D01*
X372508Y178137D01*
X372800Y178387D01*
X373133Y178470D01*
X373466Y178387D01*
X373716Y178179D01*
X373841Y177804D01*
Y176804D01*
G01X374883Y180737D02*
X374841Y180404D01*
X374675Y180112D01*
X374425Y179862D01*
X374133Y179695D01*
X373800Y179612D01*
X373466D01*
X373133Y179695D01*
X372841Y179862D01*
X372591Y180112D01*
X372425Y180404D01*
X372383Y180737D01*
X372425Y181070D01*
X372591Y181362D01*
X372841Y181612D01*
X373133Y181779D01*
X373466Y181862D01*
X373800D01*
X374133Y181779D01*
X374425Y181612D01*
X374675Y181362D01*
X374841Y181070D01*
X374883Y180737D01*
G01X374216Y181070D02*
X374883Y181570D01*
G01X372800Y183045D02*
X372550Y183295D01*
X372425Y183587D01*
X372383Y183920D01*
X372466Y184337D01*
X372675Y184629D01*
X372925Y184712D01*
X373175Y184670D01*
X373383Y184504D01*
X373800Y183670D01*
X374091Y183295D01*
X374508Y183045D01*
X374883Y182962D01*
Y184712D01*
G01X356726Y177181D02*
X370726D01*
G01X356726Y190181D02*
Y177181D01*
G01X370726Y190181D02*
X356726D01*
G01X370726Y177181D02*
Y190181D01*
G01X352660Y165651D02*
X352535Y165401D01*
X352452Y165109D01*
Y164776D01*
X352577Y164401D01*
X352785Y164109D01*
X353035Y163901D01*
X353452Y163734D01*
X353827Y163692D01*
X354202Y163776D01*
X354452Y163901D01*
X354702Y164151D01*
X354869Y164442D01*
X354952Y164734D01*
Y165026D01*
X354869Y165317D01*
X354744Y165567D01*
X354577Y165776D01*
G01X354952Y167834D02*
X352452D01*
X352952Y167334D01*
G01X354952D02*
Y168334D01*
G01Y170934D02*
X354910Y171226D01*
X354785Y171559D01*
X354577Y171767D01*
X354285Y171851D01*
X353994Y171767D01*
X353744Y171517D01*
X353619Y171142D01*
Y170726D01*
X353535Y170476D01*
X353327Y170267D01*
X353035Y170184D01*
X352744Y170309D01*
X352535Y170601D01*
X352452Y170934D01*
X352535Y171267D01*
X352744Y171559D01*
X353035Y171684D01*
X353327Y171601D01*
X353535Y171392D01*
X353619Y171142D01*
Y170726D01*
X353744Y170351D01*
X353994Y170101D01*
X354285Y170017D01*
X354577Y170101D01*
X354785Y170309D01*
X354910Y170642D01*
X354952Y170934D01*
G01X353910Y173242D02*
X353619Y173534D01*
X353452Y173784D01*
X353369Y174117D01*
X353452Y174409D01*
X353619Y174617D01*
X353869Y174784D01*
X354160Y174826D01*
X354410Y174784D01*
X354660Y174617D01*
X354869Y174367D01*
X354952Y174076D01*
X354869Y173742D01*
X354619Y173451D01*
X354244Y173284D01*
X353827Y173242D01*
X353285Y173326D01*
X352994Y173451D01*
X352702Y173659D01*
X352494Y173951D01*
X352452Y174242D01*
X352535Y174534D01*
X352744Y174742D01*
G01X352708Y139767D02*
X352583Y139517D01*
X352500Y139225D01*
Y138892D01*
X352625Y138517D01*
X352833Y138225D01*
X353083Y138017D01*
X353500Y137850D01*
X353875Y137808D01*
X354250Y137892D01*
X354500Y138017D01*
X354750Y138267D01*
X354917Y138558D01*
X355000Y138850D01*
Y139142D01*
X354917Y139433D01*
X354792Y139683D01*
X354625Y139892D01*
G01X354500Y141033D02*
X354792Y141283D01*
X354958Y141617D01*
X355000Y141992D01*
X354958Y142325D01*
X354750Y142658D01*
X354500Y142867D01*
X354250Y142908D01*
X353958Y142825D01*
X353750Y142533D01*
X353667Y142242D01*
Y141867D01*
G01Y142242D02*
X353542Y142492D01*
X353333Y142700D01*
X353083Y142783D01*
X352833Y142700D01*
X352625Y142492D01*
X352500Y142117D01*
X352542Y141742D01*
X352708Y141367D01*
G01X352917Y144258D02*
X352667Y144508D01*
X352542Y144800D01*
X352500Y145133D01*
X352583Y145550D01*
X352792Y145842D01*
X353042Y145925D01*
X353292Y145883D01*
X353500Y145717D01*
X353917Y144883D01*
X354208Y144508D01*
X354625Y144258D01*
X355000Y144175D01*
Y145925D01*
G01X354625Y147233D02*
X354833Y147483D01*
X354958Y147775D01*
X355000Y148150D01*
X354917Y148525D01*
X354750Y148817D01*
X354458Y149025D01*
X354125Y149067D01*
X353792Y148983D01*
X353583Y148775D01*
X353417Y148483D01*
X353375Y148192D01*
X353417Y147900D01*
X353583Y147525D01*
X352500Y147650D01*
Y148775D01*
G01X376762Y162601D02*
Y151401D01*
G01X358762Y162601D02*
X376762D01*
G01X358762Y151401D02*
Y162601D01*
G01X370900Y252200D02*
Y361900D01*
X403700D01*
Y252200D01*
X370900D01*
G01X378109Y206927D02*
X377859Y207052D01*
X377567Y207135D01*
X377234D01*
X376859Y207010D01*
X376567Y206802D01*
X376359Y206552D01*
X376192Y206135D01*
X376150Y205760D01*
X376234Y205385D01*
X376359Y205135D01*
X376609Y204885D01*
X376900Y204718D01*
X377192Y204635D01*
X377484D01*
X377775Y204718D01*
X378025Y204843D01*
X378234Y205010D01*
G01X380292Y204635D02*
Y207135D01*
X379792Y206635D01*
G01Y204635D02*
X380792D01*
G01X383392D02*
X383684Y204677D01*
X384017Y204802D01*
X384225Y205010D01*
X384309Y205302D01*
X384225Y205593D01*
X383975Y205843D01*
X383600Y205968D01*
X383184D01*
X382934Y206052D01*
X382725Y206260D01*
X382642Y206552D01*
X382767Y206843D01*
X383059Y207052D01*
X383392Y207135D01*
X383725Y207052D01*
X384017Y206843D01*
X384142Y206552D01*
X384059Y206260D01*
X383850Y206052D01*
X383600Y205968D01*
X383184D01*
X382809Y205843D01*
X382559Y205593D01*
X382475Y205302D01*
X382559Y205010D01*
X382767Y204802D01*
X383100Y204677D01*
X383392Y204635D01*
G01X385575Y205010D02*
X385825Y204802D01*
X386117Y204677D01*
X386492Y204635D01*
X386867Y204718D01*
X387159Y204885D01*
X387367Y205177D01*
X387409Y205510D01*
X387325Y205843D01*
X387117Y206052D01*
X386825Y206218D01*
X386534Y206260D01*
X386242Y206218D01*
X385867Y206052D01*
X385992Y207135D01*
X387117D01*
G01X379717Y260067D02*
Y262567D01*
X380758D01*
X381092Y262442D01*
X381300Y262275D01*
X381383Y261942D01*
X381300Y261609D01*
X381050Y261400D01*
X380758Y261275D01*
X379717D01*
G01X380758D02*
X381383Y260067D01*
G01X382733Y260567D02*
X382983Y260275D01*
X383317Y260109D01*
X383692Y260067D01*
X384025Y260109D01*
X384358Y260317D01*
X384567Y260567D01*
X384608Y260817D01*
X384525Y261109D01*
X384233Y261317D01*
X383942Y261400D01*
X383567D01*
G01X383942D02*
X384192Y261525D01*
X384400Y261734D01*
X384483Y261984D01*
X384400Y262234D01*
X384192Y262442D01*
X383817Y262567D01*
X383442Y262525D01*
X383067Y262359D01*
G01X385833Y260442D02*
X386083Y260234D01*
X386375Y260109D01*
X386750Y260067D01*
X387125Y260150D01*
X387417Y260317D01*
X387625Y260609D01*
X387667Y260942D01*
X387583Y261275D01*
X387375Y261484D01*
X387083Y261650D01*
X386792Y261692D01*
X386500Y261650D01*
X386125Y261484D01*
X386250Y262567D01*
X387375D01*
G01X390350Y260067D02*
Y262567D01*
X388808Y260775D01*
X390892D01*
G01X374189Y244084D02*
Y246584D01*
X375230D01*
X375564Y246459D01*
X375772Y246292D01*
X375855Y245959D01*
X375772Y245626D01*
X375522Y245417D01*
X375230Y245292D01*
X374189D01*
G01X375230D02*
X375855Y244084D01*
G01X377205Y244459D02*
X377455Y244251D01*
X377747Y244126D01*
X378122Y244084D01*
X378497Y244167D01*
X378789Y244334D01*
X378997Y244626D01*
X379039Y244959D01*
X378955Y245292D01*
X378747Y245501D01*
X378455Y245667D01*
X378164Y245709D01*
X377872Y245667D01*
X377497Y245501D01*
X377622Y246584D01*
X378747D01*
G01X381222D02*
X380889Y246501D01*
X380639Y246292D01*
X380472Y246042D01*
X380347Y245709D01*
X380305Y245334D01*
X380347Y244959D01*
X380472Y244626D01*
X380639Y244376D01*
X380889Y244167D01*
X381222Y244084D01*
X381555Y244167D01*
X381805Y244376D01*
X381972Y244626D01*
X382097Y244959D01*
X382139Y245334D01*
X382097Y245709D01*
X381972Y246042D01*
X381805Y246292D01*
X381555Y246501D01*
X381222Y246584D01*
G01X384322Y244084D02*
Y246584D01*
X383822Y246084D01*
G01Y244084D02*
X384822D01*
G01X364972Y247284D02*
Y243284D01*
X372372D01*
G01X351031Y240261D02*
Y244261D01*
X343631D01*
G01X351122Y245314D02*
Y249314D01*
X343722D01*
G01X349899Y253474D02*
Y255974D01*
X350940D01*
X351274Y255849D01*
X351482Y255682D01*
X351565Y255349D01*
X351482Y255016D01*
X351232Y254807D01*
X350940Y254682D01*
X349899D01*
G01X350940D02*
X351565Y253474D01*
G01X353832D02*
X354124Y253516D01*
X354457Y253641D01*
X354665Y253849D01*
X354749Y254141D01*
X354665Y254432D01*
X354415Y254682D01*
X354040Y254807D01*
X353624D01*
X353374Y254891D01*
X353165Y255099D01*
X353082Y255391D01*
X353207Y255682D01*
X353499Y255891D01*
X353832Y255974D01*
X354165Y255891D01*
X354457Y255682D01*
X354582Y255391D01*
X354499Y255099D01*
X354290Y254891D01*
X354040Y254807D01*
X353624D01*
X353249Y254682D01*
X352999Y254432D01*
X352915Y254141D01*
X352999Y253849D01*
X353207Y253641D01*
X353540Y253516D01*
X353832Y253474D01*
G01X349899Y257441D02*
Y259941D01*
X350940D01*
X351274Y259816D01*
X351482Y259649D01*
X351565Y259316D01*
X351482Y258983D01*
X351232Y258774D01*
X350940Y258649D01*
X349899D01*
G01X350940D02*
X351565Y257441D01*
G01X353124Y257733D02*
X353415Y257524D01*
X353749Y257441D01*
X354082Y257524D01*
X354374Y257774D01*
X354582Y258149D01*
X354665Y258524D01*
Y258983D01*
X354582Y259358D01*
X354374Y259691D01*
X354124Y259858D01*
X353832Y259941D01*
X353499Y259858D01*
X353249Y259691D01*
X353082Y259441D01*
X352999Y259108D01*
X353082Y258816D01*
X353290Y258524D01*
X353540Y258358D01*
X353832Y258316D01*
X354165Y258399D01*
X354415Y258608D01*
X354665Y258983D01*
G01X381417Y254867D02*
Y257367D01*
X382458D01*
X382792Y257242D01*
X383000Y257075D01*
X383083Y256742D01*
X383000Y256409D01*
X382750Y256200D01*
X382458Y256075D01*
X381417D01*
G01X382458D02*
X383083Y254867D01*
G01X384433Y255367D02*
X384683Y255075D01*
X385017Y254909D01*
X385392Y254867D01*
X385725Y254909D01*
X386058Y255117D01*
X386267Y255367D01*
X386308Y255617D01*
X386225Y255909D01*
X385933Y256117D01*
X385642Y256200D01*
X385267D01*
G01X385642D02*
X385892Y256325D01*
X386100Y256534D01*
X386183Y256784D01*
X386100Y257034D01*
X385892Y257242D01*
X385517Y257367D01*
X385142Y257325D01*
X384767Y257159D01*
G01X387533Y255242D02*
X387783Y255034D01*
X388075Y254909D01*
X388450Y254867D01*
X388825Y254950D01*
X389117Y255117D01*
X389325Y255409D01*
X389367Y255742D01*
X389283Y256075D01*
X389075Y256284D01*
X388783Y256450D01*
X388492Y256492D01*
X388200Y256450D01*
X387825Y256284D01*
X387950Y257367D01*
X389075D01*
G01X390758Y256950D02*
X391008Y257200D01*
X391300Y257325D01*
X391633Y257367D01*
X392050Y257284D01*
X392342Y257075D01*
X392425Y256825D01*
X392383Y256575D01*
X392217Y256367D01*
X391383Y255950D01*
X391008Y255659D01*
X390758Y255242D01*
X390675Y254867D01*
X392425D01*
G01X375299Y224041D02*
Y226541D01*
X376340D01*
X376674Y226416D01*
X376882Y226249D01*
X376965Y225916D01*
X376882Y225583D01*
X376632Y225374D01*
X376340Y225249D01*
X375299D01*
G01X376340D02*
X376965Y224041D01*
G01X379149D02*
X379232Y224583D01*
X379357Y225041D01*
X379524Y225458D01*
X379732Y225916D01*
X380065Y226541D01*
X378399D01*
G01X382332Y224041D02*
Y226541D01*
X381832Y226041D01*
G01Y224041D02*
X382832D01*
G01X384724Y224333D02*
X385015Y224124D01*
X385349Y224041D01*
X385682Y224124D01*
X385974Y224374D01*
X386182Y224749D01*
X386265Y225124D01*
Y225583D01*
X386182Y225958D01*
X385974Y226291D01*
X385724Y226458D01*
X385432Y226541D01*
X385099Y226458D01*
X384849Y226291D01*
X384682Y226041D01*
X384599Y225708D01*
X384682Y225416D01*
X384890Y225124D01*
X385140Y224958D01*
X385432Y224916D01*
X385765Y224999D01*
X386015Y225208D01*
X386265Y225583D01*
G01X364842Y226934D02*
Y222934D01*
X372242D01*
G01X374834Y264250D02*
X377334D01*
G01X374834Y263292D02*
Y265208D01*
G01X377334Y266517D02*
X374834D01*
Y267517D01*
X374959Y267850D01*
X375251Y268100D01*
X375584Y268183D01*
X375917Y268100D01*
X376167Y267892D01*
X376292Y267517D01*
Y266517D01*
G01X377334Y270367D02*
X376792Y270450D01*
X376334Y270575D01*
X375917Y270742D01*
X375459Y270950D01*
X374834Y271283D01*
Y269617D01*
G01X377334Y274050D02*
X374834D01*
X376626Y272508D01*
Y274592D01*
G01X384734Y264350D02*
X387234D01*
G01X384734Y263392D02*
Y265308D01*
G01X387234Y266617D02*
X384734D01*
Y267617D01*
X384859Y267950D01*
X385151Y268200D01*
X385484Y268283D01*
X385817Y268200D01*
X386067Y267992D01*
X386192Y267617D01*
Y266617D01*
G01X386859Y269633D02*
X387067Y269883D01*
X387192Y270175D01*
X387234Y270550D01*
X387151Y270925D01*
X386984Y271217D01*
X386692Y271425D01*
X386359Y271467D01*
X386026Y271383D01*
X385817Y271175D01*
X385651Y270883D01*
X385609Y270592D01*
X385651Y270300D01*
X385817Y269925D01*
X384734Y270050D01*
Y271175D01*
G01X386859Y272733D02*
X387067Y272983D01*
X387192Y273275D01*
X387234Y273650D01*
X387151Y274025D01*
X386984Y274317D01*
X386692Y274525D01*
X386359Y274567D01*
X386026Y274483D01*
X385817Y274275D01*
X385651Y273983D01*
X385609Y273692D01*
X385651Y273400D01*
X385817Y273025D01*
X384734Y273150D01*
Y274275D01*
G01X380034Y264950D02*
X382534D01*
G01X380034Y263992D02*
Y265908D01*
G01X382534Y267217D02*
X380034D01*
Y268217D01*
X380159Y268550D01*
X380451Y268800D01*
X380784Y268883D01*
X381117Y268800D01*
X381367Y268592D01*
X381492Y268217D01*
Y267217D01*
G01X382534Y271067D02*
X381992Y271150D01*
X381534Y271275D01*
X381117Y271442D01*
X380659Y271650D01*
X380034Y271983D01*
Y270317D01*
G01X382534Y274250D02*
X380034D01*
X380534Y273750D01*
G01X382534D02*
Y274750D01*
G01X374816Y210757D02*
X376608D01*
X376983Y210924D01*
X377233Y211257D01*
X377316Y211674D01*
X377233Y212091D01*
X376983Y212424D01*
X376608Y212591D01*
X374816D01*
G01X376816Y213857D02*
X377108Y214107D01*
X377274Y214441D01*
X377316Y214816D01*
X377274Y215149D01*
X377066Y215482D01*
X376816Y215691D01*
X376566Y215732D01*
X376274Y215649D01*
X376066Y215357D01*
X375983Y215066D01*
Y214691D01*
G01Y215066D02*
X375858Y215316D01*
X375649Y215524D01*
X375399Y215607D01*
X375149Y215524D01*
X374941Y215316D01*
X374816Y214941D01*
X374858Y214566D01*
X375024Y214191D01*
G01X376274Y217082D02*
X375983Y217374D01*
X375816Y217624D01*
X375733Y217957D01*
X375816Y218249D01*
X375983Y218457D01*
X376233Y218624D01*
X376524Y218666D01*
X376774Y218624D01*
X377024Y218457D01*
X377233Y218207D01*
X377316Y217916D01*
X377233Y217582D01*
X376983Y217291D01*
X376608Y217124D01*
X376191Y217082D01*
X375649Y217166D01*
X375358Y217291D01*
X375066Y217499D01*
X374858Y217791D01*
X374816Y218082D01*
X374899Y218374D01*
X375108Y218582D01*
G01X361535Y207973D02*
Y221373D01*
G01X371535Y207973D02*
X361535D01*
G01X371535Y221373D02*
Y207973D01*
G01X361535Y221373D02*
X371535D01*
G01X374289Y239484D02*
Y241984D01*
X375330D01*
X375664Y241859D01*
X375872Y241692D01*
X375955Y241359D01*
X375872Y241026D01*
X375622Y240817D01*
X375330Y240692D01*
X374289D01*
G01X375330D02*
X375955Y239484D01*
G01X378139D02*
X378222Y240026D01*
X378347Y240484D01*
X378514Y240901D01*
X378722Y241359D01*
X379055Y241984D01*
X377389D01*
G01X381322D02*
X380989Y241901D01*
X380739Y241692D01*
X380572Y241442D01*
X380447Y241109D01*
X380405Y240734D01*
X380447Y240359D01*
X380572Y240026D01*
X380739Y239776D01*
X380989Y239567D01*
X381322Y239484D01*
X381655Y239567D01*
X381905Y239776D01*
X382072Y240026D01*
X382197Y240359D01*
X382239Y240734D01*
X382197Y241109D01*
X382072Y241442D01*
X381905Y241692D01*
X381655Y241901D01*
X381322Y241984D01*
G01X384922Y239484D02*
Y241984D01*
X383380Y240192D01*
X385464D01*
G01X365072Y242684D02*
Y238684D01*
X372472D01*
G01X378015Y231441D02*
Y233941D01*
X378849D01*
X379182Y233816D01*
X379432Y233649D01*
X379640Y233399D01*
X379807Y233108D01*
X379849Y232691D01*
X379807Y232274D01*
X379640Y231983D01*
X379432Y231733D01*
X379182Y231566D01*
X378849Y231441D01*
X378015D01*
G01X382532D02*
Y233941D01*
X380990Y232149D01*
X383074D01*
G01X372392Y228174D02*
Y237274D01*
X350592D01*
Y228174D01*
X372392D01*
G01X392017Y327592D02*
X391767Y327717D01*
X391475Y327800D01*
X391142D01*
X390767Y327675D01*
X390475Y327467D01*
X390267Y327217D01*
X390100Y326800D01*
X390058Y326425D01*
X390142Y326050D01*
X390267Y325800D01*
X390517Y325550D01*
X390808Y325383D01*
X391100Y325300D01*
X391392D01*
X391683Y325383D01*
X391933Y325508D01*
X392142Y325675D01*
G01X394200Y325300D02*
X394492Y325342D01*
X394825Y325467D01*
X395033Y325675D01*
X395117Y325967D01*
X395033Y326258D01*
X394783Y326508D01*
X394408Y326633D01*
X393992D01*
X393742Y326717D01*
X393533Y326925D01*
X393450Y327217D01*
X393575Y327508D01*
X393867Y327717D01*
X394200Y327800D01*
X394533Y327717D01*
X394825Y327508D01*
X394950Y327217D01*
X394867Y326925D01*
X394658Y326717D01*
X394408Y326633D01*
X393992D01*
X393617Y326508D01*
X393367Y326258D01*
X393283Y325967D01*
X393367Y325675D01*
X393575Y325467D01*
X393908Y325342D01*
X394200Y325300D01*
G01X396508Y327383D02*
X396758Y327633D01*
X397050Y327758D01*
X397383Y327800D01*
X397800Y327717D01*
X398092Y327508D01*
X398175Y327258D01*
X398133Y327008D01*
X397967Y326800D01*
X397133Y326383D01*
X396758Y326092D01*
X396508Y325675D01*
X396425Y325300D01*
X398175D01*
G01X374117Y317700D02*
Y320200D01*
X375158D01*
X375492Y320075D01*
X375700Y319908D01*
X375783Y319575D01*
X375700Y319242D01*
X375450Y319033D01*
X375158Y318908D01*
X374117D01*
G01X375158D02*
X375783Y317700D01*
G01X378050D02*
Y320200D01*
X377550Y319700D01*
G01Y317700D02*
X378550D01*
G01X380358Y318742D02*
X380650Y319033D01*
X380900Y319200D01*
X381233Y319283D01*
X381525Y319200D01*
X381733Y319033D01*
X381900Y318783D01*
X381942Y318492D01*
X381900Y318242D01*
X381733Y317992D01*
X381483Y317783D01*
X381192Y317700D01*
X380858Y317783D01*
X380567Y318033D01*
X380400Y318408D01*
X380358Y318825D01*
X380442Y319367D01*
X380567Y319658D01*
X380775Y319950D01*
X381067Y320158D01*
X381358Y320200D01*
X381650Y320117D01*
X381858Y319908D01*
G01X384750Y317700D02*
Y320200D01*
X383208Y318408D01*
X385292D01*
G01X374117Y293700D02*
Y296200D01*
X375158D01*
X375492Y296075D01*
X375700Y295908D01*
X375783Y295575D01*
X375700Y295242D01*
X375450Y295033D01*
X375158Y294908D01*
X374117D01*
G01X375158D02*
X375783Y293700D01*
G01X378050D02*
Y296200D01*
X377550Y295700D01*
G01Y293700D02*
X378550D01*
G01X381067D02*
X381150Y294242D01*
X381275Y294700D01*
X381442Y295117D01*
X381650Y295575D01*
X381983Y296200D01*
X380317D01*
G01X383458Y294742D02*
X383750Y295033D01*
X384000Y295200D01*
X384333Y295283D01*
X384625Y295200D01*
X384833Y295033D01*
X385000Y294783D01*
X385042Y294492D01*
X385000Y294242D01*
X384833Y293992D01*
X384583Y293783D01*
X384292Y293700D01*
X383958Y293783D01*
X383667Y294033D01*
X383500Y294408D01*
X383458Y294825D01*
X383542Y295367D01*
X383667Y295658D01*
X383875Y295950D01*
X384167Y296158D01*
X384458Y296200D01*
X384750Y296117D01*
X384958Y295908D01*
G01X389867Y301900D02*
Y304400D01*
X390908D01*
X391242Y304275D01*
X391450Y304108D01*
X391533Y303775D01*
X391450Y303442D01*
X391200Y303233D01*
X390908Y303108D01*
X389867D01*
G01X390908D02*
X391533Y301900D01*
G01X393800D02*
Y304400D01*
X393300Y303900D01*
G01Y301900D02*
X394300D01*
G01X396900D02*
X397192Y301942D01*
X397525Y302067D01*
X397733Y302275D01*
X397817Y302567D01*
X397733Y302858D01*
X397483Y303108D01*
X397108Y303233D01*
X396692D01*
X396442Y303317D01*
X396233Y303525D01*
X396150Y303817D01*
X396275Y304108D01*
X396567Y304317D01*
X396900Y304400D01*
X397233Y304317D01*
X397525Y304108D01*
X397650Y303817D01*
X397567Y303525D01*
X397358Y303317D01*
X397108Y303233D01*
X396692D01*
X396317Y303108D01*
X396067Y302858D01*
X395983Y302567D01*
X396067Y302275D01*
X396275Y302067D01*
X396608Y301942D01*
X396900Y301900D01*
G01X400000D02*
Y304400D01*
X399500Y303900D01*
G01Y301900D02*
X400500D01*
G01X389867Y309300D02*
Y311800D01*
X390908D01*
X391242Y311675D01*
X391450Y311508D01*
X391533Y311175D01*
X391450Y310842D01*
X391200Y310633D01*
X390908Y310508D01*
X389867D01*
G01X390908D02*
X391533Y309300D01*
G01X393800D02*
Y311800D01*
X393300Y311300D01*
G01Y309300D02*
X394300D01*
G01X396900D02*
X397192Y309342D01*
X397525Y309467D01*
X397733Y309675D01*
X397817Y309967D01*
X397733Y310258D01*
X397483Y310508D01*
X397108Y310633D01*
X396692D01*
X396442Y310717D01*
X396233Y310925D01*
X396150Y311217D01*
X396275Y311508D01*
X396567Y311717D01*
X396900Y311800D01*
X397233Y311717D01*
X397525Y311508D01*
X397650Y311217D01*
X397567Y310925D01*
X397358Y310717D01*
X397108Y310633D01*
X396692D01*
X396317Y310508D01*
X396067Y310258D01*
X395983Y309967D01*
X396067Y309675D01*
X396275Y309467D01*
X396608Y309342D01*
X396900Y309300D01*
G01X399208Y311383D02*
X399458Y311633D01*
X399750Y311758D01*
X400083Y311800D01*
X400500Y311717D01*
X400792Y311508D01*
X400875Y311258D01*
X400833Y311008D01*
X400667Y310800D01*
X399833Y310383D01*
X399458Y310092D01*
X399208Y309675D01*
X399125Y309300D01*
X400875D01*
G01X389867Y313300D02*
Y315800D01*
X390908D01*
X391242Y315675D01*
X391450Y315508D01*
X391533Y315175D01*
X391450Y314842D01*
X391200Y314633D01*
X390908Y314508D01*
X389867D01*
G01X390908D02*
X391533Y313300D01*
G01X393800D02*
Y315800D01*
X393300Y315300D01*
G01Y313300D02*
X394300D01*
G01X396192Y313592D02*
X396483Y313383D01*
X396817Y313300D01*
X397150Y313383D01*
X397442Y313633D01*
X397650Y314008D01*
X397733Y314383D01*
Y314842D01*
X397650Y315217D01*
X397442Y315550D01*
X397192Y315717D01*
X396900Y315800D01*
X396567Y315717D01*
X396317Y315550D01*
X396150Y315300D01*
X396067Y314967D01*
X396150Y314675D01*
X396358Y314383D01*
X396608Y314217D01*
X396900Y314175D01*
X397233Y314258D01*
X397483Y314467D01*
X397733Y314842D01*
G01X400000Y315800D02*
X399667Y315717D01*
X399417Y315508D01*
X399250Y315258D01*
X399125Y314925D01*
X399083Y314550D01*
X399125Y314175D01*
X399250Y313842D01*
X399417Y313592D01*
X399667Y313383D01*
X400000Y313300D01*
X400333Y313383D01*
X400583Y313592D01*
X400750Y313842D01*
X400875Y314175D01*
X400917Y314550D01*
X400875Y314925D01*
X400750Y315258D01*
X400583Y315508D01*
X400333Y315717D01*
X400000Y315800D01*
G01X374017Y324100D02*
Y326600D01*
X375058D01*
X375392Y326475D01*
X375600Y326308D01*
X375683Y325975D01*
X375600Y325642D01*
X375350Y325433D01*
X375058Y325308D01*
X374017D01*
G01X375058D02*
X375683Y324100D01*
G01X377033Y324600D02*
X377283Y324308D01*
X377617Y324142D01*
X377992Y324100D01*
X378325Y324142D01*
X378658Y324350D01*
X378867Y324600D01*
X378908Y324850D01*
X378825Y325142D01*
X378533Y325350D01*
X378242Y325433D01*
X377867D01*
G01X378242D02*
X378492Y325558D01*
X378700Y325767D01*
X378783Y326017D01*
X378700Y326267D01*
X378492Y326475D01*
X378117Y326600D01*
X377742Y326558D01*
X377367Y326392D01*
G01X380133Y324600D02*
X380383Y324308D01*
X380717Y324142D01*
X381092Y324100D01*
X381425Y324142D01*
X381758Y324350D01*
X381967Y324600D01*
X382008Y324850D01*
X381925Y325142D01*
X381633Y325350D01*
X381342Y325433D01*
X380967D01*
G01X381342D02*
X381592Y325558D01*
X381800Y325767D01*
X381883Y326017D01*
X381800Y326267D01*
X381592Y326475D01*
X381217Y326600D01*
X380842Y326558D01*
X380467Y326392D01*
G01X384150Y324100D02*
X384442Y324142D01*
X384775Y324267D01*
X384983Y324475D01*
X385067Y324767D01*
X384983Y325058D01*
X384733Y325308D01*
X384358Y325433D01*
X383942D01*
X383692Y325517D01*
X383483Y325725D01*
X383400Y326017D01*
X383525Y326308D01*
X383817Y326517D01*
X384150Y326600D01*
X384483Y326517D01*
X384775Y326308D01*
X384900Y326017D01*
X384817Y325725D01*
X384608Y325517D01*
X384358Y325433D01*
X383942D01*
X383567Y325308D01*
X383317Y325058D01*
X383233Y324767D01*
X383317Y324475D01*
X383525Y324267D01*
X383858Y324142D01*
X384150Y324100D01*
G01X390267Y321300D02*
Y323800D01*
X391308D01*
X391642Y323675D01*
X391850Y323508D01*
X391933Y323175D01*
X391850Y322842D01*
X391600Y322633D01*
X391308Y322508D01*
X390267D01*
G01X391308D02*
X391933Y321300D01*
G01X394200D02*
Y323800D01*
X393700Y323300D01*
G01Y321300D02*
X394700D01*
G01X397300D02*
X397592Y321342D01*
X397925Y321467D01*
X398133Y321675D01*
X398217Y321967D01*
X398133Y322258D01*
X397883Y322508D01*
X397508Y322633D01*
X397092D01*
X396842Y322717D01*
X396633Y322925D01*
X396550Y323217D01*
X396675Y323508D01*
X396967Y323717D01*
X397300Y323800D01*
X397633Y323717D01*
X397925Y323508D01*
X398050Y323217D01*
X397967Y322925D01*
X397758Y322717D01*
X397508Y322633D01*
X397092D01*
X396717Y322508D01*
X396467Y322258D01*
X396383Y321967D01*
X396467Y321675D01*
X396675Y321467D01*
X397008Y321342D01*
X397300Y321300D01*
G01X399692Y321592D02*
X399983Y321383D01*
X400317Y321300D01*
X400650Y321383D01*
X400942Y321633D01*
X401150Y322008D01*
X401233Y322383D01*
Y322842D01*
X401150Y323217D01*
X400942Y323550D01*
X400692Y323717D01*
X400400Y323800D01*
X400067Y323717D01*
X399817Y323550D01*
X399650Y323300D01*
X399567Y322967D01*
X399650Y322675D01*
X399858Y322383D01*
X400108Y322217D01*
X400400Y322175D01*
X400733Y322258D01*
X400983Y322467D01*
X401233Y322842D01*
G01X374117Y289700D02*
Y292200D01*
X375158D01*
X375492Y292075D01*
X375700Y291908D01*
X375783Y291575D01*
X375700Y291242D01*
X375450Y291033D01*
X375158Y290908D01*
X374117D01*
G01X375158D02*
X375783Y289700D01*
G01X377258Y291783D02*
X377508Y292033D01*
X377800Y292158D01*
X378133Y292200D01*
X378550Y292117D01*
X378842Y291908D01*
X378925Y291658D01*
X378883Y291408D01*
X378717Y291200D01*
X377883Y290783D01*
X377508Y290492D01*
X377258Y290075D01*
X377175Y289700D01*
X378925D01*
G01X381067D02*
X381150Y290242D01*
X381275Y290700D01*
X381442Y291117D01*
X381650Y291575D01*
X381983Y292200D01*
X380317D01*
G01X384250Y289700D02*
Y292200D01*
X383750Y291700D01*
G01Y289700D02*
X384750D01*
G01X350561Y267885D02*
Y270385D01*
X351602D01*
X351936Y270260D01*
X352144Y270093D01*
X352227Y269760D01*
X352144Y269427D01*
X351894Y269218D01*
X351602Y269093D01*
X350561D01*
G01X351602D02*
X352227Y267885D01*
G01X354494D02*
Y270385D01*
X353994Y269885D01*
G01Y267885D02*
X354994D01*
G01X358094D02*
Y270385D01*
X356552Y268593D01*
X358636D01*
G01X348194Y266585D02*
Y270585D01*
X340794D01*
G01X350858Y272206D02*
Y274706D01*
X351899D01*
X352233Y274581D01*
X352441Y274414D01*
X352524Y274081D01*
X352441Y273748D01*
X352191Y273539D01*
X351899Y273414D01*
X350858D01*
G01X351899D02*
X352524Y272206D01*
G01X354791D02*
Y274706D01*
X354291Y274206D01*
G01Y272206D02*
X355291D01*
G01X356974Y272581D02*
X357224Y272373D01*
X357516Y272248D01*
X357891Y272206D01*
X358266Y272289D01*
X358558Y272456D01*
X358766Y272748D01*
X358808Y273081D01*
X358724Y273414D01*
X358516Y273623D01*
X358224Y273789D01*
X357933Y273831D01*
X357641Y273789D01*
X357266Y273623D01*
X357391Y274706D01*
X358516D01*
G01X348491Y270906D02*
Y274906D01*
X341091D01*
G01X374117Y297700D02*
Y300200D01*
X375158D01*
X375492Y300075D01*
X375700Y299908D01*
X375783Y299575D01*
X375700Y299242D01*
X375450Y299033D01*
X375158Y298908D01*
X374117D01*
G01X375158D02*
X375783Y297700D01*
G01X378050D02*
Y300200D01*
X377550Y299700D01*
G01Y297700D02*
X378550D01*
G01X380233Y298075D02*
X380483Y297867D01*
X380775Y297742D01*
X381150Y297700D01*
X381525Y297783D01*
X381817Y297950D01*
X382025Y298242D01*
X382067Y298575D01*
X381983Y298908D01*
X381775Y299117D01*
X381483Y299283D01*
X381192Y299325D01*
X380900Y299283D01*
X380525Y299117D01*
X380650Y300200D01*
X381775D01*
G01X383333Y298075D02*
X383583Y297867D01*
X383875Y297742D01*
X384250Y297700D01*
X384625Y297783D01*
X384917Y297950D01*
X385125Y298242D01*
X385167Y298575D01*
X385083Y298908D01*
X384875Y299117D01*
X384583Y299283D01*
X384292Y299325D01*
X384000Y299283D01*
X383625Y299117D01*
X383750Y300200D01*
X384875D01*
G01X374117Y301700D02*
Y304200D01*
X375158D01*
X375492Y304075D01*
X375700Y303908D01*
X375783Y303575D01*
X375700Y303242D01*
X375450Y303033D01*
X375158Y302908D01*
X374117D01*
G01X375158D02*
X375783Y301700D01*
G01X378050D02*
Y304200D01*
X377550Y303700D01*
G01Y301700D02*
X378550D01*
G01X380233Y302075D02*
X380483Y301867D01*
X380775Y301742D01*
X381150Y301700D01*
X381525Y301783D01*
X381817Y301950D01*
X382025Y302242D01*
X382067Y302575D01*
X381983Y302908D01*
X381775Y303117D01*
X381483Y303283D01*
X381192Y303325D01*
X380900Y303283D01*
X380525Y303117D01*
X380650Y304200D01*
X381775D01*
G01X384167Y301700D02*
X384250Y302242D01*
X384375Y302700D01*
X384542Y303117D01*
X384750Y303575D01*
X385083Y304200D01*
X383417D01*
G01X374117Y305700D02*
Y308200D01*
X375158D01*
X375492Y308075D01*
X375700Y307908D01*
X375783Y307575D01*
X375700Y307242D01*
X375450Y307033D01*
X375158Y306908D01*
X374117D01*
G01X375158D02*
X375783Y305700D01*
G01X378050D02*
Y308200D01*
X377550Y307700D01*
G01Y305700D02*
X378550D01*
G01X380358Y306742D02*
X380650Y307033D01*
X380900Y307200D01*
X381233Y307283D01*
X381525Y307200D01*
X381733Y307033D01*
X381900Y306783D01*
X381942Y306492D01*
X381900Y306242D01*
X381733Y305992D01*
X381483Y305783D01*
X381192Y305700D01*
X380858Y305783D01*
X380567Y306033D01*
X380400Y306408D01*
X380358Y306825D01*
X380442Y307367D01*
X380567Y307658D01*
X380775Y307950D01*
X381067Y308158D01*
X381358Y308200D01*
X381650Y308117D01*
X381858Y307908D01*
G01X384250Y308200D02*
X383917Y308117D01*
X383667Y307908D01*
X383500Y307658D01*
X383375Y307325D01*
X383333Y306950D01*
X383375Y306575D01*
X383500Y306242D01*
X383667Y305992D01*
X383917Y305783D01*
X384250Y305700D01*
X384583Y305783D01*
X384833Y305992D01*
X385000Y306242D01*
X385125Y306575D01*
X385167Y306950D01*
X385125Y307325D01*
X385000Y307658D01*
X384833Y307908D01*
X384583Y308117D01*
X384250Y308200D01*
G01X374117Y309700D02*
Y312200D01*
X375158D01*
X375492Y312075D01*
X375700Y311908D01*
X375783Y311575D01*
X375700Y311242D01*
X375450Y311033D01*
X375158Y310908D01*
X374117D01*
G01X375158D02*
X375783Y309700D01*
G01X378050D02*
Y312200D01*
X377550Y311700D01*
G01Y309700D02*
X378550D01*
G01X380358Y310742D02*
X380650Y311033D01*
X380900Y311200D01*
X381233Y311283D01*
X381525Y311200D01*
X381733Y311033D01*
X381900Y310783D01*
X381942Y310492D01*
X381900Y310242D01*
X381733Y309992D01*
X381483Y309783D01*
X381192Y309700D01*
X380858Y309783D01*
X380567Y310033D01*
X380400Y310408D01*
X380358Y310825D01*
X380442Y311367D01*
X380567Y311658D01*
X380775Y311950D01*
X381067Y312158D01*
X381358Y312200D01*
X381650Y312117D01*
X381858Y311908D01*
G01X383458Y311783D02*
X383708Y312033D01*
X384000Y312158D01*
X384333Y312200D01*
X384750Y312117D01*
X385042Y311908D01*
X385125Y311658D01*
X385083Y311408D01*
X384917Y311200D01*
X384083Y310783D01*
X383708Y310492D01*
X383458Y310075D01*
X383375Y309700D01*
X385125D01*
G01X374117Y313700D02*
Y316200D01*
X375158D01*
X375492Y316075D01*
X375700Y315908D01*
X375783Y315575D01*
X375700Y315242D01*
X375450Y315033D01*
X375158Y314908D01*
X374117D01*
G01X375158D02*
X375783Y313700D01*
G01X378050D02*
Y316200D01*
X377550Y315700D01*
G01Y313700D02*
X378550D01*
G01X380358Y314742D02*
X380650Y315033D01*
X380900Y315200D01*
X381233Y315283D01*
X381525Y315200D01*
X381733Y315033D01*
X381900Y314783D01*
X381942Y314492D01*
X381900Y314242D01*
X381733Y313992D01*
X381483Y313783D01*
X381192Y313700D01*
X380858Y313783D01*
X380567Y314033D01*
X380400Y314408D01*
X380358Y314825D01*
X380442Y315367D01*
X380567Y315658D01*
X380775Y315950D01*
X381067Y316158D01*
X381358Y316200D01*
X381650Y316117D01*
X381858Y315908D01*
G01X383458Y314742D02*
X383750Y315033D01*
X384000Y315200D01*
X384333Y315283D01*
X384625Y315200D01*
X384833Y315033D01*
X385000Y314783D01*
X385042Y314492D01*
X385000Y314242D01*
X384833Y313992D01*
X384583Y313783D01*
X384292Y313700D01*
X383958Y313783D01*
X383667Y314033D01*
X383500Y314408D01*
X383458Y314825D01*
X383542Y315367D01*
X383667Y315658D01*
X383875Y315950D01*
X384167Y316158D01*
X384458Y316200D01*
X384750Y316117D01*
X384958Y315908D01*
G01X389867Y289900D02*
Y292400D01*
X390908D01*
X391242Y292275D01*
X391450Y292108D01*
X391533Y291775D01*
X391450Y291442D01*
X391200Y291233D01*
X390908Y291108D01*
X389867D01*
G01X390908D02*
X391533Y289900D01*
G01X393800D02*
Y292400D01*
X393300Y291900D01*
G01Y289900D02*
X394300D01*
G01X396900D02*
X397192Y289942D01*
X397525Y290067D01*
X397733Y290275D01*
X397817Y290567D01*
X397733Y290858D01*
X397483Y291108D01*
X397108Y291233D01*
X396692D01*
X396442Y291317D01*
X396233Y291525D01*
X396150Y291817D01*
X396275Y292108D01*
X396567Y292317D01*
X396900Y292400D01*
X397233Y292317D01*
X397525Y292108D01*
X397650Y291817D01*
X397567Y291525D01*
X397358Y291317D01*
X397108Y291233D01*
X396692D01*
X396317Y291108D01*
X396067Y290858D01*
X395983Y290567D01*
X396067Y290275D01*
X396275Y290067D01*
X396608Y289942D01*
X396900Y289900D01*
G01X399208Y290942D02*
X399500Y291233D01*
X399750Y291400D01*
X400083Y291483D01*
X400375Y291400D01*
X400583Y291233D01*
X400750Y290983D01*
X400792Y290692D01*
X400750Y290442D01*
X400583Y290192D01*
X400333Y289983D01*
X400042Y289900D01*
X399708Y289983D01*
X399417Y290233D01*
X399250Y290608D01*
X399208Y291025D01*
X399292Y291567D01*
X399417Y291858D01*
X399625Y292150D01*
X399917Y292358D01*
X400208Y292400D01*
X400500Y292317D01*
X400708Y292108D01*
G01X389867Y293900D02*
Y296400D01*
X390908D01*
X391242Y296275D01*
X391450Y296108D01*
X391533Y295775D01*
X391450Y295442D01*
X391200Y295233D01*
X390908Y295108D01*
X389867D01*
G01X390908D02*
X391533Y293900D01*
G01X393800D02*
Y296400D01*
X393300Y295900D01*
G01Y293900D02*
X394300D01*
G01X396192Y294192D02*
X396483Y293983D01*
X396817Y293900D01*
X397150Y293983D01*
X397442Y294233D01*
X397650Y294608D01*
X397733Y294983D01*
Y295442D01*
X397650Y295817D01*
X397442Y296150D01*
X397192Y296317D01*
X396900Y296400D01*
X396567Y296317D01*
X396317Y296150D01*
X396150Y295900D01*
X396067Y295567D01*
X396150Y295275D01*
X396358Y294983D01*
X396608Y294817D01*
X396900Y294775D01*
X397233Y294858D01*
X397483Y295067D01*
X397733Y295442D01*
G01X400000Y293900D02*
X400292Y293942D01*
X400625Y294067D01*
X400833Y294275D01*
X400917Y294567D01*
X400833Y294858D01*
X400583Y295108D01*
X400208Y295233D01*
X399792D01*
X399542Y295317D01*
X399333Y295525D01*
X399250Y295817D01*
X399375Y296108D01*
X399667Y296317D01*
X400000Y296400D01*
X400333Y296317D01*
X400625Y296108D01*
X400750Y295817D01*
X400667Y295525D01*
X400458Y295317D01*
X400208Y295233D01*
X399792D01*
X399417Y295108D01*
X399167Y294858D01*
X399083Y294567D01*
X399167Y294275D01*
X399375Y294067D01*
X399708Y293942D01*
X400000Y293900D01*
G01X389867Y297900D02*
Y300400D01*
X390908D01*
X391242Y300275D01*
X391450Y300108D01*
X391533Y299775D01*
X391450Y299442D01*
X391200Y299233D01*
X390908Y299108D01*
X389867D01*
G01X390908D02*
X391533Y297900D01*
G01X393800D02*
Y300400D01*
X393300Y299900D01*
G01Y297900D02*
X394300D01*
G01X396192Y298192D02*
X396483Y297983D01*
X396817Y297900D01*
X397150Y297983D01*
X397442Y298233D01*
X397650Y298608D01*
X397733Y298983D01*
Y299442D01*
X397650Y299817D01*
X397442Y300150D01*
X397192Y300317D01*
X396900Y300400D01*
X396567Y300317D01*
X396317Y300150D01*
X396150Y299900D01*
X396067Y299567D01*
X396150Y299275D01*
X396358Y298983D01*
X396608Y298817D01*
X396900Y298775D01*
X397233Y298858D01*
X397483Y299067D01*
X397733Y299442D01*
G01X399292Y298192D02*
X399583Y297983D01*
X399917Y297900D01*
X400250Y297983D01*
X400542Y298233D01*
X400750Y298608D01*
X400833Y298983D01*
Y299442D01*
X400750Y299817D01*
X400542Y300150D01*
X400292Y300317D01*
X400000Y300400D01*
X399667Y300317D01*
X399417Y300150D01*
X399250Y299900D01*
X399167Y299567D01*
X399250Y299275D01*
X399458Y298983D01*
X399708Y298817D01*
X400000Y298775D01*
X400333Y298858D01*
X400583Y299067D01*
X400833Y299442D01*
G01X380417Y331300D02*
Y333800D01*
X381458D01*
X381792Y333675D01*
X382000Y333508D01*
X382083Y333175D01*
X382000Y332842D01*
X381750Y332633D01*
X381458Y332508D01*
X380417D01*
G01X381458D02*
X382083Y331300D01*
G01X383433Y331800D02*
X383683Y331508D01*
X384017Y331342D01*
X384392Y331300D01*
X384725Y331342D01*
X385058Y331550D01*
X385267Y331800D01*
X385308Y332050D01*
X385225Y332342D01*
X384933Y332550D01*
X384642Y332633D01*
X384267D01*
G01X384642D02*
X384892Y332758D01*
X385100Y332967D01*
X385183Y333217D01*
X385100Y333467D01*
X384892Y333675D01*
X384517Y333800D01*
X384142Y333758D01*
X383767Y333592D01*
G01X387950Y331300D02*
Y333800D01*
X386408Y332008D01*
X388492D01*
G01X390550Y333800D02*
X390217Y333717D01*
X389967Y333508D01*
X389800Y333258D01*
X389675Y332925D01*
X389633Y332550D01*
X389675Y332175D01*
X389800Y331842D01*
X389967Y331592D01*
X390217Y331383D01*
X390550Y331300D01*
X390883Y331383D01*
X391133Y331592D01*
X391300Y331842D01*
X391425Y332175D01*
X391467Y332550D01*
X391425Y332925D01*
X391300Y333258D01*
X391133Y333508D01*
X390883Y333717D01*
X390550Y333800D01*
G01X384534Y276850D02*
X387034D01*
G01X384534Y275892D02*
Y277808D01*
G01X387034Y279117D02*
X384534D01*
Y280117D01*
X384659Y280450D01*
X384951Y280700D01*
X385284Y280783D01*
X385617Y280700D01*
X385867Y280492D01*
X385992Y280117D01*
Y279117D01*
G01X387034Y283050D02*
X384534D01*
X385034Y282550D01*
G01X387034D02*
Y283550D01*
G01X385992Y285358D02*
X385701Y285650D01*
X385534Y285900D01*
X385451Y286233D01*
X385534Y286525D01*
X385701Y286733D01*
X385951Y286900D01*
X386242Y286942D01*
X386492Y286900D01*
X386742Y286733D01*
X386951Y286483D01*
X387034Y286192D01*
X386951Y285858D01*
X386701Y285567D01*
X386326Y285400D01*
X385909Y285358D01*
X385367Y285442D01*
X385076Y285567D01*
X384784Y285775D01*
X384576Y286067D01*
X384534Y286358D01*
X384617Y286650D01*
X384826Y286858D01*
G01X379934Y276750D02*
X382434D01*
G01X379934Y275792D02*
Y277708D01*
G01X382434Y279017D02*
X379934D01*
Y280017D01*
X380059Y280350D01*
X380351Y280600D01*
X380684Y280683D01*
X381017Y280600D01*
X381267Y280392D01*
X381392Y280017D01*
Y279017D01*
G01X382434Y282867D02*
X381892Y282950D01*
X381434Y283075D01*
X381017Y283242D01*
X380559Y283450D01*
X379934Y283783D01*
Y282117D01*
G01X382059Y285133D02*
X382267Y285383D01*
X382392Y285675D01*
X382434Y286050D01*
X382351Y286425D01*
X382184Y286717D01*
X381892Y286925D01*
X381559Y286967D01*
X381226Y286883D01*
X381017Y286675D01*
X380851Y286383D01*
X380809Y286092D01*
X380851Y285800D01*
X381017Y285425D01*
X379934Y285550D01*
Y286675D01*
G01X374934Y276650D02*
X377434D01*
G01X374934Y275692D02*
Y277608D01*
G01X377434Y278917D02*
X374934D01*
Y279917D01*
X375059Y280250D01*
X375351Y280500D01*
X375684Y280583D01*
X376017Y280500D01*
X376267Y280292D01*
X376392Y279917D01*
Y278917D01*
G01X377434Y282767D02*
X376892Y282850D01*
X376434Y282975D01*
X376017Y283142D01*
X375559Y283350D01*
X374934Y283683D01*
Y282017D01*
G01X377434Y285867D02*
X376892Y285950D01*
X376434Y286075D01*
X376017Y286242D01*
X375559Y286450D01*
X374934Y286783D01*
Y285117D01*
G01X394067Y332900D02*
X397400Y339900D01*
X400733Y332900D01*
G01X399533Y335350D02*
X395267D01*
G01X396572Y343498D02*
X394072D01*
Y344539D01*
X394197Y344873D01*
X394364Y345081D01*
X394697Y345164D01*
X395030Y345081D01*
X395239Y344831D01*
X395364Y344539D01*
Y343498D01*
G01Y344539D02*
X396572Y345164D01*
G01X396072Y346514D02*
X396364Y346764D01*
X396530Y347098D01*
X396572Y347473D01*
X396530Y347806D01*
X396322Y348139D01*
X396072Y348348D01*
X395822Y348389D01*
X395530Y348306D01*
X395322Y348014D01*
X395239Y347723D01*
Y347348D01*
G01Y347723D02*
X395114Y347973D01*
X394905Y348181D01*
X394655Y348264D01*
X394405Y348181D01*
X394197Y347973D01*
X394072Y347598D01*
X394114Y347223D01*
X394280Y346848D01*
G01X396572Y350531D02*
X396530Y350823D01*
X396405Y351156D01*
X396197Y351364D01*
X395905Y351448D01*
X395614Y351364D01*
X395364Y351114D01*
X395239Y350739D01*
Y350323D01*
X395155Y350073D01*
X394947Y349864D01*
X394655Y349781D01*
X394364Y349906D01*
X394155Y350198D01*
X394072Y350531D01*
X394155Y350864D01*
X394364Y351156D01*
X394655Y351281D01*
X394947Y351198D01*
X395155Y350989D01*
X395239Y350739D01*
Y350323D01*
X395364Y349948D01*
X395614Y349698D01*
X395905Y349614D01*
X396197Y349698D01*
X396405Y349906D01*
X396530Y350239D01*
X396572Y350531D01*
G01X394489Y352839D02*
X394239Y353089D01*
X394114Y353381D01*
X394072Y353714D01*
X394155Y354131D01*
X394364Y354423D01*
X394614Y354506D01*
X394864Y354464D01*
X395072Y354298D01*
X395489Y353464D01*
X395780Y353089D01*
X396197Y352839D01*
X396572Y352756D01*
Y354506D01*
G01X382300Y349317D02*
X379800D01*
Y350358D01*
X379925Y350692D01*
X380092Y350900D01*
X380425Y350983D01*
X380758Y350900D01*
X380967Y350650D01*
X381092Y350358D01*
Y349317D01*
G01Y350358D02*
X382300Y350983D01*
G01X381800Y352333D02*
X382092Y352583D01*
X382258Y352917D01*
X382300Y353292D01*
X382258Y353625D01*
X382050Y353958D01*
X381800Y354167D01*
X381550Y354208D01*
X381258Y354125D01*
X381050Y353833D01*
X380967Y353542D01*
Y353167D01*
G01Y353542D02*
X380842Y353792D01*
X380633Y354000D01*
X380383Y354083D01*
X380133Y354000D01*
X379925Y353792D01*
X379800Y353417D01*
X379842Y353042D01*
X380008Y352667D01*
G01X382008Y355642D02*
X382217Y355933D01*
X382300Y356267D01*
X382217Y356600D01*
X381967Y356892D01*
X381592Y357100D01*
X381217Y357183D01*
X380758D01*
X380383Y357100D01*
X380050Y356892D01*
X379883Y356642D01*
X379800Y356350D01*
X379883Y356017D01*
X380050Y355767D01*
X380300Y355600D01*
X380633Y355517D01*
X380925Y355600D01*
X381217Y355808D01*
X381383Y356058D01*
X381425Y356350D01*
X381342Y356683D01*
X381133Y356933D01*
X380758Y357183D01*
G01X382300Y359367D02*
X381758Y359450D01*
X381300Y359575D01*
X380883Y359742D01*
X380425Y359950D01*
X379800Y360283D01*
Y358617D01*
G01X392515Y343504D02*
X390015D01*
Y344545D01*
X390140Y344879D01*
X390307Y345087D01*
X390640Y345170D01*
X390973Y345087D01*
X391182Y344837D01*
X391307Y344545D01*
Y343504D01*
G01Y344545D02*
X392515Y345170D01*
G01X392015Y346520D02*
X392307Y346770D01*
X392473Y347104D01*
X392515Y347479D01*
X392473Y347812D01*
X392265Y348145D01*
X392015Y348354D01*
X391765Y348395D01*
X391473Y348312D01*
X391265Y348020D01*
X391182Y347729D01*
Y347354D01*
G01Y347729D02*
X391057Y347979D01*
X390848Y348187D01*
X390598Y348270D01*
X390348Y348187D01*
X390140Y347979D01*
X390015Y347604D01*
X390057Y347229D01*
X390223Y346854D01*
G01X392515Y350537D02*
X392473Y350829D01*
X392348Y351162D01*
X392140Y351370D01*
X391848Y351454D01*
X391557Y351370D01*
X391307Y351120D01*
X391182Y350745D01*
Y350329D01*
X391098Y350079D01*
X390890Y349870D01*
X390598Y349787D01*
X390307Y349912D01*
X390098Y350204D01*
X390015Y350537D01*
X390098Y350870D01*
X390307Y351162D01*
X390598Y351287D01*
X390890Y351204D01*
X391098Y350995D01*
X391182Y350745D01*
Y350329D01*
X391307Y349954D01*
X391557Y349704D01*
X391848Y349620D01*
X392140Y349704D01*
X392348Y349912D01*
X392473Y350245D01*
X392515Y350537D01*
G01Y353554D02*
X391973Y353637D01*
X391515Y353762D01*
X391098Y353929D01*
X390640Y354137D01*
X390015Y354470D01*
Y352804D01*
G01X378300Y349317D02*
X375800D01*
Y350358D01*
X375925Y350692D01*
X376092Y350900D01*
X376425Y350983D01*
X376758Y350900D01*
X376967Y350650D01*
X377092Y350358D01*
Y349317D01*
G01Y350358D02*
X378300Y350983D01*
G01X377800Y352333D02*
X378092Y352583D01*
X378258Y352917D01*
X378300Y353292D01*
X378258Y353625D01*
X378050Y353958D01*
X377800Y354167D01*
X377550Y354208D01*
X377258Y354125D01*
X377050Y353833D01*
X376967Y353542D01*
Y353167D01*
G01Y353542D02*
X376842Y353792D01*
X376633Y354000D01*
X376383Y354083D01*
X376133Y354000D01*
X375925Y353792D01*
X375800Y353417D01*
X375842Y353042D01*
X376008Y352667D01*
G01X378008Y355642D02*
X378217Y355933D01*
X378300Y356267D01*
X378217Y356600D01*
X377967Y356892D01*
X377592Y357100D01*
X377217Y357183D01*
X376758D01*
X376383Y357100D01*
X376050Y356892D01*
X375883Y356642D01*
X375800Y356350D01*
X375883Y356017D01*
X376050Y355767D01*
X376300Y355600D01*
X376633Y355517D01*
X376925Y355600D01*
X377217Y355808D01*
X377383Y356058D01*
X377425Y356350D01*
X377342Y356683D01*
X377133Y356933D01*
X376758Y357183D01*
G01X377258Y358658D02*
X376967Y358950D01*
X376800Y359200D01*
X376717Y359533D01*
X376800Y359825D01*
X376967Y360033D01*
X377217Y360200D01*
X377508Y360242D01*
X377758Y360200D01*
X378008Y360033D01*
X378217Y359783D01*
X378300Y359492D01*
X378217Y359158D01*
X377967Y358867D01*
X377592Y358700D01*
X377175Y358658D01*
X376633Y358742D01*
X376342Y358867D01*
X376050Y359075D01*
X375842Y359367D01*
X375800Y359658D01*
X375883Y359950D01*
X376092Y360158D01*
G01X388456Y344104D02*
X385956D01*
Y345145D01*
X386081Y345479D01*
X386248Y345687D01*
X386581Y345770D01*
X386914Y345687D01*
X387123Y345437D01*
X387248Y345145D01*
Y344104D01*
G01Y345145D02*
X388456Y345770D01*
G01X387956Y347120D02*
X388248Y347370D01*
X388414Y347704D01*
X388456Y348079D01*
X388414Y348412D01*
X388206Y348745D01*
X387956Y348954D01*
X387706Y348995D01*
X387414Y348912D01*
X387206Y348620D01*
X387123Y348329D01*
Y347954D01*
G01Y348329D02*
X386998Y348579D01*
X386789Y348787D01*
X386539Y348870D01*
X386289Y348787D01*
X386081Y348579D01*
X385956Y348204D01*
X385998Y347829D01*
X386164Y347454D01*
G01X387956Y350220D02*
X388248Y350470D01*
X388414Y350804D01*
X388456Y351179D01*
X388414Y351512D01*
X388206Y351845D01*
X387956Y352054D01*
X387706Y352095D01*
X387414Y352012D01*
X387206Y351720D01*
X387123Y351429D01*
Y351054D01*
G01Y351429D02*
X386998Y351679D01*
X386789Y351887D01*
X386539Y351970D01*
X386289Y351887D01*
X386081Y351679D01*
X385956Y351304D01*
X385998Y350929D01*
X386164Y350554D01*
G01X388081Y353320D02*
X388289Y353570D01*
X388414Y353862D01*
X388456Y354237D01*
X388373Y354612D01*
X388206Y354904D01*
X387914Y355112D01*
X387581Y355154D01*
X387248Y355070D01*
X387039Y354862D01*
X386873Y354570D01*
X386831Y354279D01*
X386873Y353987D01*
X387039Y353612D01*
X385956Y353737D01*
Y354862D01*
G01X377934Y336200D02*
X380434D01*
G01X377934Y335242D02*
Y337158D01*
G01X380434Y338467D02*
X377934D01*
Y339467D01*
X378059Y339800D01*
X378351Y340050D01*
X378684Y340133D01*
X379017Y340050D01*
X379267Y339842D01*
X379392Y339467D01*
Y338467D01*
G01X380059Y341483D02*
X380267Y341733D01*
X380392Y342025D01*
X380434Y342400D01*
X380351Y342775D01*
X380184Y343067D01*
X379892Y343275D01*
X379559Y343317D01*
X379226Y343233D01*
X379017Y343025D01*
X378851Y342733D01*
X378809Y342442D01*
X378851Y342150D01*
X379017Y341775D01*
X377934Y341900D01*
Y343025D01*
G01Y345500D02*
X378017Y345167D01*
X378226Y344917D01*
X378476Y344750D01*
X378809Y344625D01*
X379184Y344583D01*
X379559Y344625D01*
X379892Y344750D01*
X380142Y344917D01*
X380351Y345167D01*
X380434Y345500D01*
X380351Y345833D01*
X380142Y346083D01*
X379892Y346250D01*
X379559Y346375D01*
X379184Y346417D01*
X378809Y346375D01*
X378476Y346250D01*
X378226Y346083D01*
X378017Y345833D01*
X377934Y345500D01*
G01X362333Y432817D02*
X361533Y433167D01*
X360600Y433400D01*
X359533D01*
X358333Y433050D01*
X357400Y432467D01*
X356733Y431767D01*
X356200Y430600D01*
X356067Y429550D01*
X356333Y428500D01*
X356733Y427800D01*
X357533Y427100D01*
X358467Y426633D01*
X359400Y426400D01*
X360333D01*
X361267Y426633D01*
X362067Y426983D01*
X362733Y427450D01*
G01X391962Y431947D02*
X389462D01*
Y432988D01*
X389587Y433322D01*
X389754Y433530D01*
X390087Y433613D01*
X390420Y433530D01*
X390629Y433280D01*
X390754Y432988D01*
Y431947D01*
G01Y432988D02*
X391962Y433613D01*
G01X389879Y435088D02*
X389629Y435338D01*
X389504Y435630D01*
X389462Y435963D01*
X389545Y436380D01*
X389754Y436672D01*
X390004Y436755D01*
X390254Y436713D01*
X390462Y436547D01*
X390879Y435713D01*
X391170Y435338D01*
X391587Y435088D01*
X391962Y435005D01*
Y436755D01*
G01Y438980D02*
X391920Y439272D01*
X391795Y439605D01*
X391587Y439813D01*
X391295Y439897D01*
X391004Y439813D01*
X390754Y439563D01*
X390629Y439188D01*
Y438772D01*
X390545Y438522D01*
X390337Y438313D01*
X390045Y438230D01*
X389754Y438355D01*
X389545Y438647D01*
X389462Y438980D01*
X389545Y439313D01*
X389754Y439605D01*
X390045Y439730D01*
X390337Y439647D01*
X390545Y439438D01*
X390629Y439188D01*
Y438772D01*
X390754Y438397D01*
X391004Y438147D01*
X391295Y438063D01*
X391587Y438147D01*
X391795Y438355D01*
X391920Y438688D01*
X391962Y438980D01*
G01Y442080D02*
X391920Y442372D01*
X391795Y442705D01*
X391587Y442913D01*
X391295Y442997D01*
X391004Y442913D01*
X390754Y442663D01*
X390629Y442288D01*
Y441872D01*
X390545Y441622D01*
X390337Y441413D01*
X390045Y441330D01*
X389754Y441455D01*
X389545Y441747D01*
X389462Y442080D01*
X389545Y442413D01*
X389754Y442705D01*
X390045Y442830D01*
X390337Y442747D01*
X390545Y442538D01*
X390629Y442288D01*
Y441872D01*
X390754Y441497D01*
X391004Y441247D01*
X391295Y441163D01*
X391587Y441247D01*
X391795Y441455D01*
X391920Y441788D01*
X391962Y442080D01*
G01X396048Y431881D02*
X393548D01*
Y432922D01*
X393673Y433256D01*
X393840Y433464D01*
X394173Y433547D01*
X394506Y433464D01*
X394715Y433214D01*
X394840Y432922D01*
Y431881D01*
G01Y432922D02*
X396048Y433547D01*
G01X393965Y435022D02*
X393715Y435272D01*
X393590Y435564D01*
X393548Y435897D01*
X393631Y436314D01*
X393840Y436606D01*
X394090Y436689D01*
X394340Y436647D01*
X394548Y436481D01*
X394965Y435647D01*
X395256Y435272D01*
X395673Y435022D01*
X396048Y434939D01*
Y436689D01*
G01Y438914D02*
X396006Y439206D01*
X395881Y439539D01*
X395673Y439747D01*
X395381Y439831D01*
X395090Y439747D01*
X394840Y439497D01*
X394715Y439122D01*
Y438706D01*
X394631Y438456D01*
X394423Y438247D01*
X394131Y438164D01*
X393840Y438289D01*
X393631Y438581D01*
X393548Y438914D01*
X393631Y439247D01*
X393840Y439539D01*
X394131Y439664D01*
X394423Y439581D01*
X394631Y439372D01*
X394715Y439122D01*
Y438706D01*
X394840Y438331D01*
X395090Y438081D01*
X395381Y437997D01*
X395673Y438081D01*
X395881Y438289D01*
X396006Y438622D01*
X396048Y438914D01*
G01X395756Y441306D02*
X395965Y441597D01*
X396048Y441931D01*
X395965Y442264D01*
X395715Y442556D01*
X395340Y442764D01*
X394965Y442847D01*
X394506D01*
X394131Y442764D01*
X393798Y442556D01*
X393631Y442306D01*
X393548Y442014D01*
X393631Y441681D01*
X393798Y441431D01*
X394048Y441264D01*
X394381Y441181D01*
X394673Y441264D01*
X394965Y441472D01*
X395131Y441722D01*
X395173Y442014D01*
X395090Y442347D01*
X394881Y442597D01*
X394506Y442847D01*
G01X400348Y431881D02*
X397848D01*
Y432922D01*
X397973Y433256D01*
X398140Y433464D01*
X398473Y433547D01*
X398806Y433464D01*
X399015Y433214D01*
X399140Y432922D01*
Y431881D01*
G01Y432922D02*
X400348Y433547D01*
G01X398265Y435022D02*
X398015Y435272D01*
X397890Y435564D01*
X397848Y435897D01*
X397931Y436314D01*
X398140Y436606D01*
X398390Y436689D01*
X398640Y436647D01*
X398848Y436481D01*
X399265Y435647D01*
X399556Y435272D01*
X399973Y435022D01*
X400348Y434939D01*
Y436689D01*
G01X400056Y438206D02*
X400265Y438497D01*
X400348Y438831D01*
X400265Y439164D01*
X400015Y439456D01*
X399640Y439664D01*
X399265Y439747D01*
X398806D01*
X398431Y439664D01*
X398098Y439456D01*
X397931Y439206D01*
X397848Y438914D01*
X397931Y438581D01*
X398098Y438331D01*
X398348Y438164D01*
X398681Y438081D01*
X398973Y438164D01*
X399265Y438372D01*
X399431Y438622D01*
X399473Y438914D01*
X399390Y439247D01*
X399181Y439497D01*
X398806Y439747D01*
G01X397848Y442014D02*
X397931Y441681D01*
X398140Y441431D01*
X398390Y441264D01*
X398723Y441139D01*
X399098Y441097D01*
X399473Y441139D01*
X399806Y441264D01*
X400056Y441431D01*
X400265Y441681D01*
X400348Y442014D01*
X400265Y442347D01*
X400056Y442597D01*
X399806Y442764D01*
X399473Y442889D01*
X399098Y442931D01*
X398723Y442889D01*
X398390Y442764D01*
X398140Y442597D01*
X397931Y442347D01*
X397848Y442014D01*
G01X372217Y433466D02*
Y435966D01*
X373258D01*
X373592Y435841D01*
X373800Y435674D01*
X373883Y435341D01*
X373800Y435008D01*
X373550Y434799D01*
X373258Y434674D01*
X372217D01*
G01X373258D02*
X373883Y433466D01*
G01X376150D02*
Y435966D01*
X375650Y435466D01*
G01Y433466D02*
X376650D01*
G01X379750D02*
Y435966D01*
X378208Y434174D01*
X380292D01*
G01X381558Y434508D02*
X381850Y434799D01*
X382100Y434966D01*
X382433Y435049D01*
X382725Y434966D01*
X382933Y434799D01*
X383100Y434549D01*
X383142Y434258D01*
X383100Y434008D01*
X382933Y433758D01*
X382683Y433549D01*
X382392Y433466D01*
X382058Y433549D01*
X381767Y433799D01*
X381600Y434174D01*
X381558Y434591D01*
X381642Y435133D01*
X381767Y435424D01*
X381975Y435716D01*
X382267Y435924D01*
X382558Y435966D01*
X382850Y435883D01*
X383058Y435674D01*
G01X370533Y432117D02*
X368033D01*
Y433158D01*
X368158Y433492D01*
X368325Y433700D01*
X368658Y433783D01*
X368991Y433700D01*
X369200Y433450D01*
X369325Y433158D01*
Y432117D01*
G01Y433158D02*
X370533Y433783D01*
G01Y436050D02*
X368033D01*
X368533Y435550D01*
G01X370533D02*
Y436550D01*
G01Y439650D02*
X368033D01*
X369825Y438108D01*
Y440192D01*
G01X370533Y442167D02*
X369991Y442250D01*
X369533Y442375D01*
X369116Y442542D01*
X368658Y442750D01*
X368033Y443083D01*
Y441417D01*
G01X353033Y434617D02*
X350533D01*
Y435658D01*
X350658Y435992D01*
X350825Y436200D01*
X351158Y436283D01*
X351491Y436200D01*
X351700Y435950D01*
X351825Y435658D01*
Y434617D01*
G01Y435658D02*
X353033Y436283D01*
G01Y438550D02*
X350533D01*
X351033Y438050D01*
G01X353033D02*
Y439050D01*
G01Y442150D02*
X350533D01*
X352325Y440608D01*
Y442692D01*
G01X353033Y444750D02*
X352991Y445042D01*
X352866Y445375D01*
X352658Y445583D01*
X352366Y445667D01*
X352075Y445583D01*
X351825Y445333D01*
X351700Y444958D01*
Y444542D01*
X351616Y444292D01*
X351408Y444083D01*
X351116Y444000D01*
X350825Y444125D01*
X350616Y444417D01*
X350533Y444750D01*
X350616Y445083D01*
X350825Y445375D01*
X351116Y445500D01*
X351408Y445417D01*
X351616Y445208D01*
X351700Y444958D01*
Y444542D01*
X351825Y444167D01*
X352075Y443917D01*
X352366Y443833D01*
X352658Y443917D01*
X352866Y444125D01*
X352991Y444458D01*
X353033Y444750D01*
G01X349384Y434666D02*
X346884D01*
Y435707D01*
X347009Y436041D01*
X347176Y436249D01*
X347509Y436332D01*
X347842Y436249D01*
X348051Y435999D01*
X348176Y435707D01*
Y434666D01*
G01Y435707D02*
X349384Y436332D01*
G01Y438599D02*
X346884D01*
X347384Y438099D01*
G01X349384D02*
Y439099D01*
G01Y442199D02*
X346884D01*
X348676Y440657D01*
Y442741D01*
G01X349092Y444091D02*
X349301Y444382D01*
X349384Y444716D01*
X349301Y445049D01*
X349051Y445341D01*
X348676Y445549D01*
X348301Y445632D01*
X347842D01*
X347467Y445549D01*
X347134Y445341D01*
X346967Y445091D01*
X346884Y444799D01*
X346967Y444466D01*
X347134Y444216D01*
X347384Y444049D01*
X347717Y443966D01*
X348009Y444049D01*
X348301Y444257D01*
X348467Y444507D01*
X348509Y444799D01*
X348426Y445132D01*
X348217Y445382D01*
X347842Y445632D01*
G01X345533Y434717D02*
X343033D01*
Y435758D01*
X343158Y436092D01*
X343325Y436300D01*
X343658Y436383D01*
X343991Y436300D01*
X344200Y436050D01*
X344325Y435758D01*
Y434717D01*
G01Y435758D02*
X345533Y436383D01*
G01Y438650D02*
X343033D01*
X343533Y438150D01*
G01X345533D02*
Y439150D01*
G01Y441667D02*
X344991Y441750D01*
X344533Y441875D01*
X344116Y442042D01*
X343658Y442250D01*
X343033Y442583D01*
Y440917D01*
G01X345533Y444850D02*
X345491Y445142D01*
X345366Y445475D01*
X345158Y445683D01*
X344866Y445767D01*
X344575Y445683D01*
X344325Y445433D01*
X344200Y445058D01*
Y444642D01*
X344116Y444392D01*
X343908Y444183D01*
X343616Y444100D01*
X343325Y444225D01*
X343116Y444517D01*
X343033Y444850D01*
X343116Y445183D01*
X343325Y445475D01*
X343616Y445600D01*
X343908Y445517D01*
X344116Y445308D01*
X344200Y445058D01*
Y444642D01*
X344325Y444267D01*
X344575Y444017D01*
X344866Y443933D01*
X345158Y444017D01*
X345366Y444225D01*
X345491Y444558D01*
X345533Y444850D01*
G01X404400Y431887D02*
X401900D01*
Y432928D01*
X402025Y433262D01*
X402192Y433470D01*
X402525Y433553D01*
X402858Y433470D01*
X403067Y433220D01*
X403192Y432928D01*
Y431887D01*
G01Y432928D02*
X404400Y433553D01*
G01Y435737D02*
X403858Y435820D01*
X403400Y435945D01*
X402983Y436112D01*
X402525Y436320D01*
X401900Y436653D01*
Y434987D01*
G01Y438920D02*
X401983Y438587D01*
X402192Y438337D01*
X402442Y438170D01*
X402775Y438045D01*
X403150Y438003D01*
X403525Y438045D01*
X403858Y438170D01*
X404108Y438337D01*
X404317Y438587D01*
X404400Y438920D01*
X404317Y439253D01*
X404108Y439503D01*
X403858Y439670D01*
X403525Y439795D01*
X403150Y439837D01*
X402775Y439795D01*
X402442Y439670D01*
X402192Y439503D01*
X401983Y439253D01*
X401900Y438920D01*
G01X404400Y442020D02*
X404358Y442312D01*
X404233Y442645D01*
X404025Y442853D01*
X403733Y442937D01*
X403442Y442853D01*
X403192Y442603D01*
X403067Y442228D01*
Y441812D01*
X402983Y441562D01*
X402775Y441353D01*
X402483Y441270D01*
X402192Y441395D01*
X401983Y441687D01*
X401900Y442020D01*
X401983Y442353D01*
X402192Y442645D01*
X402483Y442770D01*
X402775Y442687D01*
X402983Y442478D01*
X403067Y442228D01*
Y441812D01*
X403192Y441437D01*
X403442Y441187D01*
X403733Y441103D01*
X404025Y441187D01*
X404233Y441395D01*
X404358Y441728D01*
X404400Y442020D01*
G01X387300Y432047D02*
X384800D01*
Y433088D01*
X384925Y433422D01*
X385092Y433630D01*
X385425Y433713D01*
X385758Y433630D01*
X385967Y433380D01*
X386092Y433088D01*
Y432047D01*
G01Y433088D02*
X387300Y433713D01*
G01X385217Y435188D02*
X384967Y435438D01*
X384842Y435730D01*
X384800Y436063D01*
X384883Y436480D01*
X385092Y436772D01*
X385342Y436855D01*
X385592Y436813D01*
X385800Y436647D01*
X386217Y435813D01*
X386508Y435438D01*
X386925Y435188D01*
X387300Y435105D01*
Y436855D01*
G01Y438997D02*
X386758Y439080D01*
X386300Y439205D01*
X385883Y439372D01*
X385425Y439580D01*
X384800Y439913D01*
Y438247D01*
G01X387300Y442180D02*
X387258Y442472D01*
X387133Y442805D01*
X386925Y443013D01*
X386633Y443097D01*
X386342Y443013D01*
X386092Y442763D01*
X385967Y442388D01*
Y441972D01*
X385883Y441722D01*
X385675Y441513D01*
X385383Y441430D01*
X385092Y441555D01*
X384883Y441847D01*
X384800Y442180D01*
X384883Y442513D01*
X385092Y442805D01*
X385383Y442930D01*
X385675Y442847D01*
X385883Y442638D01*
X385967Y442388D01*
Y441972D01*
X386092Y441597D01*
X386342Y441347D01*
X386633Y441263D01*
X386925Y441347D01*
X387133Y441555D01*
X387258Y441888D01*
X387300Y442180D01*
G01X356150Y442467D02*
Y439967D01*
G01X355192Y442467D02*
X357108D01*
G01X358417Y439967D02*
Y442467D01*
X359417D01*
X359750Y442342D01*
X360000Y442050D01*
X360083Y441717D01*
X360000Y441384D01*
X359792Y441134D01*
X359417Y441009D01*
X358417D01*
G01X362350Y439967D02*
Y442467D01*
X361850Y441967D01*
G01Y439967D02*
X362850D01*
G01X365450Y442467D02*
X365117Y442384D01*
X364867Y442175D01*
X364700Y441925D01*
X364575Y441592D01*
X364533Y441217D01*
X364575Y440842D01*
X364700Y440509D01*
X364867Y440259D01*
X365117Y440050D01*
X365450Y439967D01*
X365783Y440050D01*
X366033Y440259D01*
X366200Y440509D01*
X366325Y440842D01*
X366367Y441217D01*
X366325Y441592D01*
X366200Y441925D01*
X366033Y442175D01*
X365783Y442384D01*
X365450Y442467D01*
G01X373550Y442267D02*
Y439767D01*
G01X372592Y442267D02*
X374508D01*
G01X375817Y439767D02*
Y442267D01*
X376817D01*
X377150Y442142D01*
X377400Y441850D01*
X377483Y441517D01*
X377400Y441184D01*
X377192Y440934D01*
X376817Y440809D01*
X375817D01*
G01X379750Y439767D02*
Y442267D01*
X379250Y441767D01*
G01Y439767D02*
X380250D01*
G01X382850D02*
Y442267D01*
X382350Y441767D01*
G01Y439767D02*
X383350D01*
G01X356150Y437667D02*
Y435167D01*
G01X355192Y437667D02*
X357108D01*
G01X358417Y435167D02*
Y437667D01*
X359417D01*
X359750Y437542D01*
X360000Y437250D01*
X360083Y436917D01*
X360000Y436584D01*
X359792Y436334D01*
X359417Y436209D01*
X358417D01*
G01X362350Y435167D02*
Y437667D01*
X361850Y437167D01*
G01Y435167D02*
X362850D01*
G01X364658Y437250D02*
X364908Y437500D01*
X365200Y437625D01*
X365533Y437667D01*
X365950Y437584D01*
X366242Y437375D01*
X366325Y437125D01*
X366283Y436875D01*
X366117Y436667D01*
X365283Y436250D01*
X364908Y435959D01*
X364658Y435542D01*
X364575Y435167D01*
X366325D01*
G01X384800Y446417D02*
Y443917D01*
G01X383842Y446417D02*
X385758D01*
G01X387067Y443917D02*
Y446417D01*
X388067D01*
X388400Y446292D01*
X388650Y446000D01*
X388733Y445667D01*
X388650Y445334D01*
X388442Y445084D01*
X388067Y444959D01*
X387067D01*
G01X391000Y443917D02*
Y446417D01*
X390500Y445917D01*
G01Y443917D02*
X391500D01*
G01X393392Y444209D02*
X393683Y444000D01*
X394017Y443917D01*
X394350Y444000D01*
X394642Y444250D01*
X394850Y444625D01*
X394933Y445000D01*
Y445459D01*
X394850Y445834D01*
X394642Y446167D01*
X394392Y446334D01*
X394100Y446417D01*
X393767Y446334D01*
X393517Y446167D01*
X393350Y445917D01*
X393267Y445584D01*
X393350Y445292D01*
X393558Y445000D01*
X393808Y444834D01*
X394100Y444792D01*
X394433Y444875D01*
X394683Y445084D01*
X394933Y445459D01*
G01X396283Y444417D02*
X396533Y444125D01*
X396867Y443959D01*
X397242Y443917D01*
X397575Y443959D01*
X397908Y444167D01*
X398117Y444417D01*
X398158Y444667D01*
X398075Y444959D01*
X397783Y445167D01*
X397492Y445250D01*
X397117D01*
G01X397492D02*
X397742Y445375D01*
X397950Y445584D01*
X398033Y445834D01*
X397950Y446084D01*
X397742Y446292D01*
X397367Y446417D01*
X396992Y446375D01*
X396617Y446209D01*
G01X347467Y495592D02*
X347217Y495717D01*
X346925Y495800D01*
X346592D01*
X346217Y495675D01*
X345925Y495467D01*
X345717Y495217D01*
X345550Y494800D01*
X345508Y494425D01*
X345592Y494050D01*
X345717Y493800D01*
X345967Y493550D01*
X346258Y493383D01*
X346550Y493300D01*
X346842D01*
X347133Y493383D01*
X347383Y493508D01*
X347592Y493675D01*
G01X348733D02*
X348983Y493467D01*
X349275Y493342D01*
X349650Y493300D01*
X350025Y493383D01*
X350317Y493550D01*
X350525Y493842D01*
X350567Y494175D01*
X350483Y494508D01*
X350275Y494717D01*
X349983Y494883D01*
X349692Y494925D01*
X349400Y494883D01*
X349025Y494717D01*
X349150Y495800D01*
X350275D01*
G01X351958Y495383D02*
X352208Y495633D01*
X352500Y495758D01*
X352833Y495800D01*
X353250Y495717D01*
X353542Y495508D01*
X353625Y495258D01*
X353583Y495008D01*
X353417Y494800D01*
X352583Y494383D01*
X352208Y494092D01*
X351958Y493675D01*
X351875Y493300D01*
X353625D01*
G01X355058Y495383D02*
X355308Y495633D01*
X355600Y495758D01*
X355933Y495800D01*
X356350Y495717D01*
X356642Y495508D01*
X356725Y495258D01*
X356683Y495008D01*
X356517Y494800D01*
X355683Y494383D01*
X355308Y494092D01*
X355058Y493675D01*
X354975Y493300D01*
X356725D01*
G01X382917Y511100D02*
Y513600D01*
X383958D01*
X384292Y513475D01*
X384500Y513308D01*
X384583Y512975D01*
X384500Y512642D01*
X384250Y512433D01*
X383958Y512308D01*
X382917D01*
G01X383958D02*
X384583Y511100D01*
G01X386850D02*
Y513600D01*
X386350Y513100D01*
G01Y511100D02*
X387350D01*
G01X389033Y511600D02*
X389283Y511308D01*
X389617Y511142D01*
X389992Y511100D01*
X390325Y511142D01*
X390658Y511350D01*
X390867Y511600D01*
X390908Y511850D01*
X390825Y512142D01*
X390533Y512350D01*
X390242Y512433D01*
X389867D01*
G01X390242D02*
X390492Y512558D01*
X390700Y512767D01*
X390783Y513017D01*
X390700Y513267D01*
X390492Y513475D01*
X390117Y513600D01*
X389742Y513558D01*
X389367Y513392D01*
G01X392133Y511475D02*
X392383Y511267D01*
X392675Y511142D01*
X393050Y511100D01*
X393425Y511183D01*
X393717Y511350D01*
X393925Y511642D01*
X393967Y511975D01*
X393883Y512308D01*
X393675Y512517D01*
X393383Y512683D01*
X393092Y512725D01*
X392800Y512683D01*
X392425Y512517D01*
X392550Y513600D01*
X393675D01*
G01X386490Y524801D02*
Y527301D01*
X387531D01*
X387865Y527176D01*
X388073Y527009D01*
X388156Y526676D01*
X388073Y526343D01*
X387823Y526134D01*
X387531Y526009D01*
X386490D01*
G01X387531D02*
X388156Y524801D01*
G01X390423D02*
Y527301D01*
X389923Y526801D01*
G01Y524801D02*
X390923D01*
G01X392606Y525301D02*
X392856Y525009D01*
X393190Y524843D01*
X393565Y524801D01*
X393898Y524843D01*
X394231Y525051D01*
X394440Y525301D01*
X394481Y525551D01*
X394398Y525843D01*
X394106Y526051D01*
X393815Y526134D01*
X393440D01*
G01X393815D02*
X394065Y526259D01*
X394273Y526468D01*
X394356Y526718D01*
X394273Y526968D01*
X394065Y527176D01*
X393690Y527301D01*
X393315Y527259D01*
X392940Y527093D01*
G01X396540Y524801D02*
X396623Y525343D01*
X396748Y525801D01*
X396915Y526218D01*
X397123Y526676D01*
X397456Y527301D01*
X395790D01*
G01X352000Y534400D02*
X348000D01*
Y527000D01*
G01X386616Y520371D02*
Y522871D01*
X387657D01*
X387991Y522746D01*
X388199Y522579D01*
X388282Y522246D01*
X388199Y521913D01*
X387949Y521704D01*
X387657Y521579D01*
X386616D01*
G01X387657D02*
X388282Y520371D01*
G01X390549D02*
Y522871D01*
X390049Y522371D01*
G01Y520371D02*
X391049D01*
G01X392732Y520871D02*
X392982Y520579D01*
X393316Y520413D01*
X393691Y520371D01*
X394024Y520413D01*
X394357Y520621D01*
X394566Y520871D01*
X394607Y521121D01*
X394524Y521413D01*
X394232Y521621D01*
X393941Y521704D01*
X393566D01*
G01X393941D02*
X394191Y521829D01*
X394399Y522038D01*
X394482Y522288D01*
X394399Y522538D01*
X394191Y522746D01*
X393816Y522871D01*
X393441Y522829D01*
X393066Y522663D01*
G01X396749Y520371D02*
X397041Y520413D01*
X397374Y520538D01*
X397582Y520746D01*
X397666Y521038D01*
X397582Y521329D01*
X397332Y521579D01*
X396957Y521704D01*
X396541D01*
X396291Y521788D01*
X396082Y521996D01*
X395999Y522288D01*
X396124Y522579D01*
X396416Y522788D01*
X396749Y522871D01*
X397082Y522788D01*
X397374Y522579D01*
X397499Y522288D01*
X397416Y521996D01*
X397207Y521788D01*
X396957Y521704D01*
X396541D01*
X396166Y521579D01*
X395916Y521329D01*
X395832Y521038D01*
X395916Y520746D01*
X396124Y520538D01*
X396457Y520413D01*
X396749Y520371D01*
G01X352000Y526400D02*
X348000D01*
Y519000D01*
G01X383517Y499900D02*
Y502400D01*
X384558D01*
X384892Y502275D01*
X385100Y502108D01*
X385183Y501775D01*
X385100Y501442D01*
X384850Y501233D01*
X384558Y501108D01*
X383517D01*
G01X384558D02*
X385183Y499900D01*
G01X387950D02*
Y502400D01*
X386408Y500608D01*
X388492D01*
G01X389758Y501983D02*
X390008Y502233D01*
X390300Y502358D01*
X390633Y502400D01*
X391050Y502317D01*
X391342Y502108D01*
X391425Y501858D01*
X391383Y501608D01*
X391217Y501400D01*
X390383Y500983D01*
X390008Y500692D01*
X389758Y500275D01*
X389675Y499900D01*
X391425D01*
G01X393650Y502400D02*
X393317Y502317D01*
X393067Y502108D01*
X392900Y501858D01*
X392775Y501525D01*
X392733Y501150D01*
X392775Y500775D01*
X392900Y500442D01*
X393067Y500192D01*
X393317Y499983D01*
X393650Y499900D01*
X393983Y499983D01*
X394233Y500192D01*
X394400Y500442D01*
X394525Y500775D01*
X394567Y501150D01*
X394525Y501525D01*
X394400Y501858D01*
X394233Y502108D01*
X393983Y502317D01*
X393650Y502400D01*
G01X345861Y509831D02*
Y505831D01*
X353261D01*
G01X383517Y503600D02*
Y506100D01*
X384558D01*
X384892Y505975D01*
X385100Y505808D01*
X385183Y505475D01*
X385100Y505142D01*
X384850Y504933D01*
X384558Y504808D01*
X383517D01*
G01X384558D02*
X385183Y503600D01*
G01X387950D02*
Y506100D01*
X386408Y504308D01*
X388492D01*
G01X389758Y505683D02*
X390008Y505933D01*
X390300Y506058D01*
X390633Y506100D01*
X391050Y506017D01*
X391342Y505808D01*
X391425Y505558D01*
X391383Y505308D01*
X391217Y505100D01*
X390383Y504683D01*
X390008Y504392D01*
X389758Y503975D01*
X389675Y503600D01*
X391425D01*
G01X393650D02*
Y506100D01*
X393150Y505600D01*
G01Y503600D02*
X394150D01*
G01X353200Y509900D02*
Y513900D01*
X345800D01*
G01X355417Y498700D02*
Y501200D01*
X356458D01*
X356792Y501075D01*
X357000Y500908D01*
X357083Y500575D01*
X357000Y500242D01*
X356750Y500033D01*
X356458Y499908D01*
X355417D01*
G01X356458D02*
X357083Y498700D01*
G01X359267D02*
X359350Y499242D01*
X359475Y499700D01*
X359642Y500117D01*
X359850Y500575D01*
X360183Y501200D01*
X358517D01*
G01X362450Y498700D02*
Y501200D01*
X361950Y500700D01*
G01Y498700D02*
X362950D01*
G01X364633Y499075D02*
X364883Y498867D01*
X365175Y498742D01*
X365550Y498700D01*
X365925Y498783D01*
X366217Y498950D01*
X366425Y499242D01*
X366467Y499575D01*
X366383Y499908D01*
X366175Y500117D01*
X365883Y500283D01*
X365592Y500325D01*
X365300Y500283D01*
X364925Y500117D01*
X365050Y501200D01*
X366175D01*
G01X353200Y501600D02*
Y505600D01*
X345800D01*
G01X369687Y466179D02*
X367187D01*
Y467220D01*
X367312Y467554D01*
X367479Y467762D01*
X367812Y467845D01*
X368145Y467762D01*
X368354Y467512D01*
X368479Y467220D01*
Y466179D01*
G01Y467220D02*
X369687Y467845D01*
G01Y470029D02*
X369145Y470112D01*
X368687Y470237D01*
X368270Y470404D01*
X367812Y470612D01*
X367187Y470945D01*
Y469279D01*
G01X369395Y472504D02*
X369604Y472795D01*
X369687Y473129D01*
X369604Y473462D01*
X369354Y473754D01*
X368979Y473962D01*
X368604Y474045D01*
X368145D01*
X367770Y473962D01*
X367437Y473754D01*
X367270Y473504D01*
X367187Y473212D01*
X367270Y472879D01*
X367437Y472629D01*
X367687Y472462D01*
X368020Y472379D01*
X368312Y472462D01*
X368604Y472670D01*
X368770Y472920D01*
X368812Y473212D01*
X368729Y473545D01*
X368520Y473795D01*
X368145Y474045D01*
G01X369687Y476229D02*
X369145Y476312D01*
X368687Y476437D01*
X368270Y476604D01*
X367812Y476812D01*
X367187Y477145D01*
Y475479D01*
G01X361553Y474262D02*
X365553D01*
Y481662D01*
G01X346357Y474926D02*
Y477426D01*
X347398D01*
X347732Y477301D01*
X347940Y477134D01*
X348023Y476801D01*
X347940Y476468D01*
X347690Y476259D01*
X347398Y476134D01*
X346357D01*
G01X347398D02*
X348023Y474926D01*
G01X350207D02*
X350290Y475468D01*
X350415Y475926D01*
X350582Y476343D01*
X350790Y476801D01*
X351123Y477426D01*
X349457D01*
G01X352682Y475218D02*
X352973Y475009D01*
X353307Y474926D01*
X353640Y475009D01*
X353932Y475259D01*
X354140Y475634D01*
X354223Y476009D01*
Y476468D01*
X354140Y476843D01*
X353932Y477176D01*
X353682Y477343D01*
X353390Y477426D01*
X353057Y477343D01*
X352807Y477176D01*
X352640Y476926D01*
X352557Y476593D01*
X352640Y476301D01*
X352848Y476009D01*
X353098Y475843D01*
X353390Y475801D01*
X353723Y475884D01*
X353973Y476093D01*
X354223Y476468D01*
G01X355698Y475968D02*
X355990Y476259D01*
X356240Y476426D01*
X356573Y476509D01*
X356865Y476426D01*
X357073Y476259D01*
X357240Y476009D01*
X357282Y475718D01*
X357240Y475468D01*
X357073Y475218D01*
X356823Y475009D01*
X356532Y474926D01*
X356198Y475009D01*
X355907Y475259D01*
X355740Y475634D01*
X355698Y476051D01*
X355782Y476593D01*
X355907Y476884D01*
X356115Y477176D01*
X356407Y477384D01*
X356698Y477426D01*
X356990Y477343D01*
X357198Y477134D01*
G01X352630Y483570D02*
Y479570D01*
X360030D01*
G01X350400Y479917D02*
X347900D01*
Y480958D01*
X348025Y481292D01*
X348192Y481500D01*
X348525Y481583D01*
X348858Y481500D01*
X349067Y481250D01*
X349192Y480958D01*
Y479917D01*
G01Y480958D02*
X350400Y481583D01*
G01Y483767D02*
X349858Y483850D01*
X349400Y483975D01*
X348983Y484142D01*
X348525Y484350D01*
X347900Y484683D01*
Y483017D01*
G01X348317Y486158D02*
X348067Y486408D01*
X347942Y486700D01*
X347900Y487033D01*
X347983Y487450D01*
X348192Y487742D01*
X348442Y487825D01*
X348692Y487783D01*
X348900Y487617D01*
X349317Y486783D01*
X349608Y486408D01*
X350025Y486158D01*
X350400Y486075D01*
Y487825D01*
G01X350025Y489133D02*
X350233Y489383D01*
X350358Y489675D01*
X350400Y490050D01*
X350317Y490425D01*
X350150Y490717D01*
X349858Y490925D01*
X349525Y490967D01*
X349192Y490883D01*
X348983Y490675D01*
X348817Y490383D01*
X348775Y490092D01*
X348817Y489800D01*
X348983Y489425D01*
X347900Y489550D01*
Y490675D01*
G01X356440Y491230D02*
X352440D01*
Y483830D01*
G01X398795Y520289D02*
X400587D01*
X400962Y520456D01*
X401212Y520789D01*
X401295Y521206D01*
X401212Y521623D01*
X400962Y521956D01*
X400587Y522123D01*
X398795D01*
G01X399212Y523514D02*
X398962Y523764D01*
X398837Y524056D01*
X398795Y524389D01*
X398878Y524806D01*
X399087Y525098D01*
X399337Y525181D01*
X399587Y525139D01*
X399795Y524973D01*
X400212Y524139D01*
X400503Y523764D01*
X400920Y523514D01*
X401295Y523431D01*
Y525181D01*
G01X400253Y526614D02*
X399962Y526906D01*
X399795Y527156D01*
X399712Y527489D01*
X399795Y527781D01*
X399962Y527989D01*
X400212Y528156D01*
X400503Y528198D01*
X400753Y528156D01*
X401003Y527989D01*
X401212Y527739D01*
X401295Y527448D01*
X401212Y527114D01*
X400962Y526823D01*
X400587Y526656D01*
X400170Y526614D01*
X399628Y526698D01*
X399337Y526823D01*
X399045Y527031D01*
X398837Y527323D01*
X398795Y527614D01*
X398878Y527906D01*
X399087Y528114D01*
G01X363488Y539981D02*
Y520781D01*
X374688D01*
Y539981D01*
X363488D01*
Y539581D01*
G01X375583Y489566D02*
Y487774D01*
X375750Y487399D01*
X376083Y487149D01*
X376500Y487066D01*
X376917Y487149D01*
X377250Y487399D01*
X377417Y487774D01*
Y489566D01*
G01X380100Y487066D02*
Y489566D01*
X378558Y487774D01*
X380642D01*
G01X381908Y488108D02*
X382200Y488399D01*
X382450Y488566D01*
X382783Y488649D01*
X383075Y488566D01*
X383283Y488399D01*
X383450Y488149D01*
X383492Y487858D01*
X383450Y487608D01*
X383283Y487358D01*
X383033Y487149D01*
X382742Y487066D01*
X382408Y487149D01*
X382117Y487399D01*
X381950Y487774D01*
X381908Y488191D01*
X381992Y488733D01*
X382117Y489024D01*
X382325Y489316D01*
X382617Y489524D01*
X382908Y489566D01*
X383200Y489483D01*
X383408Y489274D01*
G01X373900Y497000D02*
Y483600D01*
G01X363900Y497000D02*
X373900D01*
G01X363900Y483600D02*
Y497000D01*
G01X373900Y483600D02*
X363900D01*
G01X396700Y504283D02*
X398492D01*
X398867Y504450D01*
X399117Y504783D01*
X399200Y505200D01*
X399117Y505617D01*
X398867Y505950D01*
X398492Y506117D01*
X396700D01*
G01X398700Y507383D02*
X398992Y507633D01*
X399158Y507967D01*
X399200Y508342D01*
X399158Y508675D01*
X398950Y509008D01*
X398700Y509217D01*
X398450Y509258D01*
X398158Y509175D01*
X397950Y508883D01*
X397867Y508592D01*
Y508217D01*
G01Y508592D02*
X397742Y508842D01*
X397533Y509050D01*
X397283Y509133D01*
X397033Y509050D01*
X396825Y508842D01*
X396700Y508467D01*
X396742Y508092D01*
X396908Y507717D01*
G01X398700Y510483D02*
X398992Y510733D01*
X399158Y511067D01*
X399200Y511442D01*
X399158Y511775D01*
X398950Y512108D01*
X398700Y512317D01*
X398450Y512358D01*
X398158Y512275D01*
X397950Y511983D01*
X397867Y511692D01*
Y511317D01*
G01Y511692D02*
X397742Y511942D01*
X397533Y512150D01*
X397283Y512233D01*
X397033Y512150D01*
X396825Y511942D01*
X396700Y511567D01*
X396742Y511192D01*
X396908Y510817D01*
G01X365589Y517769D02*
X373589D01*
Y505369D01*
X365589D01*
Y517769D01*
G01X369589Y516069D02*
X371089Y517569D01*
G01X369589Y516069D02*
X368089Y517569D01*
G01X390001Y545961D02*
X389751Y546086D01*
X389459Y546169D01*
X389126D01*
X388751Y546044D01*
X388459Y545836D01*
X388251Y545586D01*
X388084Y545169D01*
X388042Y544794D01*
X388126Y544419D01*
X388251Y544169D01*
X388501Y543919D01*
X388792Y543752D01*
X389084Y543669D01*
X389376D01*
X389667Y543752D01*
X389917Y543877D01*
X390126Y544044D01*
G01X391267D02*
X391517Y543836D01*
X391809Y543711D01*
X392184Y543669D01*
X392559Y543752D01*
X392851Y543919D01*
X393059Y544211D01*
X393101Y544544D01*
X393017Y544877D01*
X392809Y545086D01*
X392517Y545252D01*
X392226Y545294D01*
X391934Y545252D01*
X391559Y545086D01*
X391684Y546169D01*
X392809D01*
G01X395284Y543669D02*
Y546169D01*
X394784Y545669D01*
G01Y543669D02*
X395784D01*
G01X406100Y578667D02*
X403600D01*
Y579708D01*
X403725Y580042D01*
X403892Y580250D01*
X404225Y580333D01*
X404558Y580250D01*
X404767Y580000D01*
X404892Y579708D01*
Y578667D01*
G01Y579708D02*
X406100Y580333D01*
G01X404017Y581808D02*
X403767Y582058D01*
X403642Y582350D01*
X403600Y582683D01*
X403683Y583100D01*
X403892Y583392D01*
X404142Y583475D01*
X404392Y583433D01*
X404600Y583267D01*
X405017Y582433D01*
X405308Y582058D01*
X405725Y581808D01*
X406100Y581725D01*
Y583475D01*
G01X405808Y584992D02*
X406017Y585283D01*
X406100Y585617D01*
X406017Y585950D01*
X405767Y586242D01*
X405392Y586450D01*
X405017Y586533D01*
X404558D01*
X404183Y586450D01*
X403850Y586242D01*
X403683Y585992D01*
X403600Y585700D01*
X403683Y585367D01*
X403850Y585117D01*
X404100Y584950D01*
X404433Y584867D01*
X404725Y584950D01*
X405017Y585158D01*
X405183Y585408D01*
X405225Y585700D01*
X405142Y586033D01*
X404933Y586283D01*
X404558Y586533D01*
G01X380550Y579406D02*
X384550D01*
Y586806D01*
G01X394133Y599890D02*
X390133D01*
Y592490D01*
G01X385733Y592590D02*
X389733D01*
Y599990D01*
G01X350000Y585467D02*
X347500D01*
Y586508D01*
X347625Y586842D01*
X347792Y587050D01*
X348125Y587133D01*
X348458Y587050D01*
X348667Y586800D01*
X348792Y586508D01*
Y585467D01*
G01Y586508D02*
X350000Y587133D01*
G01X347917Y588608D02*
X347667Y588858D01*
X347542Y589150D01*
X347500Y589483D01*
X347583Y589900D01*
X347792Y590192D01*
X348042Y590275D01*
X348292Y590233D01*
X348500Y590067D01*
X348917Y589233D01*
X349208Y588858D01*
X349625Y588608D01*
X350000Y588525D01*
Y590275D01*
G01Y593000D02*
X347500D01*
X349292Y591458D01*
Y593542D01*
G01X358820Y584836D02*
X362820D01*
Y592236D01*
G01X346500Y585467D02*
X344000D01*
Y586508D01*
X344125Y586842D01*
X344292Y587050D01*
X344625Y587133D01*
X344958Y587050D01*
X345167Y586800D01*
X345292Y586508D01*
Y585467D01*
G01Y586508D02*
X346500Y587133D01*
G01X344417Y588608D02*
X344167Y588858D01*
X344042Y589150D01*
X344000Y589483D01*
X344083Y589900D01*
X344292Y590192D01*
X344542Y590275D01*
X344792Y590233D01*
X345000Y590067D01*
X345417Y589233D01*
X345708Y588858D01*
X346125Y588608D01*
X346500Y588525D01*
Y590275D01*
G01X346125Y591583D02*
X346333Y591833D01*
X346458Y592125D01*
X346500Y592500D01*
X346417Y592875D01*
X346250Y593167D01*
X345958Y593375D01*
X345625Y593417D01*
X345292Y593333D01*
X345083Y593125D01*
X344917Y592833D01*
X344875Y592542D01*
X344917Y592250D01*
X345083Y591875D01*
X344000Y592000D01*
Y593125D01*
G01X358680Y591064D02*
X354680D01*
Y583664D01*
G01X395967Y592800D02*
Y595300D01*
X397008D01*
X397342Y595175D01*
X397550Y595008D01*
X397633Y594675D01*
X397550Y594342D01*
X397300Y594133D01*
X397008Y594008D01*
X395967D01*
G01X397008D02*
X397633Y592800D01*
G01X398983Y593300D02*
X399233Y593008D01*
X399567Y592842D01*
X399942Y592800D01*
X400275Y592842D01*
X400608Y593050D01*
X400817Y593300D01*
X400858Y593550D01*
X400775Y593842D01*
X400483Y594050D01*
X400192Y594133D01*
X399817D01*
G01X400192D02*
X400442Y594258D01*
X400650Y594467D01*
X400733Y594717D01*
X400650Y594967D01*
X400442Y595175D01*
X400067Y595300D01*
X399692Y595258D01*
X399317Y595092D01*
G01X403000Y595300D02*
X402667Y595217D01*
X402417Y595008D01*
X402250Y594758D01*
X402125Y594425D01*
X402083Y594050D01*
X402125Y593675D01*
X402250Y593342D01*
X402417Y593092D01*
X402667Y592883D01*
X403000Y592800D01*
X403333Y592883D01*
X403583Y593092D01*
X403750Y593342D01*
X403875Y593675D01*
X403917Y594050D01*
X403875Y594425D01*
X403750Y594758D01*
X403583Y595008D01*
X403333Y595217D01*
X403000Y595300D01*
G01X393000Y587571D02*
Y591571D01*
X385600D01*
G01X342900Y585567D02*
X340400D01*
Y586608D01*
X340525Y586942D01*
X340692Y587150D01*
X341025Y587233D01*
X341358Y587150D01*
X341567Y586900D01*
X341692Y586608D01*
Y585567D01*
G01Y586608D02*
X342900Y587233D01*
G01X342400Y588583D02*
X342692Y588833D01*
X342858Y589167D01*
X342900Y589542D01*
X342858Y589875D01*
X342650Y590208D01*
X342400Y590417D01*
X342150Y590458D01*
X341858Y590375D01*
X341650Y590083D01*
X341567Y589792D01*
Y589417D01*
G01Y589792D02*
X341442Y590042D01*
X341233Y590250D01*
X340983Y590333D01*
X340733Y590250D01*
X340525Y590042D01*
X340400Y589667D01*
X340442Y589292D01*
X340608Y588917D01*
G01X342400Y591683D02*
X342692Y591933D01*
X342858Y592267D01*
X342900Y592642D01*
X342858Y592975D01*
X342650Y593308D01*
X342400Y593517D01*
X342150Y593558D01*
X341858Y593475D01*
X341650Y593183D01*
X341567Y592892D01*
Y592517D01*
G01Y592892D02*
X341442Y593142D01*
X341233Y593350D01*
X340983Y593433D01*
X340733Y593350D01*
X340525Y593142D01*
X340400Y592767D01*
X340442Y592392D01*
X340608Y592017D01*
G01X350480Y584164D02*
X354480D01*
Y591564D01*
G01X402600Y578667D02*
X400100D01*
Y579708D01*
X400225Y580042D01*
X400392Y580250D01*
X400725Y580333D01*
X401058Y580250D01*
X401267Y580000D01*
X401392Y579708D01*
Y578667D01*
G01Y579708D02*
X402600Y580333D01*
G01X402100Y581683D02*
X402392Y581933D01*
X402558Y582267D01*
X402600Y582642D01*
X402558Y582975D01*
X402350Y583308D01*
X402100Y583517D01*
X401850Y583558D01*
X401558Y583475D01*
X401350Y583183D01*
X401267Y582892D01*
Y582517D01*
G01Y582892D02*
X401142Y583142D01*
X400933Y583350D01*
X400683Y583433D01*
X400433Y583350D01*
X400225Y583142D01*
X400100Y582767D01*
X400142Y582392D01*
X400308Y582017D01*
G01X402600Y586200D02*
X400100D01*
X401892Y584658D01*
Y586742D01*
G01X376350Y579406D02*
X380350D01*
Y586806D01*
G01X395967Y589100D02*
Y591600D01*
X397008D01*
X397342Y591475D01*
X397550Y591308D01*
X397633Y590975D01*
X397550Y590642D01*
X397300Y590433D01*
X397008Y590308D01*
X395967D01*
G01X397008D02*
X397633Y589100D01*
G01X398983Y589600D02*
X399233Y589308D01*
X399567Y589142D01*
X399942Y589100D01*
X400275Y589142D01*
X400608Y589350D01*
X400817Y589600D01*
X400858Y589850D01*
X400775Y590142D01*
X400483Y590350D01*
X400192Y590433D01*
X399817D01*
G01X400192D02*
X400442Y590558D01*
X400650Y590767D01*
X400733Y591017D01*
X400650Y591267D01*
X400442Y591475D01*
X400067Y591600D01*
X399692Y591558D01*
X399317Y591392D01*
G01X402083Y589475D02*
X402333Y589267D01*
X402625Y589142D01*
X403000Y589100D01*
X403375Y589183D01*
X403667Y589350D01*
X403875Y589642D01*
X403917Y589975D01*
X403833Y590308D01*
X403625Y590517D01*
X403333Y590683D01*
X403042Y590725D01*
X402750Y590683D01*
X402375Y590517D01*
X402500Y591600D01*
X403625D01*
G01X391979Y583543D02*
Y587543D01*
X384579D01*
G01X399100Y578667D02*
X396600D01*
Y579708D01*
X396725Y580042D01*
X396892Y580250D01*
X397225Y580333D01*
X397558Y580250D01*
X397767Y580000D01*
X397892Y579708D01*
Y578667D01*
G01Y579708D02*
X399100Y580333D01*
G01Y583100D02*
X396600D01*
X398392Y581558D01*
Y583642D01*
G01X399100Y585700D02*
X396600D01*
X397100Y585200D01*
G01X399100D02*
Y586200D01*
G01X376292Y588800D02*
X372292D01*
Y581400D01*
G01X343287Y535559D02*
X347287D01*
Y542959D01*
G01X354017Y542567D02*
Y545067D01*
X355058D01*
X355392Y544942D01*
X355600Y544775D01*
X355683Y544442D01*
X355600Y544109D01*
X355350Y543900D01*
X355058Y543775D01*
X354017D01*
G01X355058D02*
X355683Y542567D01*
G01X357950D02*
Y545067D01*
X357450Y544567D01*
G01Y542567D02*
X358450D01*
G01X360133Y543067D02*
X360383Y542775D01*
X360717Y542609D01*
X361092Y542567D01*
X361425Y542609D01*
X361758Y542817D01*
X361967Y543067D01*
X362008Y543317D01*
X361925Y543609D01*
X361633Y543817D01*
X361342Y543900D01*
X360967D01*
G01X361342D02*
X361592Y544025D01*
X361800Y544234D01*
X361883Y544484D01*
X361800Y544734D01*
X361592Y544942D01*
X361217Y545067D01*
X360842Y545025D01*
X360467Y544859D01*
G01X363358Y543609D02*
X363650Y543900D01*
X363900Y544067D01*
X364233Y544150D01*
X364525Y544067D01*
X364733Y543900D01*
X364900Y543650D01*
X364942Y543359D01*
X364900Y543109D01*
X364733Y542859D01*
X364483Y542650D01*
X364192Y542567D01*
X363858Y542650D01*
X363567Y542900D01*
X363400Y543275D01*
X363358Y543692D01*
X363442Y544234D01*
X363567Y544525D01*
X363775Y544817D01*
X364067Y545025D01*
X364358Y545067D01*
X364650Y544984D01*
X364858Y544775D01*
G01X343300Y547100D02*
Y543100D01*
X350700D01*
G01X389725Y532586D02*
Y535086D01*
X390766D01*
X391100Y534961D01*
X391308Y534794D01*
X391391Y534461D01*
X391308Y534128D01*
X391058Y533919D01*
X390766Y533794D01*
X389725D01*
G01X390766D02*
X391391Y532586D01*
G01X393658D02*
Y535086D01*
X393158Y534586D01*
G01Y532586D02*
X394158D01*
G01X395841Y533086D02*
X396091Y532794D01*
X396425Y532628D01*
X396800Y532586D01*
X397133Y532628D01*
X397466Y532836D01*
X397675Y533086D01*
X397716Y533336D01*
X397633Y533628D01*
X397341Y533836D01*
X397050Y533919D01*
X396675D01*
G01X397050D02*
X397300Y534044D01*
X397508Y534253D01*
X397591Y534503D01*
X397508Y534753D01*
X397300Y534961D01*
X396925Y535086D01*
X396550Y535044D01*
X396175Y534878D01*
G01X399150Y532878D02*
X399441Y532669D01*
X399775Y532586D01*
X400108Y532669D01*
X400400Y532919D01*
X400608Y533294D01*
X400691Y533669D01*
Y534128D01*
X400608Y534503D01*
X400400Y534836D01*
X400150Y535003D01*
X399858Y535086D01*
X399525Y535003D01*
X399275Y534836D01*
X399108Y534586D01*
X399025Y534253D01*
X399108Y533961D01*
X399316Y533669D01*
X399566Y533503D01*
X399858Y533461D01*
X400191Y533544D01*
X400441Y533753D01*
X400691Y534128D01*
G01X387600Y537900D02*
X383600D01*
Y530500D01*
G01X346600Y563017D02*
X344100D01*
Y564058D01*
X344225Y564392D01*
X344392Y564600D01*
X344725Y564683D01*
X345058Y564600D01*
X345267Y564350D01*
X345392Y564058D01*
Y563017D01*
G01Y564058D02*
X346600Y564683D01*
G01Y567450D02*
X344100D01*
X345892Y565908D01*
Y567992D01*
G01X344517Y569258D02*
X344267Y569508D01*
X344142Y569800D01*
X344100Y570133D01*
X344183Y570550D01*
X344392Y570842D01*
X344642Y570925D01*
X344892Y570883D01*
X345100Y570717D01*
X345517Y569883D01*
X345808Y569508D01*
X346225Y569258D01*
X346600Y569175D01*
Y570925D01*
G01X344517Y572358D02*
X344267Y572608D01*
X344142Y572900D01*
X344100Y573233D01*
X344183Y573650D01*
X344392Y573942D01*
X344642Y574025D01*
X344892Y573983D01*
X345100Y573817D01*
X345517Y572983D01*
X345808Y572608D01*
X346225Y572358D01*
X346600Y572275D01*
Y574025D01*
G01X347900Y583500D02*
X343900D01*
Y576100D01*
G01X397849Y553517D02*
X395349D01*
Y554558D01*
X395474Y554892D01*
X395641Y555100D01*
X395974Y555183D01*
X396307Y555100D01*
X396516Y554850D01*
X396641Y554558D01*
Y553517D01*
G01Y554558D02*
X397849Y555183D01*
G01Y557950D02*
X395349D01*
X397141Y556408D01*
Y558492D01*
G01X395766Y559758D02*
X395516Y560008D01*
X395391Y560300D01*
X395349Y560633D01*
X395432Y561050D01*
X395641Y561342D01*
X395891Y561425D01*
X396141Y561383D01*
X396349Y561217D01*
X396766Y560383D01*
X397057Y560008D01*
X397474Y559758D01*
X397849Y559675D01*
Y561425D01*
G01X397349Y562733D02*
X397641Y562983D01*
X397807Y563317D01*
X397849Y563692D01*
X397807Y564025D01*
X397599Y564358D01*
X397349Y564567D01*
X397099Y564608D01*
X396807Y564525D01*
X396599Y564233D01*
X396516Y563942D01*
Y563567D01*
G01Y563942D02*
X396391Y564192D01*
X396182Y564400D01*
X395932Y564483D01*
X395682Y564400D01*
X395474Y564192D01*
X395349Y563817D01*
X395391Y563442D01*
X395557Y563067D01*
G01X389549Y558200D02*
X393549D01*
Y565600D01*
G01X395117Y574000D02*
Y576500D01*
X396158D01*
X396492Y576375D01*
X396700Y576208D01*
X396783Y575875D01*
X396700Y575542D01*
X396450Y575333D01*
X396158Y575208D01*
X395117D01*
G01X396158D02*
X396783Y574000D01*
G01X399550D02*
Y576500D01*
X398008Y574708D01*
X400092D01*
G01X401358Y576083D02*
X401608Y576333D01*
X401900Y576458D01*
X402233Y576500D01*
X402650Y576417D01*
X402942Y576208D01*
X403025Y575958D01*
X402983Y575708D01*
X402817Y575500D01*
X401983Y575083D01*
X401608Y574792D01*
X401358Y574375D01*
X401275Y574000D01*
X403025D01*
G01X404458Y575042D02*
X404750Y575333D01*
X405000Y575500D01*
X405333Y575583D01*
X405625Y575500D01*
X405833Y575333D01*
X406000Y575083D01*
X406042Y574792D01*
X406000Y574542D01*
X405833Y574292D01*
X405583Y574083D01*
X405292Y574000D01*
X404958Y574083D01*
X404667Y574333D01*
X404500Y574708D01*
X404458Y575125D01*
X404542Y575667D01*
X404667Y575958D01*
X404875Y576250D01*
X405167Y576458D01*
X405458Y576500D01*
X405750Y576417D01*
X405958Y576208D01*
G01X391700Y574500D02*
Y578500D01*
X384300D01*
G01X395117Y570300D02*
Y572800D01*
X396158D01*
X396492Y572675D01*
X396700Y572508D01*
X396783Y572175D01*
X396700Y571842D01*
X396450Y571633D01*
X396158Y571508D01*
X395117D01*
G01X396158D02*
X396783Y570300D01*
G01X399550D02*
Y572800D01*
X398008Y571008D01*
X400092D01*
G01X401358Y572383D02*
X401608Y572633D01*
X401900Y572758D01*
X402233Y572800D01*
X402650Y572717D01*
X402942Y572508D01*
X403025Y572258D01*
X402983Y572008D01*
X402817Y571800D01*
X401983Y571383D01*
X401608Y571092D01*
X401358Y570675D01*
X401275Y570300D01*
X403025D01*
G01X405167D02*
X405250Y570842D01*
X405375Y571300D01*
X405542Y571717D01*
X405750Y572175D01*
X406083Y572800D01*
X404417D01*
G01X391700Y570500D02*
Y574500D01*
X384300D01*
G01X395117Y566600D02*
Y569100D01*
X396158D01*
X396492Y568975D01*
X396700Y568808D01*
X396783Y568475D01*
X396700Y568142D01*
X396450Y567933D01*
X396158Y567808D01*
X395117D01*
G01X396158D02*
X396783Y566600D01*
G01X399550D02*
Y569100D01*
X398008Y567308D01*
X400092D01*
G01X401358Y568683D02*
X401608Y568933D01*
X401900Y569058D01*
X402233Y569100D01*
X402650Y569017D01*
X402942Y568808D01*
X403025Y568558D01*
X402983Y568308D01*
X402817Y568100D01*
X401983Y567683D01*
X401608Y567392D01*
X401358Y566975D01*
X401275Y566600D01*
X403025D01*
G01X405250D02*
X405542Y566642D01*
X405875Y566767D01*
X406083Y566975D01*
X406167Y567267D01*
X406083Y567558D01*
X405833Y567808D01*
X405458Y567933D01*
X405042D01*
X404792Y568017D01*
X404583Y568225D01*
X404500Y568517D01*
X404625Y568808D01*
X404917Y569017D01*
X405250Y569100D01*
X405583Y569017D01*
X405875Y568808D01*
X406000Y568517D01*
X405917Y568225D01*
X405708Y568017D01*
X405458Y567933D01*
X405042D01*
X404667Y567808D01*
X404417Y567558D01*
X404333Y567267D01*
X404417Y566975D01*
X404625Y566767D01*
X404958Y566642D01*
X405250Y566600D01*
G01X384300Y570500D02*
Y566500D01*
X391700D01*
G01X371088Y539881D02*
X369288Y537781D01*
X367088Y539881D01*
G01X393408Y580417D02*
X393283Y580167D01*
X393200Y579875D01*
Y579542D01*
X393325Y579167D01*
X393533Y578875D01*
X393783Y578667D01*
X394200Y578500D01*
X394575Y578458D01*
X394950Y578542D01*
X395200Y578667D01*
X395450Y578917D01*
X395617Y579208D01*
X395700Y579500D01*
Y579792D01*
X395617Y580083D01*
X395492Y580333D01*
X395325Y580542D01*
G01X395700Y582600D02*
X393200D01*
X393700Y582100D01*
G01X395700D02*
Y583100D01*
G01Y585700D02*
X395658Y585992D01*
X395533Y586325D01*
X395325Y586533D01*
X395033Y586617D01*
X394742Y586533D01*
X394492Y586283D01*
X394367Y585908D01*
Y585492D01*
X394283Y585242D01*
X394075Y585033D01*
X393783Y584950D01*
X393492Y585075D01*
X393283Y585367D01*
X393200Y585700D01*
X393283Y586033D01*
X393492Y586325D01*
X393783Y586450D01*
X394075Y586367D01*
X394283Y586158D01*
X394367Y585908D01*
Y585492D01*
X394492Y585117D01*
X394742Y584867D01*
X395033Y584783D01*
X395325Y584867D01*
X395533Y585075D01*
X395658Y585408D01*
X395700Y585700D01*
G01X383283Y554867D02*
Y553075D01*
X383450Y552700D01*
X383783Y552450D01*
X384200Y552367D01*
X384617Y552450D01*
X384950Y552700D01*
X385117Y553075D01*
Y554867D01*
G01X386383Y552867D02*
X386633Y552575D01*
X386967Y552409D01*
X387342Y552367D01*
X387675Y552409D01*
X388008Y552617D01*
X388217Y552867D01*
X388258Y553117D01*
X388175Y553409D01*
X387883Y553617D01*
X387592Y553700D01*
X387217D01*
G01X387592D02*
X387842Y553825D01*
X388050Y554034D01*
X388133Y554284D01*
X388050Y554534D01*
X387842Y554742D01*
X387467Y554867D01*
X387092Y554825D01*
X386717Y554659D01*
G01X390900Y552367D02*
Y554867D01*
X389358Y553075D01*
X391442D01*
G01X351339Y578279D02*
X372339D01*
Y546629D01*
X361339D01*
Y578279D01*
G01X369989D02*
X366839Y575129D01*
X363689Y578279D01*
G01X378017Y649859D02*
X377767Y649984D01*
X377475Y650067D01*
X377142D01*
X376767Y649942D01*
X376475Y649734D01*
X376267Y649484D01*
X376100Y649067D01*
X376058Y648692D01*
X376142Y648317D01*
X376267Y648067D01*
X376517Y647817D01*
X376808Y647650D01*
X377100Y647567D01*
X377392D01*
X377683Y647650D01*
X377933Y647775D01*
X378142Y647942D01*
G01X380200Y647567D02*
Y650067D01*
X379700Y649567D01*
G01Y647567D02*
X380700D01*
G01X383217D02*
X383300Y648109D01*
X383425Y648567D01*
X383592Y648984D01*
X383800Y649442D01*
X384133Y650067D01*
X382467D01*
G01X387717Y649859D02*
X387467Y649984D01*
X387175Y650067D01*
X386842D01*
X386467Y649942D01*
X386175Y649734D01*
X385967Y649484D01*
X385800Y649067D01*
X385758Y648692D01*
X385842Y648317D01*
X385967Y648067D01*
X386217Y647817D01*
X386508Y647650D01*
X386800Y647567D01*
X387092D01*
X387383Y647650D01*
X387633Y647775D01*
X387842Y647942D01*
G01X389108Y649650D02*
X389358Y649900D01*
X389650Y650025D01*
X389983Y650067D01*
X390400Y649984D01*
X390692Y649775D01*
X390775Y649525D01*
X390733Y649275D01*
X390567Y649067D01*
X389733Y648650D01*
X389358Y648359D01*
X389108Y647942D01*
X389025Y647567D01*
X390775D01*
G01X393000Y650067D02*
X392667Y649984D01*
X392417Y649775D01*
X392250Y649525D01*
X392125Y649192D01*
X392083Y648817D01*
X392125Y648442D01*
X392250Y648109D01*
X392417Y647859D01*
X392667Y647650D01*
X393000Y647567D01*
X393333Y647650D01*
X393583Y647859D01*
X393750Y648109D01*
X393875Y648442D01*
X393917Y648817D01*
X393875Y649192D01*
X393750Y649525D01*
X393583Y649775D01*
X393333Y649984D01*
X393000Y650067D01*
G01X342208Y635267D02*
X342083Y635017D01*
X342000Y634725D01*
Y634392D01*
X342125Y634017D01*
X342333Y633725D01*
X342583Y633517D01*
X343000Y633350D01*
X343375Y633308D01*
X343750Y633392D01*
X344000Y633517D01*
X344250Y633767D01*
X344417Y634058D01*
X344500Y634350D01*
Y634642D01*
X344417Y634933D01*
X344292Y635183D01*
X344125Y635392D01*
G01X342417Y636658D02*
X342167Y636908D01*
X342042Y637200D01*
X342000Y637533D01*
X342083Y637950D01*
X342292Y638242D01*
X342542Y638325D01*
X342792Y638283D01*
X343000Y638117D01*
X343417Y637283D01*
X343708Y636908D01*
X344125Y636658D01*
X344500Y636575D01*
Y638325D01*
G01X344000Y639633D02*
X344292Y639883D01*
X344458Y640217D01*
X344500Y640592D01*
X344458Y640925D01*
X344250Y641258D01*
X344000Y641467D01*
X343750Y641508D01*
X343458Y641425D01*
X343250Y641133D01*
X343167Y640842D01*
Y640467D01*
G01Y640842D02*
X343042Y641092D01*
X342833Y641300D01*
X342583Y641383D01*
X342333Y641300D01*
X342125Y641092D01*
X342000Y640717D01*
X342042Y640342D01*
X342208Y639967D01*
G01X344500Y643567D02*
X343958Y643650D01*
X343500Y643775D01*
X343083Y643942D01*
X342625Y644150D01*
X342000Y644483D01*
Y642817D01*
G01X394586Y629049D02*
Y631549D01*
X395627D01*
X395961Y631424D01*
X396169Y631257D01*
X396252Y630924D01*
X396169Y630591D01*
X395919Y630382D01*
X395627Y630257D01*
X394586D01*
G01X395627D02*
X396252Y629049D01*
G01X397727Y631132D02*
X397977Y631382D01*
X398269Y631507D01*
X398602Y631549D01*
X399019Y631466D01*
X399311Y631257D01*
X399394Y631007D01*
X399352Y630757D01*
X399186Y630549D01*
X398352Y630132D01*
X397977Y629841D01*
X397727Y629424D01*
X397644Y629049D01*
X399394D01*
G01X400827Y630091D02*
X401119Y630382D01*
X401369Y630549D01*
X401702Y630632D01*
X401994Y630549D01*
X402202Y630382D01*
X402369Y630132D01*
X402411Y629841D01*
X402369Y629591D01*
X402202Y629341D01*
X401952Y629132D01*
X401661Y629049D01*
X401327Y629132D01*
X401036Y629382D01*
X400869Y629757D01*
X400827Y630174D01*
X400911Y630716D01*
X401036Y631007D01*
X401244Y631299D01*
X401536Y631507D01*
X401827Y631549D01*
X402119Y631466D01*
X402327Y631257D01*
G01X385781Y625786D02*
Y621786D01*
X393181D01*
G01X395867Y611400D02*
Y613900D01*
X396908D01*
X397242Y613775D01*
X397450Y613608D01*
X397533Y613275D01*
X397450Y612942D01*
X397200Y612733D01*
X396908Y612608D01*
X395867D01*
G01X396908D02*
X397533Y611400D01*
G01X398883Y611900D02*
X399133Y611608D01*
X399467Y611442D01*
X399842Y611400D01*
X400175Y611442D01*
X400508Y611650D01*
X400717Y611900D01*
X400758Y612150D01*
X400675Y612442D01*
X400383Y612650D01*
X400092Y612733D01*
X399717D01*
G01X400092D02*
X400342Y612858D01*
X400550Y613067D01*
X400633Y613317D01*
X400550Y613567D01*
X400342Y613775D01*
X399967Y613900D01*
X399592Y613858D01*
X399217Y613692D01*
G01X402900Y611400D02*
Y613900D01*
X402400Y613400D01*
G01Y611400D02*
X403400D01*
G01X393100Y600100D02*
Y604100D01*
X385700D01*
G01X402100Y601667D02*
X399600D01*
Y602708D01*
X399725Y603042D01*
X399892Y603250D01*
X400225Y603333D01*
X400558Y603250D01*
X400767Y603000D01*
X400892Y602708D01*
Y601667D01*
G01Y602708D02*
X402100Y603333D01*
G01X401600Y604683D02*
X401892Y604933D01*
X402058Y605267D01*
X402100Y605642D01*
X402058Y605975D01*
X401850Y606308D01*
X401600Y606517D01*
X401350Y606558D01*
X401058Y606475D01*
X400850Y606183D01*
X400767Y605892D01*
Y605517D01*
G01Y605892D02*
X400642Y606142D01*
X400433Y606350D01*
X400183Y606433D01*
X399933Y606350D01*
X399725Y606142D01*
X399600Y605767D01*
X399642Y605392D01*
X399808Y605017D01*
G01X401058Y607908D02*
X400767Y608200D01*
X400600Y608450D01*
X400517Y608783D01*
X400600Y609075D01*
X400767Y609283D01*
X401017Y609450D01*
X401308Y609492D01*
X401558Y609450D01*
X401808Y609283D01*
X402017Y609033D01*
X402100Y608742D01*
X402017Y608408D01*
X401767Y608117D01*
X401392Y607950D01*
X400975Y607908D01*
X400433Y607992D01*
X400142Y608117D01*
X399850Y608325D01*
X399642Y608617D01*
X399600Y608908D01*
X399683Y609200D01*
X399892Y609408D01*
G01X398400Y601667D02*
X395900D01*
Y602708D01*
X396025Y603042D01*
X396192Y603250D01*
X396525Y603333D01*
X396858Y603250D01*
X397067Y603000D01*
X397192Y602708D01*
Y601667D01*
G01Y602708D02*
X398400Y603333D01*
G01Y606100D02*
X395900D01*
X397692Y604558D01*
Y606642D01*
G01X397900Y607783D02*
X398192Y608033D01*
X398358Y608367D01*
X398400Y608742D01*
X398358Y609075D01*
X398150Y609408D01*
X397900Y609617D01*
X397650Y609658D01*
X397358Y609575D01*
X397150Y609283D01*
X397067Y608992D01*
Y608617D01*
G01Y608992D02*
X396942Y609242D01*
X396733Y609450D01*
X396483Y609533D01*
X396233Y609450D01*
X396025Y609242D01*
X395900Y608867D01*
X395942Y608492D01*
X396108Y608117D01*
G01X394586Y625349D02*
Y627849D01*
X395627D01*
X395961Y627724D01*
X396169Y627557D01*
X396252Y627224D01*
X396169Y626891D01*
X395919Y626682D01*
X395627Y626557D01*
X394586D01*
G01X395627D02*
X396252Y625349D01*
G01X398519D02*
Y627849D01*
X398019Y627349D01*
G01Y625349D02*
X399019D01*
G01X401619D02*
X401911Y625391D01*
X402244Y625516D01*
X402452Y625724D01*
X402536Y626016D01*
X402452Y626307D01*
X402202Y626557D01*
X401827Y626682D01*
X401411D01*
X401161Y626766D01*
X400952Y626974D01*
X400869Y627266D01*
X400994Y627557D01*
X401286Y627766D01*
X401619Y627849D01*
X401952Y627766D01*
X402244Y627557D01*
X402369Y627266D01*
X402286Y626974D01*
X402077Y626766D01*
X401827Y626682D01*
X401411D01*
X401036Y626557D01*
X400786Y626307D01*
X400702Y626016D01*
X400786Y625724D01*
X400994Y625516D01*
X401327Y625391D01*
X401619Y625349D01*
G01X393136Y617701D02*
Y621701D01*
X385736D01*
G01X395867Y615100D02*
Y617600D01*
X396908D01*
X397242Y617475D01*
X397450Y617308D01*
X397533Y616975D01*
X397450Y616642D01*
X397200Y616433D01*
X396908Y616308D01*
X395867D01*
G01X396908D02*
X397533Y615100D01*
G01X399800D02*
Y617600D01*
X399300Y617100D01*
G01Y615100D02*
X400300D01*
G01X402192Y615392D02*
X402483Y615183D01*
X402817Y615100D01*
X403150Y615183D01*
X403442Y615433D01*
X403650Y615808D01*
X403733Y616183D01*
Y616642D01*
X403650Y617017D01*
X403442Y617350D01*
X403192Y617517D01*
X402900Y617600D01*
X402567Y617517D01*
X402317Y617350D01*
X402150Y617100D01*
X402067Y616767D01*
X402150Y616475D01*
X402358Y616183D01*
X402608Y616017D01*
X402900Y615975D01*
X403233Y616058D01*
X403483Y616267D01*
X403733Y616642D01*
G01X393100Y604200D02*
Y608200D01*
X385700D01*
G01X394766Y633204D02*
Y635704D01*
X395807D01*
X396141Y635579D01*
X396349Y635412D01*
X396432Y635079D01*
X396349Y634746D01*
X396099Y634537D01*
X395807Y634412D01*
X394766D01*
G01X395807D02*
X396432Y633204D01*
G01X397907Y635287D02*
X398157Y635537D01*
X398449Y635662D01*
X398782Y635704D01*
X399199Y635621D01*
X399491Y635412D01*
X399574Y635162D01*
X399532Y634912D01*
X399366Y634704D01*
X398532Y634287D01*
X398157Y633996D01*
X397907Y633579D01*
X397824Y633204D01*
X399574D01*
G01X401799Y635704D02*
X401466Y635621D01*
X401216Y635412D01*
X401049Y635162D01*
X400924Y634829D01*
X400882Y634454D01*
X400924Y634079D01*
X401049Y633746D01*
X401216Y633496D01*
X401466Y633287D01*
X401799Y633204D01*
X402132Y633287D01*
X402382Y633496D01*
X402549Y633746D01*
X402674Y634079D01*
X402716Y634454D01*
X402674Y634829D01*
X402549Y635162D01*
X402382Y635412D01*
X402132Y635621D01*
X401799Y635704D01*
G01X392986Y626081D02*
Y630081D01*
X385586D01*
G01X395867Y618800D02*
Y621300D01*
X396908D01*
X397242Y621175D01*
X397450Y621008D01*
X397533Y620675D01*
X397450Y620342D01*
X397200Y620133D01*
X396908Y620008D01*
X395867D01*
G01X396908D02*
X397533Y618800D01*
G01X399008Y620883D02*
X399258Y621133D01*
X399550Y621258D01*
X399883Y621300D01*
X400300Y621217D01*
X400592Y621008D01*
X400675Y620758D01*
X400633Y620508D01*
X400467Y620300D01*
X399633Y619883D01*
X399258Y619592D01*
X399008Y619175D01*
X398925Y618800D01*
X400675D01*
G01X401983Y619300D02*
X402233Y619008D01*
X402567Y618842D01*
X402942Y618800D01*
X403275Y618842D01*
X403608Y619050D01*
X403817Y619300D01*
X403858Y619550D01*
X403775Y619842D01*
X403483Y620050D01*
X403192Y620133D01*
X402817D01*
G01X403192D02*
X403442Y620258D01*
X403650Y620467D01*
X403733Y620717D01*
X403650Y620967D01*
X403442Y621175D01*
X403067Y621300D01*
X402692Y621258D01*
X402317Y621092D01*
G01X385700Y612300D02*
Y608300D01*
X393100D01*
G01X378267Y643067D02*
Y645567D01*
X379308D01*
X379642Y645442D01*
X379850Y645275D01*
X379933Y644942D01*
X379850Y644609D01*
X379600Y644400D01*
X379308Y644275D01*
X378267D01*
G01X379308D02*
X379933Y643067D01*
G01X381408Y645150D02*
X381658Y645400D01*
X381950Y645525D01*
X382283Y645567D01*
X382700Y645484D01*
X382992Y645275D01*
X383075Y645025D01*
X383033Y644775D01*
X382867Y644567D01*
X382033Y644150D01*
X381658Y643859D01*
X381408Y643442D01*
X381325Y643067D01*
X383075D01*
G01X385217D02*
X385300Y643609D01*
X385425Y644067D01*
X385592Y644484D01*
X385800Y644942D01*
X386133Y645567D01*
X384467D01*
G01X360664Y637920D02*
Y633920D01*
X368064D01*
G01X348600Y644367D02*
X346100D01*
Y645408D01*
X346225Y645742D01*
X346392Y645950D01*
X346725Y646033D01*
X347058Y645950D01*
X347267Y645700D01*
X347392Y645408D01*
Y644367D01*
G01Y645408D02*
X348600Y646033D01*
G01X346517Y647508D02*
X346267Y647758D01*
X346142Y648050D01*
X346100Y648383D01*
X346183Y648800D01*
X346392Y649092D01*
X346642Y649175D01*
X346892Y649133D01*
X347100Y648967D01*
X347517Y648133D01*
X347808Y647758D01*
X348225Y647508D01*
X348600Y647425D01*
Y649175D01*
G01Y651400D02*
X348558Y651692D01*
X348433Y652025D01*
X348225Y652233D01*
X347933Y652317D01*
X347642Y652233D01*
X347392Y651983D01*
X347267Y651608D01*
Y651192D01*
X347183Y650942D01*
X346975Y650733D01*
X346683Y650650D01*
X346392Y650775D01*
X346183Y651067D01*
X346100Y651400D01*
X346183Y651733D01*
X346392Y652025D01*
X346683Y652150D01*
X346975Y652067D01*
X347183Y651858D01*
X347267Y651608D01*
Y651192D01*
X347392Y650817D01*
X347642Y650567D01*
X347933Y650483D01*
X348225Y650567D01*
X348433Y650775D01*
X348558Y651108D01*
X348600Y651400D01*
G01X346600Y633600D02*
X350600D01*
Y641000D01*
G01X394761Y637354D02*
Y639854D01*
X395802D01*
X396136Y639729D01*
X396344Y639562D01*
X396427Y639229D01*
X396344Y638896D01*
X396094Y638687D01*
X395802Y638562D01*
X394761D01*
G01X395802D02*
X396427Y637354D01*
G01X397777Y637854D02*
X398027Y637562D01*
X398361Y637396D01*
X398736Y637354D01*
X399069Y637396D01*
X399402Y637604D01*
X399611Y637854D01*
X399652Y638104D01*
X399569Y638396D01*
X399277Y638604D01*
X398986Y638687D01*
X398611D01*
G01X398986D02*
X399236Y638812D01*
X399444Y639021D01*
X399527Y639271D01*
X399444Y639521D01*
X399236Y639729D01*
X398861Y639854D01*
X398486Y639812D01*
X398111Y639646D01*
G01X401002Y639437D02*
X401252Y639687D01*
X401544Y639812D01*
X401877Y639854D01*
X402294Y639771D01*
X402586Y639562D01*
X402669Y639312D01*
X402627Y639062D01*
X402461Y638854D01*
X401627Y638437D01*
X401252Y638146D01*
X401002Y637729D01*
X400919Y637354D01*
X402669D01*
G01X392950Y635348D02*
Y639348D01*
X385550D01*
G01X396800Y599000D02*
Y596500D01*
G01X395842Y599000D02*
X397758D01*
G01X399067Y596500D02*
Y599000D01*
X400067D01*
X400400Y598875D01*
X400650Y598583D01*
X400733Y598250D01*
X400650Y597917D01*
X400442Y597667D01*
X400067Y597542D01*
X399067D01*
G01X402083Y596875D02*
X402333Y596667D01*
X402625Y596542D01*
X403000Y596500D01*
X403375Y596583D01*
X403667Y596750D01*
X403875Y597042D01*
X403917Y597375D01*
X403833Y597708D01*
X403625Y597917D01*
X403333Y598083D01*
X403042Y598125D01*
X402750Y598083D01*
X402375Y597917D01*
X402500Y599000D01*
X403625D01*
G01X367084Y658350D02*
X367042Y658017D01*
X366876Y657725D01*
X366626Y657475D01*
X366334Y657308D01*
X366001Y657225D01*
X365667D01*
X365334Y657308D01*
X365042Y657475D01*
X364792Y657725D01*
X364626Y658017D01*
X364584Y658350D01*
X364626Y658683D01*
X364792Y658975D01*
X365042Y659225D01*
X365334Y659392D01*
X365667Y659475D01*
X366001D01*
X366334Y659392D01*
X366626Y659225D01*
X366876Y658975D01*
X367042Y658683D01*
X367084Y658350D01*
G01X366417Y658683D02*
X367084Y659183D01*
G01Y661450D02*
X364584D01*
X365084Y660950D01*
G01X367084D02*
Y661950D01*
G01X365001Y663758D02*
X364751Y664008D01*
X364626Y664300D01*
X364584Y664633D01*
X364667Y665050D01*
X364876Y665342D01*
X365126Y665425D01*
X365376Y665383D01*
X365584Y665217D01*
X366001Y664383D01*
X366292Y664008D01*
X366709Y663758D01*
X367084Y663675D01*
Y665425D01*
G01X371484Y658550D02*
X371442Y658217D01*
X371276Y657925D01*
X371026Y657675D01*
X370734Y657508D01*
X370401Y657425D01*
X370067D01*
X369734Y657508D01*
X369442Y657675D01*
X369192Y657925D01*
X369026Y658217D01*
X368984Y658550D01*
X369026Y658883D01*
X369192Y659175D01*
X369442Y659425D01*
X369734Y659592D01*
X370067Y659675D01*
X370401D01*
X370734Y659592D01*
X371026Y659425D01*
X371276Y659175D01*
X371442Y658883D01*
X371484Y658550D01*
G01X370817Y658883D02*
X371484Y659383D01*
G01Y661650D02*
X368984D01*
X369484Y661150D01*
G01X371484D02*
Y662150D01*
G01Y664750D02*
X368984D01*
X369484Y664250D01*
G01X371484D02*
Y665250D01*
G01X340381Y667305D02*
Y653305D01*
G01X353381D02*
Y667305D01*
G01X340381Y653305D02*
X353381D01*
G01X350308Y646117D02*
X350183Y645867D01*
X350100Y645575D01*
Y645242D01*
X350225Y644867D01*
X350433Y644575D01*
X350683Y644367D01*
X351100Y644200D01*
X351475Y644158D01*
X351850Y644242D01*
X352100Y644367D01*
X352350Y644617D01*
X352517Y644908D01*
X352600Y645200D01*
Y645492D01*
X352517Y645783D01*
X352392Y646033D01*
X352225Y646242D01*
G01X352600Y648300D02*
X350100D01*
X350600Y647800D01*
G01X352600D02*
Y648800D01*
G01X352308Y650692D02*
X352517Y650983D01*
X352600Y651317D01*
X352517Y651650D01*
X352267Y651942D01*
X351892Y652150D01*
X351517Y652233D01*
X351058D01*
X350683Y652150D01*
X350350Y651942D01*
X350183Y651692D01*
X350100Y651400D01*
X350183Y651067D01*
X350350Y650817D01*
X350600Y650650D01*
X350933Y650567D01*
X351225Y650650D01*
X351517Y650858D01*
X351683Y651108D01*
X351725Y651400D01*
X351642Y651733D01*
X351433Y651983D01*
X351058Y652233D01*
G01X378875Y653500D02*
X380625Y656000D01*
G01X378875D02*
X380625Y653500D01*
G01X382850D02*
Y656000D01*
X382350Y655500D01*
G01Y653500D02*
X383350D01*
G01X373011Y654949D02*
X356311D01*
Y642749D01*
X373011D01*
Y654949D01*
G01X349083Y632500D02*
Y630708D01*
X349250Y630333D01*
X349583Y630083D01*
X350000Y630000D01*
X350417Y630083D01*
X350750Y630333D01*
X350917Y630708D01*
Y632500D01*
G01X352392Y630292D02*
X352683Y630083D01*
X353017Y630000D01*
X353350Y630083D01*
X353642Y630333D01*
X353850Y630708D01*
X353933Y631083D01*
Y631542D01*
X353850Y631917D01*
X353642Y632250D01*
X353392Y632417D01*
X353100Y632500D01*
X352767Y632417D01*
X352517Y632250D01*
X352350Y632000D01*
X352267Y631667D01*
X352350Y631375D01*
X352558Y631083D01*
X352808Y630917D01*
X353100Y630875D01*
X353433Y630958D01*
X353683Y631167D01*
X353933Y631542D01*
G01X355492Y630292D02*
X355783Y630083D01*
X356117Y630000D01*
X356450Y630083D01*
X356742Y630333D01*
X356950Y630708D01*
X357033Y631083D01*
Y631542D01*
X356950Y631917D01*
X356742Y632250D01*
X356492Y632417D01*
X356200Y632500D01*
X355867Y632417D01*
X355617Y632250D01*
X355450Y632000D01*
X355367Y631667D01*
X355450Y631375D01*
X355658Y631083D01*
X355908Y630917D01*
X356200Y630875D01*
X356533Y630958D01*
X356783Y631167D01*
X357033Y631542D01*
G01X359164Y629720D02*
Y627820D01*
G01X368964Y630320D02*
Y627620D01*
G01X382164Y616520D02*
X380164D01*
G01X380264Y606720D02*
X382664D01*
G01X367064Y597420D02*
Y595620D01*
G01X357264Y597720D02*
Y595020D01*
G01X350264Y612520D02*
X348264D01*
G01X380964Y623420D02*
Y628420D01*
X375964D01*
G01X380964Y601820D02*
Y596820D01*
X375964D01*
G01X354364D02*
X349364D01*
Y601820D01*
G01X393467Y698658D02*
X393217Y698783D01*
X392925Y698866D01*
X392592D01*
X392217Y698741D01*
X391925Y698533D01*
X391717Y698283D01*
X391550Y697866D01*
X391508Y697491D01*
X391592Y697116D01*
X391717Y696866D01*
X391967Y696616D01*
X392258Y696449D01*
X392550Y696366D01*
X392842D01*
X393133Y696449D01*
X393383Y696574D01*
X393592Y696741D01*
G01X395650Y696366D02*
Y698866D01*
X395150Y698366D01*
G01Y696366D02*
X396150D01*
G01X399250D02*
Y698866D01*
X397708Y697074D01*
X399792D01*
G01X401850Y696366D02*
Y698866D01*
X401350Y698366D01*
G01Y696366D02*
X402350D01*
G01X344967Y708592D02*
X344717Y708717D01*
X344425Y708800D01*
X344092D01*
X343717Y708675D01*
X343425Y708467D01*
X343217Y708217D01*
X343050Y707800D01*
X343008Y707425D01*
X343092Y707050D01*
X343217Y706800D01*
X343467Y706550D01*
X343758Y706383D01*
X344050Y706300D01*
X344342D01*
X344633Y706383D01*
X344883Y706508D01*
X345092Y706675D01*
G01X347150Y706300D02*
Y708800D01*
X346650Y708300D01*
G01Y706300D02*
X347650D01*
G01X349333Y706800D02*
X349583Y706508D01*
X349917Y706342D01*
X350292Y706300D01*
X350625Y706342D01*
X350958Y706550D01*
X351167Y706800D01*
X351208Y707050D01*
X351125Y707342D01*
X350833Y707550D01*
X350542Y707633D01*
X350167D01*
G01X350542D02*
X350792Y707758D01*
X351000Y707967D01*
X351083Y708217D01*
X351000Y708467D01*
X350792Y708675D01*
X350417Y708800D01*
X350042Y708758D01*
X349667Y708592D01*
G01X352558Y707342D02*
X352850Y707633D01*
X353100Y707800D01*
X353433Y707883D01*
X353725Y707800D01*
X353933Y707633D01*
X354100Y707383D01*
X354142Y707092D01*
X354100Y706842D01*
X353933Y706592D01*
X353683Y706383D01*
X353392Y706300D01*
X353058Y706383D01*
X352767Y706633D01*
X352600Y707008D01*
X352558Y707425D01*
X352642Y707967D01*
X352767Y708258D01*
X352975Y708550D01*
X353267Y708758D01*
X353558Y708800D01*
X353850Y708717D01*
X354058Y708508D01*
G01X392317Y692166D02*
Y694666D01*
X393358D01*
X393692Y694541D01*
X393900Y694374D01*
X393983Y694041D01*
X393900Y693708D01*
X393650Y693499D01*
X393358Y693374D01*
X392317D01*
G01X393358D02*
X393983Y692166D01*
G01X396167D02*
X396250Y692708D01*
X396375Y693166D01*
X396542Y693583D01*
X396750Y694041D01*
X397083Y694666D01*
X395417D01*
G01X398433Y692666D02*
X398683Y692374D01*
X399017Y692208D01*
X399392Y692166D01*
X399725Y692208D01*
X400058Y692416D01*
X400267Y692666D01*
X400308Y692916D01*
X400225Y693208D01*
X399933Y693416D01*
X399642Y693499D01*
X399267D01*
G01X399642D02*
X399892Y693624D01*
X400100Y693833D01*
X400183Y694083D01*
X400100Y694333D01*
X399892Y694541D01*
X399517Y694666D01*
X399142Y694624D01*
X398767Y694458D01*
G01X401658Y693208D02*
X401950Y693499D01*
X402200Y693666D01*
X402533Y693749D01*
X402825Y693666D01*
X403033Y693499D01*
X403200Y693249D01*
X403242Y692958D01*
X403200Y692708D01*
X403033Y692458D01*
X402783Y692249D01*
X402492Y692166D01*
X402158Y692249D01*
X401867Y692499D01*
X401700Y692874D01*
X401658Y693291D01*
X401742Y693833D01*
X401867Y694124D01*
X402075Y694416D01*
X402367Y694624D01*
X402658Y694666D01*
X402950Y694583D01*
X403158Y694374D01*
G01X390625Y691371D02*
Y695371D01*
X383225D01*
G01X395117Y671766D02*
Y674266D01*
X396158D01*
X396492Y674141D01*
X396700Y673974D01*
X396783Y673641D01*
X396700Y673308D01*
X396450Y673099D01*
X396158Y672974D01*
X395117D01*
G01X396158D02*
X396783Y671766D01*
G01X398967D02*
X399050Y672308D01*
X399175Y672766D01*
X399342Y673183D01*
X399550Y673641D01*
X399883Y674266D01*
X398217D01*
G01X401358Y673849D02*
X401608Y674099D01*
X401900Y674224D01*
X402233Y674266D01*
X402650Y674183D01*
X402942Y673974D01*
X403025Y673724D01*
X402983Y673474D01*
X402817Y673266D01*
X401983Y672849D01*
X401608Y672558D01*
X401358Y672141D01*
X401275Y671766D01*
X403025D01*
G01X405750D02*
Y674266D01*
X404208Y672474D01*
X406292D01*
G01X391100Y669800D02*
Y673800D01*
X383700D01*
G01X358683Y658667D02*
X356183D01*
Y659708D01*
X356308Y660042D01*
X356475Y660250D01*
X356808Y660333D01*
X357141Y660250D01*
X357350Y660000D01*
X357475Y659708D01*
Y658667D01*
G01Y659708D02*
X358683Y660333D01*
G01Y662517D02*
X358141Y662600D01*
X357683Y662725D01*
X357266Y662892D01*
X356808Y663100D01*
X356183Y663433D01*
Y661767D01*
G01X356600Y664908D02*
X356350Y665158D01*
X356225Y665450D01*
X356183Y665783D01*
X356266Y666200D01*
X356475Y666492D01*
X356725Y666575D01*
X356975Y666533D01*
X357183Y666367D01*
X357600Y665533D01*
X357891Y665158D01*
X358308Y664908D01*
X358683Y664825D01*
Y666575D01*
G01X357641Y668008D02*
X357350Y668300D01*
X357183Y668550D01*
X357100Y668883D01*
X357183Y669175D01*
X357350Y669383D01*
X357600Y669550D01*
X357891Y669592D01*
X358141Y669550D01*
X358391Y669383D01*
X358600Y669133D01*
X358683Y668842D01*
X358600Y668508D01*
X358350Y668217D01*
X357975Y668050D01*
X357558Y668008D01*
X357016Y668092D01*
X356725Y668217D01*
X356433Y668425D01*
X356225Y668717D01*
X356183Y669008D01*
X356266Y669300D01*
X356475Y669508D01*
G01X363183Y658767D02*
X360683D01*
Y659808D01*
X360808Y660142D01*
X360975Y660350D01*
X361308Y660433D01*
X361641Y660350D01*
X361850Y660100D01*
X361975Y659808D01*
Y658767D01*
G01Y659808D02*
X363183Y660433D01*
G01Y662617D02*
X362641Y662700D01*
X362183Y662825D01*
X361766Y662992D01*
X361308Y663200D01*
X360683Y663533D01*
Y661867D01*
G01X361100Y665008D02*
X360850Y665258D01*
X360725Y665550D01*
X360683Y665883D01*
X360766Y666300D01*
X360975Y666592D01*
X361225Y666675D01*
X361475Y666633D01*
X361683Y666467D01*
X362100Y665633D01*
X362391Y665258D01*
X362808Y665008D01*
X363183Y664925D01*
Y666675D01*
G01X362683Y667983D02*
X362975Y668233D01*
X363141Y668567D01*
X363183Y668942D01*
X363141Y669275D01*
X362933Y669608D01*
X362683Y669817D01*
X362433Y669858D01*
X362141Y669775D01*
X361933Y669483D01*
X361850Y669192D01*
Y668817D01*
G01Y669192D02*
X361725Y669442D01*
X361516Y669650D01*
X361266Y669733D01*
X361016Y669650D01*
X360808Y669442D01*
X360683Y669067D01*
X360725Y668692D01*
X360891Y668317D01*
G01X392972Y688244D02*
Y690744D01*
X394013D01*
X394347Y690619D01*
X394555Y690452D01*
X394638Y690119D01*
X394555Y689786D01*
X394305Y689577D01*
X394013Y689452D01*
X392972D01*
G01X394013D02*
X394638Y688244D01*
G01X396905D02*
Y690744D01*
X396405Y690244D01*
G01Y688244D02*
X397405D01*
G01X399213Y690327D02*
X399463Y690577D01*
X399755Y690702D01*
X400088Y690744D01*
X400505Y690661D01*
X400797Y690452D01*
X400880Y690202D01*
X400838Y689952D01*
X400672Y689744D01*
X399838Y689327D01*
X399463Y689036D01*
X399213Y688619D01*
X399130Y688244D01*
X400880D01*
G01X403605D02*
Y690744D01*
X402063Y688952D01*
X404147D01*
G01X394055Y682644D02*
Y686644D01*
X386655D01*
G01X394817Y677867D02*
Y680367D01*
X395858D01*
X396192Y680242D01*
X396400Y680075D01*
X396483Y679742D01*
X396400Y679409D01*
X396150Y679200D01*
X395858Y679075D01*
X394817D01*
G01X395858D02*
X396483Y677867D01*
G01X398750D02*
Y680367D01*
X398250Y679867D01*
G01Y677867D02*
X399250D01*
G01X401058Y679950D02*
X401308Y680200D01*
X401600Y680325D01*
X401933Y680367D01*
X402350Y680284D01*
X402642Y680075D01*
X402725Y679825D01*
X402683Y679575D01*
X402517Y679367D01*
X401683Y678950D01*
X401308Y678659D01*
X401058Y678242D01*
X400975Y677867D01*
X402725D01*
G01X404033Y678367D02*
X404283Y678075D01*
X404617Y677909D01*
X404992Y677867D01*
X405325Y677909D01*
X405658Y678117D01*
X405867Y678367D01*
X405908Y678617D01*
X405825Y678909D01*
X405533Y679117D01*
X405242Y679200D01*
X404867D01*
G01X405242D02*
X405492Y679325D01*
X405700Y679534D01*
X405783Y679784D01*
X405700Y680034D01*
X405492Y680242D01*
X405117Y680367D01*
X404742Y680325D01*
X404367Y680159D01*
G01X391600Y675900D02*
Y679900D01*
X384200D01*
G01X353381Y667305D02*
X340381D01*
G01X375833Y708700D02*
Y706908D01*
X376000Y706533D01*
X376333Y706283D01*
X376750Y706200D01*
X377167Y706283D01*
X377500Y706533D01*
X377667Y706908D01*
Y708700D01*
G01X379850Y706200D02*
Y708700D01*
X379350Y708200D01*
G01Y706200D02*
X380350D01*
G01X382950Y708700D02*
X382617Y708617D01*
X382367Y708408D01*
X382200Y708158D01*
X382075Y707825D01*
X382033Y707450D01*
X382075Y707075D01*
X382200Y706742D01*
X382367Y706492D01*
X382617Y706283D01*
X382950Y706200D01*
X383283Y706283D01*
X383533Y706492D01*
X383700Y706742D01*
X383825Y707075D01*
X383867Y707450D01*
X383825Y707825D01*
X383700Y708158D01*
X383533Y708408D01*
X383283Y708617D01*
X382950Y708700D01*
G01X385258Y707242D02*
X385550Y707533D01*
X385800Y707700D01*
X386133Y707783D01*
X386425Y707700D01*
X386633Y707533D01*
X386800Y707283D01*
X386842Y706992D01*
X386800Y706742D01*
X386633Y706492D01*
X386383Y706283D01*
X386092Y706200D01*
X385758Y706283D01*
X385467Y706533D01*
X385300Y706908D01*
X385258Y707325D01*
X385342Y707867D01*
X385467Y708158D01*
X385675Y708450D01*
X385967Y708658D01*
X386258Y708700D01*
X386550Y708617D01*
X386758Y708408D01*
G01X374000Y705200D02*
Y713200D01*
G01Y699200D02*
Y705200D01*
G01Y699200D02*
Y713200D01*
G01X356000Y699200D02*
X374000D01*
G01X356000Y713200D02*
Y699200D01*
G01X374000Y713200D02*
X356000D01*
G01X440802Y18649D02*
X440552Y18774D01*
X440260Y18857D01*
X439927D01*
X439552Y18732D01*
X439260Y18524D01*
X439052Y18274D01*
X438885Y17857D01*
X438843Y17482D01*
X438927Y17107D01*
X439052Y16857D01*
X439302Y16607D01*
X439593Y16440D01*
X439885Y16357D01*
X440177D01*
X440468Y16440D01*
X440718Y16565D01*
X440927Y16732D01*
G01X442985Y16357D02*
Y18857D01*
X442485Y18357D01*
G01Y16357D02*
X443485D01*
G01X445168Y16857D02*
X445418Y16565D01*
X445752Y16399D01*
X446127Y16357D01*
X446460Y16399D01*
X446793Y16607D01*
X447002Y16857D01*
X447043Y17107D01*
X446960Y17399D01*
X446668Y17607D01*
X446377Y17690D01*
X446002D01*
G01X446377D02*
X446627Y17815D01*
X446835Y18024D01*
X446918Y18274D01*
X446835Y18524D01*
X446627Y18732D01*
X446252Y18857D01*
X445877Y18815D01*
X445502Y18649D01*
G01X449185Y16357D02*
Y18857D01*
X448685Y18357D01*
G01Y16357D02*
X449685D01*
G01X454718Y66661D02*
X454468Y66786D01*
X454176Y66869D01*
X453843D01*
X453468Y66744D01*
X453176Y66536D01*
X452968Y66286D01*
X452801Y65869D01*
X452759Y65494D01*
X452843Y65119D01*
X452968Y64869D01*
X453218Y64619D01*
X453509Y64452D01*
X453801Y64369D01*
X454093D01*
X454384Y64452D01*
X454634Y64577D01*
X454843Y64744D01*
G01X456901Y64369D02*
Y66869D01*
X456401Y66369D01*
G01Y64369D02*
X457401D01*
G01X459084Y64869D02*
X459334Y64577D01*
X459668Y64411D01*
X460043Y64369D01*
X460376Y64411D01*
X460709Y64619D01*
X460918Y64869D01*
X460959Y65119D01*
X460876Y65411D01*
X460584Y65619D01*
X460293Y65702D01*
X459918D01*
G01X460293D02*
X460543Y65827D01*
X460751Y66036D01*
X460834Y66286D01*
X460751Y66536D01*
X460543Y66744D01*
X460168Y66869D01*
X459793Y66827D01*
X459418Y66661D01*
G01X462184Y64869D02*
X462434Y64577D01*
X462768Y64411D01*
X463143Y64369D01*
X463476Y64411D01*
X463809Y64619D01*
X464018Y64869D01*
X464059Y65119D01*
X463976Y65411D01*
X463684Y65619D01*
X463393Y65702D01*
X463018D01*
G01X463393D02*
X463643Y65827D01*
X463851Y66036D01*
X463934Y66286D01*
X463851Y66536D01*
X463643Y66744D01*
X463268Y66869D01*
X462893Y66827D01*
X462518Y66661D01*
G01X422402Y61057D02*
Y63557D01*
X423443D01*
X423777Y63432D01*
X423985Y63265D01*
X424068Y62932D01*
X423985Y62599D01*
X423735Y62390D01*
X423443Y62265D01*
X422402D01*
G01X423443D02*
X424068Y61057D01*
G01X426835D02*
Y63557D01*
X425293Y61765D01*
X427377D01*
G01X428518Y61432D02*
X428768Y61224D01*
X429060Y61099D01*
X429435Y61057D01*
X429810Y61140D01*
X430102Y61307D01*
X430310Y61599D01*
X430352Y61932D01*
X430268Y62265D01*
X430060Y62474D01*
X429768Y62640D01*
X429477Y62682D01*
X429185Y62640D01*
X428810Y62474D01*
X428935Y63557D01*
X430060D01*
G01X433035Y61057D02*
Y63557D01*
X431493Y61765D01*
X433577D01*
G01X439585Y36057D02*
Y40057D01*
X432185D01*
G01X435017Y60667D02*
Y63167D01*
X436058D01*
X436392Y63042D01*
X436600Y62875D01*
X436683Y62542D01*
X436600Y62209D01*
X436350Y62000D01*
X436058Y61875D01*
X435017D01*
G01X436058D02*
X436683Y60667D01*
G01X439450D02*
Y63167D01*
X437908Y61375D01*
X439992D01*
G01X441258Y61709D02*
X441550Y62000D01*
X441800Y62167D01*
X442133Y62250D01*
X442425Y62167D01*
X442633Y62000D01*
X442800Y61750D01*
X442842Y61459D01*
X442800Y61209D01*
X442633Y60959D01*
X442383Y60750D01*
X442092Y60667D01*
X441758Y60750D01*
X441467Y61000D01*
X441300Y61375D01*
X441258Y61792D01*
X441342Y62334D01*
X441467Y62625D01*
X441675Y62917D01*
X441967Y63125D01*
X442258Y63167D01*
X442550Y63084D01*
X442758Y62875D01*
G01X444358Y62750D02*
X444608Y63000D01*
X444900Y63125D01*
X445233Y63167D01*
X445650Y63084D01*
X445942Y62875D01*
X446025Y62625D01*
X445983Y62375D01*
X445817Y62167D01*
X444983Y61750D01*
X444608Y61459D01*
X444358Y61042D01*
X444275Y60667D01*
X446025D01*
G01X448016Y36147D02*
Y40147D01*
X440616D01*
G01X442481Y54947D02*
Y58947D01*
X435081D01*
G01X439102Y12457D02*
Y14957D01*
X440143D01*
X440477Y14832D01*
X440685Y14665D01*
X440768Y14332D01*
X440685Y13999D01*
X440435Y13790D01*
X440143Y13665D01*
X439102D01*
G01X440143D02*
X440768Y12457D01*
G01X443535D02*
Y14957D01*
X441993Y13165D01*
X444077D01*
G01X445218Y12832D02*
X445468Y12624D01*
X445760Y12499D01*
X446135Y12457D01*
X446510Y12540D01*
X446802Y12707D01*
X447010Y12999D01*
X447052Y13332D01*
X446968Y13665D01*
X446760Y13874D01*
X446468Y14040D01*
X446177Y14082D01*
X445885Y14040D01*
X445510Y13874D01*
X445635Y14957D01*
X446760D01*
G01X448527Y12749D02*
X448818Y12540D01*
X449152Y12457D01*
X449485Y12540D01*
X449777Y12790D01*
X449985Y13165D01*
X450068Y13540D01*
Y13999D01*
X449985Y14374D01*
X449777Y14707D01*
X449527Y14874D01*
X449235Y14957D01*
X448902Y14874D01*
X448652Y14707D01*
X448485Y14457D01*
X448402Y14124D01*
X448485Y13832D01*
X448693Y13540D01*
X448943Y13374D01*
X449235Y13332D01*
X449568Y13415D01*
X449818Y13624D01*
X450068Y13999D01*
G01X448085Y28457D02*
Y32457D01*
X440685D01*
G01X439102Y8157D02*
Y10657D01*
X440143D01*
X440477Y10532D01*
X440685Y10365D01*
X440768Y10032D01*
X440685Y9699D01*
X440435Y9490D01*
X440143Y9365D01*
X439102D01*
G01X440143D02*
X440768Y8157D01*
G01X443535D02*
Y10657D01*
X441993Y8865D01*
X444077D01*
G01X445343Y9199D02*
X445635Y9490D01*
X445885Y9657D01*
X446218Y9740D01*
X446510Y9657D01*
X446718Y9490D01*
X446885Y9240D01*
X446927Y8949D01*
X446885Y8699D01*
X446718Y8449D01*
X446468Y8240D01*
X446177Y8157D01*
X445843Y8240D01*
X445552Y8490D01*
X445385Y8865D01*
X445343Y9282D01*
X445427Y9824D01*
X445552Y10115D01*
X445760Y10407D01*
X446052Y10615D01*
X446343Y10657D01*
X446635Y10574D01*
X446843Y10365D01*
G01X449235Y10657D02*
X448902Y10574D01*
X448652Y10365D01*
X448485Y10115D01*
X448360Y9782D01*
X448318Y9407D01*
X448360Y9032D01*
X448485Y8699D01*
X448652Y8449D01*
X448902Y8240D01*
X449235Y8157D01*
X449568Y8240D01*
X449818Y8449D01*
X449985Y8699D01*
X450110Y9032D01*
X450152Y9407D01*
X450110Y9782D01*
X449985Y10115D01*
X449818Y10365D01*
X449568Y10574D01*
X449235Y10657D01*
G01X448085Y24157D02*
Y28157D01*
X440685D01*
G01X439002Y3957D02*
Y6457D01*
X440043D01*
X440377Y6332D01*
X440585Y6165D01*
X440668Y5832D01*
X440585Y5499D01*
X440335Y5290D01*
X440043Y5165D01*
X439002D01*
G01X440043D02*
X440668Y3957D01*
G01X443435D02*
Y6457D01*
X441893Y4665D01*
X443977D01*
G01X445118Y4332D02*
X445368Y4124D01*
X445660Y3999D01*
X446035Y3957D01*
X446410Y4040D01*
X446702Y4207D01*
X446910Y4499D01*
X446952Y4832D01*
X446868Y5165D01*
X446660Y5374D01*
X446368Y5540D01*
X446077Y5582D01*
X445785Y5540D01*
X445410Y5374D01*
X445535Y6457D01*
X446660D01*
G01X448343Y4999D02*
X448635Y5290D01*
X448885Y5457D01*
X449218Y5540D01*
X449510Y5457D01*
X449718Y5290D01*
X449885Y5040D01*
X449927Y4749D01*
X449885Y4499D01*
X449718Y4249D01*
X449468Y4040D01*
X449177Y3957D01*
X448843Y4040D01*
X448552Y4290D01*
X448385Y4665D01*
X448343Y5082D01*
X448427Y5624D01*
X448552Y5915D01*
X448760Y6207D01*
X449052Y6415D01*
X449343Y6457D01*
X449635Y6374D01*
X449843Y6165D01*
G01X447985Y19957D02*
Y23957D01*
X440585D01*
G01X474500Y67900D02*
X470500D01*
Y60500D01*
G01X470200Y68000D02*
X466200D01*
Y60600D01*
G01X465200Y61100D02*
X461200D01*
Y53700D01*
G01X425567Y67949D02*
X425317Y68074D01*
X425025Y68157D01*
X424692D01*
X424317Y68032D01*
X424025Y67824D01*
X423817Y67574D01*
X423650Y67157D01*
X423608Y66782D01*
X423692Y66407D01*
X423817Y66157D01*
X424067Y65907D01*
X424358Y65740D01*
X424650Y65657D01*
X424942D01*
X425233Y65740D01*
X425483Y65865D01*
X425692Y66032D01*
G01X427750Y65657D02*
Y68157D01*
X427250Y67657D01*
G01Y65657D02*
X428250D01*
G01X431350D02*
Y68157D01*
X429808Y66365D01*
X431892D01*
G01X433950Y65657D02*
X434242Y65699D01*
X434575Y65824D01*
X434783Y66032D01*
X434867Y66324D01*
X434783Y66615D01*
X434533Y66865D01*
X434158Y66990D01*
X433742D01*
X433492Y67074D01*
X433283Y67282D01*
X433200Y67574D01*
X433325Y67865D01*
X433617Y68074D01*
X433950Y68157D01*
X434283Y68074D01*
X434575Y67865D01*
X434700Y67574D01*
X434617Y67282D01*
X434408Y67074D01*
X434158Y66990D01*
X433742D01*
X433367Y66865D01*
X433117Y66615D01*
X433033Y66324D01*
X433117Y66032D01*
X433325Y65824D01*
X433658Y65699D01*
X433950Y65657D01*
G01X463983Y18667D02*
Y16875D01*
X464150Y16500D01*
X464483Y16250D01*
X464900Y16167D01*
X465317Y16250D01*
X465650Y16500D01*
X465817Y16875D01*
Y18667D01*
G01X467083Y16667D02*
X467333Y16375D01*
X467667Y16209D01*
X468042Y16167D01*
X468375Y16209D01*
X468708Y16417D01*
X468917Y16667D01*
X468958Y16917D01*
X468875Y17209D01*
X468583Y17417D01*
X468292Y17500D01*
X467917D01*
G01X468292D02*
X468542Y17625D01*
X468750Y17834D01*
X468833Y18084D01*
X468750Y18334D01*
X468542Y18542D01*
X468167Y18667D01*
X467792Y18625D01*
X467417Y18459D01*
G01X470183Y16542D02*
X470433Y16334D01*
X470725Y16209D01*
X471100Y16167D01*
X471475Y16250D01*
X471767Y16417D01*
X471975Y16709D01*
X472017Y17042D01*
X471933Y17375D01*
X471725Y17584D01*
X471433Y17750D01*
X471142Y17792D01*
X470850Y17750D01*
X470475Y17584D01*
X470600Y18667D01*
X471725D01*
G01X453050Y34413D02*
X455050D01*
G01X463080Y19450D02*
Y22450D01*
G01X465048Y51350D02*
Y48350D01*
G01X459150Y21550D02*
X454150D01*
Y26550D01*
G01X442722Y48015D02*
X446722D01*
Y55415D01*
G01X439599Y66017D02*
X437099D01*
Y67058D01*
X437224Y67392D01*
X437391Y67600D01*
X437724Y67683D01*
X438057Y67600D01*
X438266Y67350D01*
X438391Y67058D01*
Y66017D01*
G01Y67058D02*
X439599Y67683D01*
G01Y70450D02*
X437099D01*
X438891Y68908D01*
Y70992D01*
G01X439224Y72133D02*
X439432Y72383D01*
X439557Y72675D01*
X439599Y73050D01*
X439516Y73425D01*
X439349Y73717D01*
X439057Y73925D01*
X438724Y73967D01*
X438391Y73883D01*
X438182Y73675D01*
X438016Y73383D01*
X437974Y73092D01*
X438016Y72800D01*
X438182Y72425D01*
X437099Y72550D01*
Y73675D01*
G01X439099Y75233D02*
X439391Y75483D01*
X439557Y75817D01*
X439599Y76192D01*
X439557Y76525D01*
X439349Y76858D01*
X439099Y77067D01*
X438849Y77108D01*
X438557Y77025D01*
X438349Y76733D01*
X438266Y76442D01*
Y76067D01*
G01Y76442D02*
X438141Y76692D01*
X437932Y76900D01*
X437682Y76983D01*
X437432Y76900D01*
X437224Y76692D01*
X437099Y76317D01*
X437141Y75942D01*
X437307Y75567D01*
G01X446754Y47801D02*
X442754D01*
Y40401D01*
G01X424298Y79947D02*
Y82447D01*
X425339D01*
X425673Y82322D01*
X425881Y82155D01*
X425964Y81822D01*
X425881Y81489D01*
X425631Y81280D01*
X425339Y81155D01*
X424298D01*
G01X425339D02*
X425964Y79947D01*
G01X428731D02*
Y82447D01*
X427189Y80655D01*
X429273D01*
G01X430414Y80322D02*
X430664Y80114D01*
X430956Y79989D01*
X431331Y79947D01*
X431706Y80030D01*
X431998Y80197D01*
X432206Y80489D01*
X432248Y80822D01*
X432164Y81155D01*
X431956Y81364D01*
X431664Y81530D01*
X431373Y81572D01*
X431081Y81530D01*
X430706Y81364D01*
X430831Y82447D01*
X431956D01*
G01X434431Y79947D02*
X434723Y79989D01*
X435056Y80114D01*
X435264Y80322D01*
X435348Y80614D01*
X435264Y80905D01*
X435014Y81155D01*
X434639Y81280D01*
X434223D01*
X433973Y81364D01*
X433764Y81572D01*
X433681Y81864D01*
X433806Y82155D01*
X434098Y82364D01*
X434431Y82447D01*
X434764Y82364D01*
X435056Y82155D01*
X435181Y81864D01*
X435098Y81572D01*
X434889Y81364D01*
X434639Y81280D01*
X434223D01*
X433848Y81155D01*
X433598Y80905D01*
X433514Y80614D01*
X433598Y80322D01*
X433806Y80114D01*
X434139Y79989D01*
X434431Y79947D01*
G01X473300Y73417D02*
X470800D01*
Y74458D01*
X470925Y74792D01*
X471092Y75000D01*
X471425Y75083D01*
X471758Y75000D01*
X471967Y74750D01*
X472092Y74458D01*
Y73417D01*
G01Y74458D02*
X473300Y75083D01*
G01Y77850D02*
X470800D01*
X472592Y76308D01*
Y78392D01*
G01X473300Y80950D02*
X470800D01*
X472592Y79408D01*
Y81492D01*
G01X473300Y83550D02*
X470800D01*
X471300Y83050D01*
G01X473300D02*
Y84050D01*
G01X469000Y73517D02*
X466500D01*
Y74558D01*
X466625Y74892D01*
X466792Y75100D01*
X467125Y75183D01*
X467458Y75100D01*
X467667Y74850D01*
X467792Y74558D01*
Y73517D01*
G01Y74558D02*
X469000Y75183D01*
G01Y77950D02*
X466500D01*
X468292Y76408D01*
Y78492D01*
G01X469000Y81050D02*
X466500D01*
X468292Y79508D01*
Y81592D01*
G01X466500Y83650D02*
X466583Y83317D01*
X466792Y83067D01*
X467042Y82900D01*
X467375Y82775D01*
X467750Y82733D01*
X468125Y82775D01*
X468458Y82900D01*
X468708Y83067D01*
X468917Y83317D01*
X469000Y83650D01*
X468917Y83983D01*
X468708Y84233D01*
X468458Y84400D01*
X468125Y84525D01*
X467750Y84567D01*
X467375Y84525D01*
X467042Y84400D01*
X466792Y84233D01*
X466583Y83983D01*
X466500Y83650D01*
G01X456534Y69917D02*
X454034D01*
Y70958D01*
X454159Y71292D01*
X454326Y71500D01*
X454659Y71583D01*
X454992Y71500D01*
X455201Y71250D01*
X455326Y70958D01*
Y69917D01*
G01Y70958D02*
X456534Y71583D01*
G01Y74350D02*
X454034D01*
X455826Y72808D01*
Y74892D01*
G01X456034Y76033D02*
X456326Y76283D01*
X456492Y76617D01*
X456534Y76992D01*
X456492Y77325D01*
X456284Y77658D01*
X456034Y77867D01*
X455784Y77908D01*
X455492Y77825D01*
X455284Y77533D01*
X455201Y77242D01*
Y76867D01*
G01Y77242D02*
X455076Y77492D01*
X454867Y77700D01*
X454617Y77783D01*
X454367Y77700D01*
X454159Y77492D01*
X454034Y77117D01*
X454076Y76742D01*
X454242Y76367D01*
G01X456534Y80050D02*
X454034D01*
X454534Y79550D01*
G01X456534D02*
Y80550D01*
G01X425567Y77749D02*
X425317Y77874D01*
X425025Y77957D01*
X424692D01*
X424317Y77832D01*
X424025Y77624D01*
X423817Y77374D01*
X423650Y76957D01*
X423608Y76582D01*
X423692Y76207D01*
X423817Y75957D01*
X424067Y75707D01*
X424358Y75540D01*
X424650Y75457D01*
X424942D01*
X425233Y75540D01*
X425483Y75665D01*
X425692Y75832D01*
G01X427750Y75457D02*
Y77957D01*
X427250Y77457D01*
G01Y75457D02*
X428250D01*
G01X431350D02*
Y77957D01*
X429808Y76165D01*
X431892D01*
G01X433242Y75749D02*
X433533Y75540D01*
X433867Y75457D01*
X434200Y75540D01*
X434492Y75790D01*
X434700Y76165D01*
X434783Y76540D01*
Y76999D01*
X434700Y77374D01*
X434492Y77707D01*
X434242Y77874D01*
X433950Y77957D01*
X433617Y77874D01*
X433367Y77707D01*
X433200Y77457D01*
X433117Y77124D01*
X433200Y76832D01*
X433408Y76540D01*
X433658Y76374D01*
X433950Y76332D01*
X434283Y76415D01*
X434533Y76624D01*
X434783Y76999D01*
G01X448042Y71067D02*
X447917Y70817D01*
X447834Y70525D01*
Y70192D01*
X447959Y69817D01*
X448167Y69525D01*
X448417Y69317D01*
X448834Y69150D01*
X449209Y69108D01*
X449584Y69192D01*
X449834Y69317D01*
X450084Y69567D01*
X450251Y69858D01*
X450334Y70150D01*
Y70442D01*
X450251Y70733D01*
X450126Y70983D01*
X449959Y71192D01*
G01X450334Y73250D02*
X447834D01*
X448334Y72750D01*
G01X450334D02*
Y73750D01*
G01X448251Y75558D02*
X448001Y75808D01*
X447876Y76100D01*
X447834Y76433D01*
X447917Y76850D01*
X448126Y77142D01*
X448376Y77225D01*
X448626Y77183D01*
X448834Y77017D01*
X449251Y76183D01*
X449542Y75808D01*
X449959Y75558D01*
X450334Y75475D01*
Y77225D01*
G01Y79450D02*
X450292Y79742D01*
X450167Y80075D01*
X449959Y80283D01*
X449667Y80367D01*
X449376Y80283D01*
X449126Y80033D01*
X449001Y79658D01*
Y79242D01*
X448917Y78992D01*
X448709Y78783D01*
X448417Y78700D01*
X448126Y78825D01*
X447917Y79117D01*
X447834Y79450D01*
X447917Y79783D01*
X448126Y80075D01*
X448417Y80200D01*
X448709Y80117D01*
X448917Y79908D01*
X449001Y79658D01*
Y79242D01*
X449126Y78867D01*
X449376Y78617D01*
X449667Y78533D01*
X449959Y78617D01*
X450167Y78825D01*
X450292Y79158D01*
X450334Y79450D01*
G01X425567Y72849D02*
X425317Y72974D01*
X425025Y73057D01*
X424692D01*
X424317Y72932D01*
X424025Y72724D01*
X423817Y72474D01*
X423650Y72057D01*
X423608Y71682D01*
X423692Y71307D01*
X423817Y71057D01*
X424067Y70807D01*
X424358Y70640D01*
X424650Y70557D01*
X424942D01*
X425233Y70640D01*
X425483Y70765D01*
X425692Y70932D01*
G01X427750Y70557D02*
Y73057D01*
X427250Y72557D01*
G01Y70557D02*
X428250D01*
G01X431350D02*
Y73057D01*
X429808Y71265D01*
X431892D01*
G01X433867Y70557D02*
X433950Y71099D01*
X434075Y71557D01*
X434242Y71974D01*
X434450Y72432D01*
X434783Y73057D01*
X433117D01*
G01X509232Y117921D02*
Y113921D01*
X507632D01*
X507099Y114121D01*
X506699Y114588D01*
X506566Y115121D01*
X506699Y115654D01*
X507032Y116054D01*
X507632Y116254D01*
X509232D01*
G01X504232Y117921D02*
Y115254D01*
G01Y115788D02*
X503899Y115521D01*
X503566Y115321D01*
X503099Y115254D01*
X502766Y115321D01*
X502366Y115521D01*
G01X499699Y116121D02*
X497566D01*
X497766Y115654D01*
X498099Y115388D01*
X498566Y115254D01*
X499032Y115321D01*
X499432Y115521D01*
X499699Y115988D01*
X499832Y116388D01*
Y116788D01*
X499699Y117188D01*
X499366Y117588D01*
X498966Y117854D01*
X498499Y117921D01*
X498032Y117788D01*
X497566Y117388D01*
G01X495099Y117454D02*
X494766Y117721D01*
X494299Y117921D01*
X493899D01*
X493499Y117788D01*
X493232Y117588D01*
X493099Y117321D01*
X493166Y116921D01*
X493432Y116721D01*
X494632Y116321D01*
X494899Y115854D01*
X494766Y115521D01*
X494499Y115321D01*
X494099Y115254D01*
X493699Y115321D01*
X493299Y115521D01*
G01X490499Y117454D02*
X490166Y117721D01*
X489699Y117921D01*
X489299D01*
X488899Y117788D01*
X488632Y117588D01*
X488499Y117321D01*
X488566Y116921D01*
X488832Y116721D01*
X490032Y116321D01*
X490299Y115854D01*
X490166Y115521D01*
X489899Y115321D01*
X489499Y115254D01*
X489099Y115321D01*
X488699Y115521D01*
G01X481566Y117921D02*
Y113921D01*
X479032D01*
G01X479966Y115854D02*
X481566D01*
G01X475699Y115254D02*
Y117921D01*
G01Y114188D02*
X475832Y114121D01*
Y113988D01*
X475699Y113921D01*
X475566Y113988D01*
Y114121D01*
X475699Y114188D01*
G01X471099Y113921D02*
Y117921D01*
G01X472032Y115254D02*
X470166D01*
G01X416299Y188977D02*
X559999D01*
Y112116D01*
X416299D01*
Y188977D01*
G01X443600Y72917D02*
X441100D01*
Y73958D01*
X441225Y74292D01*
X441392Y74500D01*
X441725Y74583D01*
X442058Y74500D01*
X442267Y74250D01*
X442392Y73958D01*
Y72917D01*
G01Y73958D02*
X443600Y74583D01*
G01Y77350D02*
X441100D01*
X442892Y75808D01*
Y77892D01*
G01X443225Y79033D02*
X443433Y79283D01*
X443558Y79575D01*
X443600Y79950D01*
X443517Y80325D01*
X443350Y80617D01*
X443058Y80825D01*
X442725Y80867D01*
X442392Y80783D01*
X442183Y80575D01*
X442017Y80283D01*
X441975Y79992D01*
X442017Y79700D01*
X442183Y79325D01*
X441100Y79450D01*
Y80575D01*
G01X443600Y82967D02*
X443058Y83050D01*
X442600Y83175D01*
X442183Y83342D01*
X441725Y83550D01*
X441100Y83883D01*
Y82217D01*
G01X407442Y145417D02*
X407317Y145167D01*
X407234Y144875D01*
Y144542D01*
X407359Y144167D01*
X407567Y143875D01*
X407817Y143667D01*
X408234Y143500D01*
X408609Y143458D01*
X408984Y143542D01*
X409234Y143667D01*
X409484Y143917D01*
X409651Y144208D01*
X409734Y144500D01*
Y144792D01*
X409651Y145083D01*
X409526Y145333D01*
X409359Y145542D01*
G01X409734Y146642D02*
X407234D01*
X409734Y148558D01*
X407234D01*
G01X409734Y150700D02*
X407234D01*
X407734Y150200D01*
G01X409734D02*
Y151200D01*
G01X455545Y758540D02*
Y762540D01*
X454745Y761740D01*
G01Y758540D02*
X456345D01*
G01X511342Y54967D02*
X511217Y54717D01*
X511134Y54425D01*
Y54092D01*
X511259Y53717D01*
X511467Y53425D01*
X511717Y53217D01*
X512134Y53050D01*
X512509Y53008D01*
X512884Y53092D01*
X513134Y53217D01*
X513384Y53467D01*
X513551Y53758D01*
X513634Y54050D01*
Y54342D01*
X513551Y54633D01*
X513426Y54883D01*
X513259Y55092D01*
G01X513634Y57150D02*
X511134D01*
X511634Y56650D01*
G01X513634D02*
Y57650D01*
G01X513134Y59333D02*
X513426Y59583D01*
X513592Y59917D01*
X513634Y60292D01*
X513592Y60625D01*
X513384Y60958D01*
X513134Y61167D01*
X512884Y61208D01*
X512592Y61125D01*
X512384Y60833D01*
X512301Y60542D01*
Y60167D01*
G01Y60542D02*
X512176Y60792D01*
X511967Y61000D01*
X511717Y61083D01*
X511467Y61000D01*
X511259Y60792D01*
X511134Y60417D01*
X511176Y60042D01*
X511342Y59667D01*
G01X513634Y63850D02*
X511134D01*
X512926Y62308D01*
Y64392D01*
G01X484600Y51100D02*
Y47100D01*
X492000D01*
G01X487517Y16500D02*
Y19000D01*
X488558D01*
X488892Y18875D01*
X489100Y18708D01*
X489183Y18375D01*
X489100Y18042D01*
X488850Y17833D01*
X488558Y17708D01*
X487517D01*
G01X488558D02*
X489183Y16500D01*
G01X491950D02*
Y19000D01*
X490408Y17208D01*
X492492D01*
G01X493633Y17000D02*
X493883Y16708D01*
X494217Y16542D01*
X494592Y16500D01*
X494925Y16542D01*
X495258Y16750D01*
X495467Y17000D01*
X495508Y17250D01*
X495425Y17542D01*
X495133Y17750D01*
X494842Y17833D01*
X494467D01*
G01X494842D02*
X495092Y17958D01*
X495300Y18167D01*
X495383Y18417D01*
X495300Y18667D01*
X495092Y18875D01*
X494717Y19000D01*
X494342Y18958D01*
X493967Y18792D01*
G01X496733Y16875D02*
X496983Y16667D01*
X497275Y16542D01*
X497650Y16500D01*
X498025Y16583D01*
X498317Y16750D01*
X498525Y17042D01*
X498567Y17375D01*
X498483Y17708D01*
X498275Y17917D01*
X497983Y18083D01*
X497692Y18125D01*
X497400Y18083D01*
X497025Y17917D01*
X497150Y19000D01*
X498275D01*
G01X487800Y36000D02*
Y32000D01*
X495200D01*
G01X487517Y12500D02*
Y15000D01*
X488558D01*
X488892Y14875D01*
X489100Y14708D01*
X489183Y14375D01*
X489100Y14042D01*
X488850Y13833D01*
X488558Y13708D01*
X487517D01*
G01X488558D02*
X489183Y12500D01*
G01X491950D02*
Y15000D01*
X490408Y13208D01*
X492492D01*
G01X493633Y13000D02*
X493883Y12708D01*
X494217Y12542D01*
X494592Y12500D01*
X494925Y12542D01*
X495258Y12750D01*
X495467Y13000D01*
X495508Y13250D01*
X495425Y13542D01*
X495133Y13750D01*
X494842Y13833D01*
X494467D01*
G01X494842D02*
X495092Y13958D01*
X495300Y14167D01*
X495383Y14417D01*
X495300Y14667D01*
X495092Y14875D01*
X494717Y15000D01*
X494342Y14958D01*
X493967Y14792D01*
G01X497650Y12500D02*
X497942Y12542D01*
X498275Y12667D01*
X498483Y12875D01*
X498567Y13167D01*
X498483Y13458D01*
X498233Y13708D01*
X497858Y13833D01*
X497442D01*
X497192Y13917D01*
X496983Y14125D01*
X496900Y14417D01*
X497025Y14708D01*
X497317Y14917D01*
X497650Y15000D01*
X497983Y14917D01*
X498275Y14708D01*
X498400Y14417D01*
X498317Y14125D01*
X498108Y13917D01*
X497858Y13833D01*
X497442D01*
X497067Y13708D01*
X496817Y13458D01*
X496733Y13167D01*
X496817Y12875D01*
X497025Y12667D01*
X497358Y12542D01*
X497650Y12500D01*
G01X495200Y28000D02*
Y32000D01*
X487800D01*
G01X487517Y4500D02*
Y7000D01*
X488558D01*
X488892Y6875D01*
X489100Y6708D01*
X489183Y6375D01*
X489100Y6042D01*
X488850Y5833D01*
X488558Y5708D01*
X487517D01*
G01X488558D02*
X489183Y4500D01*
G01X491367D02*
X491450Y5042D01*
X491575Y5500D01*
X491742Y5917D01*
X491950Y6375D01*
X492283Y7000D01*
X490617D01*
G01X494550Y4500D02*
Y7000D01*
X494050Y6500D01*
G01Y4500D02*
X495050D01*
G01X496858Y6583D02*
X497108Y6833D01*
X497400Y6958D01*
X497733Y7000D01*
X498150Y6917D01*
X498442Y6708D01*
X498525Y6458D01*
X498483Y6208D01*
X498317Y6000D01*
X497483Y5583D01*
X497108Y5292D01*
X496858Y4875D01*
X496775Y4500D01*
X498525D01*
G01X495200Y20000D02*
Y24000D01*
X487800D01*
G01X487517Y8500D02*
Y11000D01*
X488558D01*
X488892Y10875D01*
X489100Y10708D01*
X489183Y10375D01*
X489100Y10042D01*
X488850Y9833D01*
X488558Y9708D01*
X487517D01*
G01X488558D02*
X489183Y8500D01*
G01X491367D02*
X491450Y9042D01*
X491575Y9500D01*
X491742Y9917D01*
X491950Y10375D01*
X492283Y11000D01*
X490617D01*
G01X494550Y8500D02*
Y11000D01*
X494050Y10500D01*
G01Y8500D02*
X495050D01*
G01X497650D02*
Y11000D01*
X497150Y10500D01*
G01Y8500D02*
X498150D01*
G01X495200Y24000D02*
Y28000D01*
X487800D01*
G01X480400Y69973D02*
Y65973D01*
X487800D01*
G01X480525Y60850D02*
Y56850D01*
X487925D01*
G01X530900Y47400D02*
Y51400D01*
X523500D01*
G01X530900Y51600D02*
Y55600D01*
X523500D01*
G01X508022Y4010D02*
X505522D01*
Y5051D01*
X505647Y5385D01*
X505814Y5593D01*
X506147Y5676D01*
X506480Y5593D01*
X506689Y5343D01*
X506814Y5051D01*
Y4010D01*
G01Y5051D02*
X508022Y5676D01*
G01Y8443D02*
X505522D01*
X507314Y6901D01*
Y8985D01*
G01X507647Y10126D02*
X507855Y10376D01*
X507980Y10668D01*
X508022Y11043D01*
X507939Y11418D01*
X507772Y11710D01*
X507480Y11918D01*
X507147Y11960D01*
X506814Y11876D01*
X506605Y11668D01*
X506439Y11376D01*
X506397Y11085D01*
X506439Y10793D01*
X506605Y10418D01*
X505522Y10543D01*
Y11668D01*
G01X507647Y13226D02*
X507855Y13476D01*
X507980Y13768D01*
X508022Y14143D01*
X507939Y14518D01*
X507772Y14810D01*
X507480Y15018D01*
X507147Y15060D01*
X506814Y14976D01*
X506605Y14768D01*
X506439Y14476D01*
X506397Y14185D01*
X506439Y13893D01*
X506605Y13518D01*
X505522Y13643D01*
Y14768D01*
G01X501030Y5760D02*
X500905Y5510D01*
X500822Y5218D01*
Y4885D01*
X500947Y4510D01*
X501155Y4218D01*
X501405Y4010D01*
X501822Y3843D01*
X502197Y3801D01*
X502572Y3885D01*
X502822Y4010D01*
X503072Y4260D01*
X503239Y4551D01*
X503322Y4843D01*
Y5135D01*
X503239Y5426D01*
X503114Y5676D01*
X502947Y5885D01*
G01X503322Y7943D02*
X500822D01*
X501322Y7443D01*
G01X503322D02*
Y8443D01*
G01Y11543D02*
X500822D01*
X502614Y10001D01*
Y12085D01*
G01X502280Y13351D02*
X501989Y13643D01*
X501822Y13893D01*
X501739Y14226D01*
X501822Y14518D01*
X501989Y14726D01*
X502239Y14893D01*
X502530Y14935D01*
X502780Y14893D01*
X503030Y14726D01*
X503239Y14476D01*
X503322Y14185D01*
X503239Y13851D01*
X502989Y13560D01*
X502614Y13393D01*
X502197Y13351D01*
X501655Y13435D01*
X501364Y13560D01*
X501072Y13768D01*
X500864Y14060D01*
X500822Y14351D01*
X500905Y14643D01*
X501114Y14851D01*
G01X511734Y13440D02*
Y15940D01*
X512775D01*
X513109Y15815D01*
X513317Y15648D01*
X513400Y15315D01*
X513317Y14982D01*
X513067Y14773D01*
X512775Y14648D01*
X511734D01*
G01X512775D02*
X513400Y13440D01*
G01X516167D02*
Y15940D01*
X514625Y14148D01*
X516709D01*
G01X517850Y13815D02*
X518100Y13607D01*
X518392Y13482D01*
X518767Y13440D01*
X519142Y13523D01*
X519434Y13690D01*
X519642Y13982D01*
X519684Y14315D01*
X519600Y14648D01*
X519392Y14857D01*
X519100Y15023D01*
X518809Y15065D01*
X518517Y15023D01*
X518142Y14857D01*
X518267Y15940D01*
X519392D01*
G01X521867D02*
X521534Y15857D01*
X521284Y15648D01*
X521117Y15398D01*
X520992Y15065D01*
X520950Y14690D01*
X520992Y14315D01*
X521117Y13982D01*
X521284Y13732D01*
X521534Y13523D01*
X521867Y13440D01*
X522200Y13523D01*
X522450Y13732D01*
X522617Y13982D01*
X522742Y14315D01*
X522784Y14690D01*
X522742Y15065D01*
X522617Y15398D01*
X522450Y15648D01*
X522200Y15857D01*
X521867Y15940D01*
G01X523357Y21944D02*
X518157D01*
G01X523357Y28944D02*
X515557D01*
G01X523357Y21944D02*
Y28944D01*
G01X509957Y21944D02*
X518657D01*
G01X509957Y28944D02*
Y21944D01*
G01X516357Y28944D02*
X509957D01*
G01X499637Y28677D02*
X497137D01*
Y29718D01*
X497262Y30052D01*
X497429Y30260D01*
X497762Y30343D01*
X498095Y30260D01*
X498304Y30010D01*
X498429Y29718D01*
Y28677D01*
G01Y29718D02*
X499637Y30343D01*
G01Y32527D02*
X499095Y32610D01*
X498637Y32735D01*
X498220Y32902D01*
X497762Y33110D01*
X497137Y33443D01*
Y31777D01*
G01Y35710D02*
X497220Y35377D01*
X497429Y35127D01*
X497679Y34960D01*
X498012Y34835D01*
X498387Y34793D01*
X498762Y34835D01*
X499095Y34960D01*
X499345Y35127D01*
X499554Y35377D01*
X499637Y35710D01*
X499554Y36043D01*
X499345Y36293D01*
X499095Y36460D01*
X498762Y36585D01*
X498387Y36627D01*
X498012Y36585D01*
X497679Y36460D01*
X497429Y36293D01*
X497220Y36043D01*
X497137Y35710D01*
G01X499345Y38102D02*
X499554Y38393D01*
X499637Y38727D01*
X499554Y39060D01*
X499304Y39352D01*
X498929Y39560D01*
X498554Y39643D01*
X498095D01*
X497720Y39560D01*
X497387Y39352D01*
X497220Y39102D01*
X497137Y38810D01*
X497220Y38477D01*
X497387Y38227D01*
X497637Y38060D01*
X497970Y37977D01*
X498262Y38060D01*
X498554Y38268D01*
X498720Y38518D01*
X498762Y38810D01*
X498679Y39143D01*
X498470Y39393D01*
X498095Y39643D01*
G01X500849Y37952D02*
X506049D01*
G01X500849Y30952D02*
X508649D01*
G01X500849Y37952D02*
Y30952D01*
G01X514249Y37952D02*
X505549D01*
G01X514249Y30952D02*
Y37952D01*
G01X507849Y30952D02*
X514249D01*
G01X498966Y47452D02*
Y49952D01*
X500007D01*
X500341Y49827D01*
X500549Y49660D01*
X500632Y49327D01*
X500549Y48994D01*
X500299Y48785D01*
X500007Y48660D01*
X498966D01*
G01X500007D02*
X500632Y47452D01*
G01X502816D02*
X502899Y47994D01*
X503024Y48452D01*
X503191Y48869D01*
X503399Y49327D01*
X503732Y49952D01*
X502066D01*
G01X505999Y47452D02*
Y49952D01*
X505499Y49452D01*
G01Y47452D02*
X506499D01*
G01X509099Y49952D02*
X508766Y49869D01*
X508516Y49660D01*
X508349Y49410D01*
X508224Y49077D01*
X508182Y48702D01*
X508224Y48327D01*
X508349Y47994D01*
X508516Y47744D01*
X508766Y47535D01*
X509099Y47452D01*
X509432Y47535D01*
X509682Y47744D01*
X509849Y47994D01*
X509974Y48327D01*
X510016Y48702D01*
X509974Y49077D01*
X509849Y49410D01*
X509682Y49660D01*
X509432Y49869D01*
X509099Y49952D01*
G01X514249Y38752D02*
X509049D01*
G01X514249Y45752D02*
X506449D01*
G01X514249Y38752D02*
Y45752D01*
G01X500849Y38752D02*
X509549D01*
G01X500849Y45752D02*
Y38752D01*
G01X507249Y45752D02*
X500849D01*
G01X488490Y57170D02*
X502490D01*
G01X488490Y70170D02*
Y57170D01*
G01X502490D02*
Y70170D01*
G01X483950Y34413D02*
X480950D01*
G01X474888Y50350D02*
Y48350D01*
G01X472920Y20450D02*
Y22450D01*
G01X476850Y49250D02*
X481850D01*
Y44250D01*
G01X476850Y21550D02*
X481850D01*
Y26550D01*
G01X534495Y59528D02*
Y62028D01*
X535536D01*
X535870Y61903D01*
X536078Y61736D01*
X536161Y61403D01*
X536078Y61070D01*
X535828Y60861D01*
X535536Y60736D01*
X534495D01*
G01X535536D02*
X536161Y59528D01*
G01X538928D02*
Y62028D01*
X537386Y60236D01*
X539470D01*
G01X542028Y59528D02*
Y62028D01*
X540486Y60236D01*
X542570D01*
G01X545128Y59528D02*
Y62028D01*
X543586Y60236D01*
X545670D01*
G01X548050Y58100D02*
Y45100D01*
X532550D01*
Y58100D01*
X548050D01*
G01X524893Y21235D02*
X554893D01*
G01X524893Y42935D02*
Y21235D01*
G01X554893Y42935D02*
X524893D01*
G01X520970Y59590D02*
X530070D01*
Y81390D01*
X520970D01*
Y59590D01*
G01X475808Y74867D02*
X475683Y74617D01*
X475600Y74325D01*
Y73992D01*
X475725Y73617D01*
X475933Y73325D01*
X476183Y73117D01*
X476600Y72950D01*
X476975Y72908D01*
X477350Y72992D01*
X477600Y73117D01*
X477850Y73367D01*
X478017Y73658D01*
X478100Y73950D01*
Y74242D01*
X478017Y74533D01*
X477892Y74783D01*
X477725Y74992D01*
G01X478100Y77050D02*
X475600D01*
X476100Y76550D01*
G01X478100D02*
Y77550D01*
G01X476017Y79358D02*
X475767Y79608D01*
X475642Y79900D01*
X475600Y80233D01*
X475683Y80650D01*
X475892Y80942D01*
X476142Y81025D01*
X476392Y80983D01*
X476600Y80817D01*
X477017Y79983D01*
X477308Y79608D01*
X477725Y79358D01*
X478100Y79275D01*
Y81025D01*
G01X477808Y82542D02*
X478017Y82833D01*
X478100Y83167D01*
X478017Y83500D01*
X477767Y83792D01*
X477392Y84000D01*
X477017Y84083D01*
X476558D01*
X476183Y84000D01*
X475850Y83792D01*
X475683Y83542D01*
X475600Y83250D01*
X475683Y82917D01*
X475850Y82667D01*
X476100Y82500D01*
X476433Y82417D01*
X476725Y82500D01*
X477017Y82708D01*
X477183Y82958D01*
X477225Y83250D01*
X477142Y83583D01*
X476933Y83833D01*
X476558Y84083D01*
G01X493667Y77659D02*
X493417Y77784D01*
X493125Y77867D01*
X492792D01*
X492417Y77742D01*
X492125Y77534D01*
X491917Y77284D01*
X491750Y76867D01*
X491708Y76492D01*
X491792Y76117D01*
X491917Y75867D01*
X492167Y75617D01*
X492458Y75450D01*
X492750Y75367D01*
X493042D01*
X493333Y75450D01*
X493583Y75575D01*
X493792Y75742D01*
G01X495850Y75367D02*
Y77867D01*
X495350Y77367D01*
G01Y75367D02*
X496350D01*
G01X498033Y75867D02*
X498283Y75575D01*
X498617Y75409D01*
X498992Y75367D01*
X499325Y75409D01*
X499658Y75617D01*
X499867Y75867D01*
X499908Y76117D01*
X499825Y76409D01*
X499533Y76617D01*
X499242Y76700D01*
X498867D01*
G01X499242D02*
X499492Y76825D01*
X499700Y77034D01*
X499783Y77284D01*
X499700Y77534D01*
X499492Y77742D01*
X499117Y77867D01*
X498742Y77825D01*
X498367Y77659D01*
G01X502050Y77867D02*
X501717Y77784D01*
X501467Y77575D01*
X501300Y77325D01*
X501175Y76992D01*
X501133Y76617D01*
X501175Y76242D01*
X501300Y75909D01*
X501467Y75659D01*
X501717Y75450D01*
X502050Y75367D01*
X502383Y75450D01*
X502633Y75659D01*
X502800Y75909D01*
X502925Y76242D01*
X502967Y76617D01*
X502925Y76992D01*
X502800Y77325D01*
X502633Y77575D01*
X502383Y77784D01*
X502050Y77867D01*
G01X488017Y83300D02*
Y85800D01*
X489058D01*
X489392Y85675D01*
X489600Y85508D01*
X489683Y85175D01*
X489600Y84842D01*
X489350Y84633D01*
X489058Y84508D01*
X488017D01*
G01X489058D02*
X489683Y83300D01*
G01X492450D02*
Y85800D01*
X490908Y84008D01*
X492992D01*
G01X494133Y83800D02*
X494383Y83508D01*
X494717Y83342D01*
X495092Y83300D01*
X495425Y83342D01*
X495758Y83550D01*
X495967Y83800D01*
X496008Y84050D01*
X495925Y84342D01*
X495633Y84550D01*
X495342Y84633D01*
X494967D01*
G01X495342D02*
X495592Y84758D01*
X495800Y84967D01*
X495883Y85217D01*
X495800Y85467D01*
X495592Y85675D01*
X495217Y85800D01*
X494842Y85758D01*
X494467Y85592D01*
G01X497442Y83592D02*
X497733Y83383D01*
X498067Y83300D01*
X498400Y83383D01*
X498692Y83633D01*
X498900Y84008D01*
X498983Y84383D01*
Y84842D01*
X498900Y85217D01*
X498692Y85550D01*
X498442Y85717D01*
X498150Y85800D01*
X497817Y85717D01*
X497567Y85550D01*
X497400Y85300D01*
X497317Y84967D01*
X497400Y84675D01*
X497608Y84383D01*
X497858Y84217D01*
X498150Y84175D01*
X498483Y84258D01*
X498733Y84467D01*
X498983Y84842D01*
G01X510300Y104416D02*
Y101916D01*
G01X509342Y104416D02*
X511258D01*
G01X512567Y101916D02*
Y104416D01*
X513567D01*
X513900Y104291D01*
X514150Y103999D01*
X514233Y103666D01*
X514150Y103333D01*
X513942Y103083D01*
X513567Y102958D01*
X512567D01*
G01X515708Y103999D02*
X515958Y104249D01*
X516250Y104374D01*
X516583Y104416D01*
X517000Y104333D01*
X517292Y104124D01*
X517375Y103874D01*
X517333Y103624D01*
X517167Y103416D01*
X516333Y102999D01*
X515958Y102708D01*
X515708Y102291D01*
X515625Y101916D01*
X517375D01*
G01X530500Y105266D02*
Y102766D01*
G01X529542Y105266D02*
X531458D01*
G01X532767Y102766D02*
Y105266D01*
X533767D01*
X534100Y105141D01*
X534350Y104849D01*
X534433Y104516D01*
X534350Y104183D01*
X534142Y103933D01*
X533767Y103808D01*
X532767D01*
G01X535783Y103266D02*
X536033Y102974D01*
X536367Y102808D01*
X536742Y102766D01*
X537075Y102808D01*
X537408Y103016D01*
X537617Y103266D01*
X537658Y103516D01*
X537575Y103808D01*
X537283Y104016D01*
X536992Y104099D01*
X536617D01*
G01X536992D02*
X537242Y104224D01*
X537450Y104433D01*
X537533Y104683D01*
X537450Y104933D01*
X537242Y105141D01*
X536867Y105266D01*
X536492Y105224D01*
X536117Y105058D01*
G01X510200Y109966D02*
Y107466D01*
G01X509242Y109966D02*
X511158D01*
G01X512467Y107466D02*
Y109966D01*
X513467D01*
X513800Y109841D01*
X514050Y109549D01*
X514133Y109216D01*
X514050Y108883D01*
X513842Y108633D01*
X513467Y108508D01*
X512467D01*
G01X516400Y107466D02*
Y109966D01*
X515900Y109466D01*
G01Y107466D02*
X516900D01*
G01X480517Y93973D02*
Y96473D01*
X481558D01*
X481892Y96348D01*
X482100Y96181D01*
X482183Y95848D01*
X482100Y95515D01*
X481850Y95306D01*
X481558Y95181D01*
X480517D01*
G01X481558D02*
X482183Y93973D01*
G01X484950D02*
Y96473D01*
X483408Y94681D01*
X485492D01*
G01X486633Y94473D02*
X486883Y94181D01*
X487217Y94015D01*
X487592Y93973D01*
X487925Y94015D01*
X488258Y94223D01*
X488467Y94473D01*
X488508Y94723D01*
X488425Y95015D01*
X488133Y95223D01*
X487842Y95306D01*
X487467D01*
G01X487842D02*
X488092Y95431D01*
X488300Y95640D01*
X488383Y95890D01*
X488300Y96140D01*
X488092Y96348D01*
X487717Y96473D01*
X487342Y96431D01*
X486967Y96265D01*
G01X491150Y93973D02*
Y96473D01*
X489608Y94681D01*
X491692D01*
G01X481042Y87850D02*
Y90350D01*
X482083D01*
X482417Y90225D01*
X482625Y90058D01*
X482708Y89725D01*
X482625Y89392D01*
X482375Y89183D01*
X482083Y89058D01*
X481042D01*
G01X482083D02*
X482708Y87850D01*
G01X485475D02*
Y90350D01*
X483933Y88558D01*
X486017D01*
G01X487158Y88350D02*
X487408Y88058D01*
X487742Y87892D01*
X488117Y87850D01*
X488450Y87892D01*
X488783Y88100D01*
X488992Y88350D01*
X489033Y88600D01*
X488950Y88892D01*
X488658Y89100D01*
X488367Y89183D01*
X487992D01*
G01X488367D02*
X488617Y89308D01*
X488825Y89517D01*
X488908Y89767D01*
X488825Y90017D01*
X488617Y90225D01*
X488242Y90350D01*
X487867Y90308D01*
X487492Y90142D01*
G01X490383Y89933D02*
X490633Y90183D01*
X490925Y90308D01*
X491258Y90350D01*
X491675Y90267D01*
X491967Y90058D01*
X492050Y89808D01*
X492008Y89558D01*
X491842Y89350D01*
X491008Y88933D01*
X490633Y88642D01*
X490383Y88225D01*
X490300Y87850D01*
X492050D01*
G01X508555Y82219D02*
Y84719D01*
X509596D01*
X509930Y84594D01*
X510138Y84427D01*
X510221Y84094D01*
X510138Y83761D01*
X509888Y83552D01*
X509596Y83427D01*
X508555D01*
G01X509596D02*
X510221Y82219D01*
G01X512988D02*
Y84719D01*
X511446Y82927D01*
X513530D01*
G01X516088Y82219D02*
Y84719D01*
X514546Y82927D01*
X516630D01*
G01X517771Y82719D02*
X518021Y82427D01*
X518355Y82261D01*
X518730Y82219D01*
X519063Y82261D01*
X519396Y82469D01*
X519605Y82719D01*
X519646Y82969D01*
X519563Y83261D01*
X519271Y83469D01*
X518980Y83552D01*
X518605D01*
G01X518980D02*
X519230Y83677D01*
X519438Y83886D01*
X519521Y84136D01*
X519438Y84386D01*
X519230Y84594D01*
X518855Y84719D01*
X518480Y84677D01*
X518105Y84511D01*
G01X509055Y86219D02*
Y88719D01*
X510096D01*
X510430Y88594D01*
X510638Y88427D01*
X510721Y88094D01*
X510638Y87761D01*
X510388Y87552D01*
X510096Y87427D01*
X509055D01*
G01X510096D02*
X510721Y86219D01*
G01X513488D02*
Y88719D01*
X511946Y86927D01*
X514030D01*
G01X516588Y86219D02*
Y88719D01*
X515046Y86927D01*
X517130D01*
G01X518396Y88302D02*
X518646Y88552D01*
X518938Y88677D01*
X519271Y88719D01*
X519688Y88636D01*
X519980Y88427D01*
X520063Y88177D01*
X520021Y87927D01*
X519855Y87719D01*
X519021Y87302D01*
X518646Y87011D01*
X518396Y86594D01*
X518313Y86219D01*
X520063D01*
G01X533606Y82036D02*
X533481Y81786D01*
X533398Y81494D01*
Y81161D01*
X533523Y80786D01*
X533731Y80494D01*
X533981Y80286D01*
X534398Y80119D01*
X534773Y80077D01*
X535148Y80161D01*
X535398Y80286D01*
X535648Y80536D01*
X535815Y80827D01*
X535898Y81119D01*
Y81411D01*
X535815Y81702D01*
X535690Y81952D01*
X535523Y82161D01*
G01X535898Y84219D02*
X533398D01*
X533898Y83719D01*
G01X535898D02*
Y84719D01*
G01X535398Y86402D02*
X535690Y86652D01*
X535856Y86986D01*
X535898Y87361D01*
X535856Y87694D01*
X535648Y88027D01*
X535398Y88236D01*
X535148Y88277D01*
X534856Y88194D01*
X534648Y87902D01*
X534565Y87611D01*
Y87236D01*
G01Y87611D02*
X534440Y87861D01*
X534231Y88069D01*
X533981Y88152D01*
X533731Y88069D01*
X533523Y87861D01*
X533398Y87486D01*
X533440Y87111D01*
X533606Y86736D01*
G01X535606Y89711D02*
X535815Y90002D01*
X535898Y90336D01*
X535815Y90669D01*
X535565Y90961D01*
X535190Y91169D01*
X534815Y91252D01*
X534356D01*
X533981Y91169D01*
X533648Y90961D01*
X533481Y90711D01*
X533398Y90419D01*
X533481Y90086D01*
X533648Y89836D01*
X533898Y89669D01*
X534231Y89586D01*
X534523Y89669D01*
X534815Y89877D01*
X534981Y90127D01*
X535023Y90419D01*
X534940Y90752D01*
X534731Y91002D01*
X534356Y91252D01*
G01X494667Y88000D02*
Y90500D01*
X495667D01*
X496000Y90375D01*
X496250Y90083D01*
X496333Y89750D01*
X496250Y89417D01*
X496042Y89167D01*
X495667Y89042D01*
X494667D01*
G01X498600Y88000D02*
X498267Y88042D01*
X497975Y88208D01*
X497725Y88458D01*
X497558Y88750D01*
X497475Y89083D01*
Y89417D01*
X497558Y89750D01*
X497725Y90042D01*
X497975Y90292D01*
X498267Y90458D01*
X498600Y90500D01*
X498933Y90458D01*
X499225Y90292D01*
X499475Y90042D01*
X499642Y89750D01*
X499725Y89417D01*
Y89083D01*
X499642Y88750D01*
X499475Y88458D01*
X499225Y88208D01*
X498933Y88042D01*
X498600Y88000D01*
G01X498933Y88667D02*
X499433Y88000D01*
G01X501700D02*
Y90500D01*
X501200Y90000D01*
G01Y88000D02*
X502200D01*
G01X502490Y70170D02*
X488490D01*
G01X493417Y79500D02*
Y82000D01*
X494417D01*
X494750Y81875D01*
X495000Y81583D01*
X495083Y81250D01*
X495000Y80917D01*
X494792Y80667D01*
X494417Y80542D01*
X493417D01*
G01X497350Y79500D02*
Y82000D01*
X496850Y81500D01*
G01Y79500D02*
X497850D01*
G01X509071Y91219D02*
Y93719D01*
X509905D01*
X510238Y93594D01*
X510488Y93427D01*
X510696Y93177D01*
X510863Y92886D01*
X510905Y92469D01*
X510863Y92052D01*
X510696Y91761D01*
X510488Y91511D01*
X510238Y91344D01*
X509905Y91219D01*
X509071D01*
G01X513088D02*
Y93719D01*
X512588Y93219D01*
G01Y91219D02*
X513588D01*
G01X542394Y203859D02*
X541861Y204192D01*
X541261Y204392D01*
X540727D01*
X540194Y204192D01*
X539794Y203859D01*
X539594Y203392D01*
X539727Y202925D01*
X540061Y202525D01*
X540661Y202259D01*
X541461Y202125D01*
X541927Y201859D01*
X542127Y201392D01*
X541994Y200925D01*
X541661Y200592D01*
X541194Y200392D01*
X540727D01*
X540261Y200525D01*
X539861Y200859D01*
G01X536394Y204392D02*
Y200392D01*
G01X531794Y201725D02*
Y204392D01*
G01Y200659D02*
X531927Y200592D01*
Y200459D01*
X531794Y200392D01*
X531661Y200459D01*
Y200592D01*
X531794Y200659D01*
G01X527194Y200392D02*
Y204392D01*
G01X528127Y201725D02*
X526261D01*
G01X485773Y761873D02*
X486173Y762273D01*
X486640Y762473D01*
X487173Y762540D01*
X487840Y762407D01*
X488307Y762073D01*
X488440Y761673D01*
X488373Y761273D01*
X488107Y760940D01*
X486773Y760273D01*
X486173Y759807D01*
X485773Y759140D01*
X485640Y758540D01*
X488440D01*
G01X560003Y30409D02*
X589603D01*
Y-7191D01*
X560003D01*
Y30409D01*
G01X561942Y33917D02*
X561817Y33667D01*
X561734Y33375D01*
Y33042D01*
X561859Y32667D01*
X562067Y32375D01*
X562317Y32167D01*
X562734Y32000D01*
X563109Y31958D01*
X563484Y32042D01*
X563734Y32167D01*
X563984Y32417D01*
X564151Y32708D01*
X564234Y33000D01*
Y33292D01*
X564151Y33583D01*
X564026Y33833D01*
X563859Y34042D01*
G01Y35183D02*
X564067Y35433D01*
X564192Y35725D01*
X564234Y36100D01*
X564151Y36475D01*
X563984Y36767D01*
X563692Y36975D01*
X563359Y37017D01*
X563026Y36933D01*
X562817Y36725D01*
X562651Y36433D01*
X562609Y36142D01*
X562651Y35850D01*
X562817Y35475D01*
X561734Y35600D01*
Y36725D01*
G01X564234Y39200D02*
X561734D01*
X562234Y38700D01*
G01X564234D02*
Y39700D01*
G01Y42217D02*
X563692Y42300D01*
X563234Y42425D01*
X562817Y42592D01*
X562359Y42800D01*
X561734Y43133D01*
Y41467D01*
G01X553000Y79500D02*
Y65500D01*
G01X566000D02*
Y79500D01*
G01X553000Y65500D02*
X566000D01*
G01X544534Y64233D02*
X546326D01*
X546701Y64400D01*
X546951Y64733D01*
X547034Y65150D01*
X546951Y65567D01*
X546701Y65900D01*
X546326Y66067D01*
X544534D01*
G01X546659Y67333D02*
X546867Y67583D01*
X546992Y67875D01*
X547034Y68250D01*
X546951Y68625D01*
X546784Y68917D01*
X546492Y69125D01*
X546159Y69167D01*
X545826Y69083D01*
X545617Y68875D01*
X545451Y68583D01*
X545409Y68292D01*
X545451Y68000D01*
X545617Y67625D01*
X544534Y67750D01*
Y68875D01*
G01Y71350D02*
X544617Y71017D01*
X544826Y70767D01*
X545076Y70600D01*
X545409Y70475D01*
X545784Y70433D01*
X546159Y70475D01*
X546492Y70600D01*
X546742Y70767D01*
X546951Y71017D01*
X547034Y71350D01*
X546951Y71683D01*
X546742Y71933D01*
X546492Y72100D01*
X546159Y72225D01*
X545784Y72267D01*
X545409Y72225D01*
X545076Y72100D01*
X544826Y71933D01*
X544617Y71683D01*
X544534Y71350D01*
G01X550100Y50180D02*
Y63580D01*
G01X560100Y50180D02*
X550100D01*
G01X560100Y63580D02*
Y50180D01*
G01X550100Y63580D02*
X560100D01*
G01X568684Y37667D02*
X566184D01*
Y38708D01*
X566309Y39042D01*
X566476Y39250D01*
X566809Y39333D01*
X567142Y39250D01*
X567351Y39000D01*
X567476Y38708D01*
Y37667D01*
G01Y38708D02*
X568684Y39333D01*
G01Y41600D02*
X568642Y41892D01*
X568517Y42225D01*
X568309Y42433D01*
X568017Y42517D01*
X567726Y42433D01*
X567476Y42183D01*
X567351Y41808D01*
Y41392D01*
X567267Y41142D01*
X567059Y40933D01*
X566767Y40850D01*
X566476Y40975D01*
X566267Y41267D01*
X566184Y41600D01*
X566267Y41933D01*
X566476Y42225D01*
X566767Y42350D01*
X567059Y42267D01*
X567267Y42058D01*
X567351Y41808D01*
Y41392D01*
X567476Y41017D01*
X567726Y40767D01*
X568017Y40683D01*
X568309Y40767D01*
X568517Y40975D01*
X568642Y41308D01*
X568684Y41600D01*
G01X566184Y44700D02*
X566267Y44367D01*
X566476Y44117D01*
X566726Y43950D01*
X567059Y43825D01*
X567434Y43783D01*
X567809Y43825D01*
X568142Y43950D01*
X568392Y44117D01*
X568601Y44367D01*
X568684Y44700D01*
X568601Y45033D01*
X568392Y45283D01*
X568142Y45450D01*
X567809Y45575D01*
X567434Y45617D01*
X567059Y45575D01*
X566726Y45450D01*
X566476Y45283D01*
X566267Y45033D01*
X566184Y44700D01*
G01X568684Y47800D02*
X566184D01*
X566684Y47300D01*
G01X568684D02*
Y48300D01*
G01X588683Y46167D02*
X586183D01*
Y47208D01*
X586308Y47542D01*
X586475Y47750D01*
X586808Y47833D01*
X587141Y47750D01*
X587350Y47500D01*
X587475Y47208D01*
Y46167D01*
G01Y47208D02*
X588683Y47833D01*
G01Y50017D02*
X588141Y50100D01*
X587683Y50225D01*
X587266Y50392D01*
X586808Y50600D01*
X586183Y50933D01*
Y49267D01*
G01X588183Y52283D02*
X588475Y52533D01*
X588641Y52867D01*
X588683Y53242D01*
X588641Y53575D01*
X588433Y53908D01*
X588183Y54117D01*
X587933Y54158D01*
X587641Y54075D01*
X587433Y53783D01*
X587350Y53492D01*
Y53117D01*
G01Y53492D02*
X587225Y53742D01*
X587016Y53950D01*
X586766Y54033D01*
X586516Y53950D01*
X586308Y53742D01*
X586183Y53367D01*
X586225Y52992D01*
X586391Y52617D01*
G01X588683Y56217D02*
X588141Y56300D01*
X587683Y56425D01*
X587266Y56592D01*
X586808Y56800D01*
X586183Y57133D01*
Y55467D01*
G01X558684Y29950D02*
X558642Y29617D01*
X558476Y29325D01*
X558226Y29075D01*
X557934Y28908D01*
X557601Y28825D01*
X557267D01*
X556934Y28908D01*
X556642Y29075D01*
X556392Y29325D01*
X556226Y29617D01*
X556184Y29950D01*
X556226Y30283D01*
X556392Y30575D01*
X556642Y30825D01*
X556934Y30992D01*
X557267Y31075D01*
X557601D01*
X557934Y30992D01*
X558226Y30825D01*
X558476Y30575D01*
X558642Y30283D01*
X558684Y29950D01*
G01X558017Y30283D02*
X558684Y30783D01*
G01X558309Y32133D02*
X558517Y32383D01*
X558642Y32675D01*
X558684Y33050D01*
X558601Y33425D01*
X558434Y33717D01*
X558142Y33925D01*
X557809Y33967D01*
X557476Y33883D01*
X557267Y33675D01*
X557101Y33383D01*
X557059Y33092D01*
X557101Y32800D01*
X557267Y32425D01*
X556184Y32550D01*
Y33675D01*
G01X554893Y21235D02*
Y42935D01*
G01X569517Y35766D02*
Y33266D01*
X571183D01*
G01X574283D02*
X572617D01*
Y35766D01*
X574283D01*
G01X573617Y34558D02*
X572617D01*
G01X575633Y33266D02*
Y35766D01*
X576467D01*
X576800Y35641D01*
X577050Y35474D01*
X577258Y35224D01*
X577425Y34933D01*
X577467Y34516D01*
X577425Y34099D01*
X577258Y33808D01*
X577050Y33558D01*
X576800Y33391D01*
X576467Y33266D01*
X575633D01*
G01X578733Y33766D02*
X578983Y33474D01*
X579317Y33308D01*
X579692Y33266D01*
X580025Y33308D01*
X580358Y33516D01*
X580567Y33766D01*
X580608Y34016D01*
X580525Y34308D01*
X580233Y34516D01*
X579942Y34599D01*
X579567D01*
G01X579942D02*
X580192Y34724D01*
X580400Y34933D01*
X580483Y35183D01*
X580400Y35433D01*
X580192Y35641D01*
X579817Y35766D01*
X579442Y35724D01*
X579067Y35558D01*
G01X567898Y15199D02*
X561198D01*
G01X572998D02*
X577098D01*
G01X567898Y10099D02*
X572998Y15199D01*
G01X567898Y20299D02*
Y10099D01*
G01X572998Y15199D02*
X567898Y20299D01*
G01X582198Y10099D02*
X577098Y15199D01*
G01X582198Y20299D02*
Y10099D01*
G01X577098Y15199D02*
X582198Y20299D01*
G01Y15199D02*
X585898D01*
G01X572998Y12399D02*
Y18799D01*
G01X577098Y12399D02*
Y18799D01*
G01X579450Y68600D02*
X579117Y68642D01*
X578825Y68808D01*
X578575Y69058D01*
X578408Y69350D01*
X578325Y69683D01*
Y70017D01*
X578408Y70350D01*
X578575Y70642D01*
X578825Y70892D01*
X579117Y71058D01*
X579450Y71100D01*
X579783Y71058D01*
X580075Y70892D01*
X580325Y70642D01*
X580492Y70350D01*
X580575Y70017D01*
Y69683D01*
X580492Y69350D01*
X580325Y69058D01*
X580075Y68808D01*
X579783Y68642D01*
X579450Y68600D01*
G01X579783Y69267D02*
X580283Y68600D01*
G01X581758Y70683D02*
X582008Y70933D01*
X582300Y71058D01*
X582633Y71100D01*
X583050Y71017D01*
X583342Y70808D01*
X583425Y70558D01*
X583383Y70308D01*
X583217Y70100D01*
X582383Y69683D01*
X582008Y69392D01*
X581758Y68975D01*
X581675Y68600D01*
X583425D01*
G01X585650Y71100D02*
X585317Y71017D01*
X585067Y70808D01*
X584900Y70558D01*
X584775Y70225D01*
X584733Y69850D01*
X584775Y69475D01*
X584900Y69142D01*
X585067Y68892D01*
X585317Y68683D01*
X585650Y68600D01*
X585983Y68683D01*
X586233Y68892D01*
X586400Y69142D01*
X586525Y69475D01*
X586567Y69850D01*
X586525Y70225D01*
X586400Y70558D01*
X586233Y70808D01*
X585983Y71017D01*
X585650Y71100D01*
G01X587833Y68975D02*
X588083Y68767D01*
X588375Y68642D01*
X588750Y68600D01*
X589125Y68683D01*
X589417Y68850D01*
X589625Y69142D01*
X589667Y69475D01*
X589583Y69808D01*
X589375Y70017D01*
X589083Y70183D01*
X588792Y70225D01*
X588500Y70183D01*
X588125Y70017D01*
X588250Y71100D01*
X589375D01*
G01X579600Y60235D02*
X579340D01*
X577905Y58800D01*
X579340Y57365D01*
G01X579600Y60235D02*
Y57365D01*
X568600D01*
G01Y60235D02*
X579600D01*
G01X568600D02*
Y57365D01*
G01X537916Y81916D02*
X537791Y81666D01*
X537708Y81374D01*
Y81041D01*
X537833Y80666D01*
X538041Y80374D01*
X538291Y80166D01*
X538708Y79999D01*
X539083Y79957D01*
X539458Y80041D01*
X539708Y80166D01*
X539958Y80416D01*
X540125Y80707D01*
X540208Y80999D01*
Y81291D01*
X540125Y81582D01*
X540000Y81832D01*
X539833Y82041D01*
G01X540208Y84099D02*
X537708D01*
X538208Y83599D01*
G01X540208D02*
Y84599D01*
G01X539708Y86282D02*
X540000Y86532D01*
X540166Y86866D01*
X540208Y87241D01*
X540166Y87574D01*
X539958Y87907D01*
X539708Y88116D01*
X539458Y88157D01*
X539166Y88074D01*
X538958Y87782D01*
X538875Y87491D01*
Y87116D01*
G01Y87491D02*
X538750Y87741D01*
X538541Y87949D01*
X538291Y88032D01*
X538041Y87949D01*
X537833Y87741D01*
X537708Y87366D01*
X537750Y86991D01*
X537916Y86616D01*
G01X540208Y90299D02*
X540166Y90591D01*
X540041Y90924D01*
X539833Y91132D01*
X539541Y91216D01*
X539250Y91132D01*
X539000Y90882D01*
X538875Y90507D01*
Y90091D01*
X538791Y89841D01*
X538583Y89632D01*
X538291Y89549D01*
X538000Y89674D01*
X537791Y89966D01*
X537708Y90299D01*
X537791Y90632D01*
X538000Y90924D01*
X538291Y91049D01*
X538583Y90966D01*
X538791Y90757D01*
X538875Y90507D01*
Y90091D01*
X539000Y89716D01*
X539250Y89466D01*
X539541Y89382D01*
X539833Y89466D01*
X540041Y89674D01*
X540166Y90007D01*
X540208Y90299D01*
G01X556867Y88617D02*
Y91117D01*
X557908D01*
X558242Y90992D01*
X558450Y90825D01*
X558533Y90492D01*
X558450Y90159D01*
X558200Y89950D01*
X557908Y89825D01*
X556867D01*
G01X557908D02*
X558533Y88617D01*
G01X560717D02*
X560800Y89159D01*
X560925Y89617D01*
X561092Y90034D01*
X561300Y90492D01*
X561633Y91117D01*
X559967D01*
G01X562983Y89117D02*
X563233Y88825D01*
X563567Y88659D01*
X563942Y88617D01*
X564275Y88659D01*
X564608Y88867D01*
X564817Y89117D01*
X564858Y89367D01*
X564775Y89659D01*
X564483Y89867D01*
X564192Y89950D01*
X563817D01*
G01X564192D02*
X564442Y90075D01*
X564650Y90284D01*
X564733Y90534D01*
X564650Y90784D01*
X564442Y90992D01*
X564067Y91117D01*
X563692Y91075D01*
X563317Y90909D01*
G01X566083Y88992D02*
X566333Y88784D01*
X566625Y88659D01*
X567000Y88617D01*
X567375Y88700D01*
X567667Y88867D01*
X567875Y89159D01*
X567917Y89492D01*
X567833Y89825D01*
X567625Y90034D01*
X567333Y90200D01*
X567042Y90242D01*
X566750Y90200D01*
X566375Y90034D01*
X566500Y91117D01*
X567625D01*
G01X564700Y80000D02*
Y84000D01*
X557300D01*
G01X569884Y73350D02*
X569842Y73017D01*
X569676Y72725D01*
X569426Y72475D01*
X569134Y72308D01*
X568801Y72225D01*
X568467D01*
X568134Y72308D01*
X567842Y72475D01*
X567592Y72725D01*
X567426Y73017D01*
X567384Y73350D01*
X567426Y73683D01*
X567592Y73975D01*
X567842Y74225D01*
X568134Y74392D01*
X568467Y74475D01*
X568801D01*
X569134Y74392D01*
X569426Y74225D01*
X569676Y73975D01*
X569842Y73683D01*
X569884Y73350D01*
G01X569217Y73683D02*
X569884Y74183D01*
G01X567801Y75658D02*
X567551Y75908D01*
X567426Y76200D01*
X567384Y76533D01*
X567467Y76950D01*
X567676Y77242D01*
X567926Y77325D01*
X568176Y77283D01*
X568384Y77117D01*
X568801Y76283D01*
X569092Y75908D01*
X569509Y75658D01*
X569884Y75575D01*
Y77325D01*
G01X567801Y78758D02*
X567551Y79008D01*
X567426Y79300D01*
X567384Y79633D01*
X567467Y80050D01*
X567676Y80342D01*
X567926Y80425D01*
X568176Y80383D01*
X568384Y80217D01*
X568801Y79383D01*
X569092Y79008D01*
X569509Y78758D01*
X569884Y78675D01*
Y80425D01*
G01X566000Y79500D02*
X553000D01*
G01X590100Y155600D02*
X592600D01*
G01X590100Y154642D02*
Y156558D01*
G01X592600Y157867D02*
X590100D01*
Y158867D01*
X590225Y159200D01*
X590517Y159450D01*
X590850Y159533D01*
X591183Y159450D01*
X591433Y159242D01*
X591558Y158867D01*
Y157867D01*
G01X592600Y161800D02*
X590100D01*
X590600Y161300D01*
G01X592600D02*
Y162300D01*
G01Y164900D02*
X592558Y165192D01*
X592433Y165525D01*
X592225Y165733D01*
X591933Y165817D01*
X591642Y165733D01*
X591392Y165483D01*
X591267Y165108D01*
Y164692D01*
X591183Y164442D01*
X590975Y164233D01*
X590683Y164150D01*
X590392Y164275D01*
X590183Y164567D01*
X590100Y164900D01*
X590183Y165233D01*
X590392Y165525D01*
X590683Y165650D01*
X590975Y165567D01*
X591183Y165358D01*
X591267Y165108D01*
Y164692D01*
X591392Y164317D01*
X591642Y164067D01*
X591933Y163983D01*
X592225Y164067D01*
X592433Y164275D01*
X592558Y164608D01*
X592600Y164900D01*
G01X590100Y168000D02*
X590183Y167667D01*
X590392Y167417D01*
X590642Y167250D01*
X590975Y167125D01*
X591350Y167083D01*
X591725Y167125D01*
X592058Y167250D01*
X592308Y167417D01*
X592517Y167667D01*
X592600Y168000D01*
X592517Y168333D01*
X592308Y168583D01*
X592058Y168750D01*
X591725Y168875D01*
X591350Y168917D01*
X590975Y168875D01*
X590642Y168750D01*
X590392Y168583D01*
X590183Y168333D01*
X590100Y168000D01*
G01X601500Y155500D02*
X604000D01*
G01X601500Y154542D02*
Y156458D01*
G01X604000Y157767D02*
X601500D01*
Y158767D01*
X601625Y159100D01*
X601917Y159350D01*
X602250Y159433D01*
X602583Y159350D01*
X602833Y159142D01*
X602958Y158767D01*
Y157767D01*
G01X604000Y161700D02*
X601500D01*
X602000Y161200D01*
G01X604000D02*
Y162200D01*
G01Y164800D02*
X603958Y165092D01*
X603833Y165425D01*
X603625Y165633D01*
X603333Y165717D01*
X603042Y165633D01*
X602792Y165383D01*
X602667Y165008D01*
Y164592D01*
X602583Y164342D01*
X602375Y164133D01*
X602083Y164050D01*
X601792Y164175D01*
X601583Y164467D01*
X601500Y164800D01*
X601583Y165133D01*
X601792Y165425D01*
X602083Y165550D01*
X602375Y165467D01*
X602583Y165258D01*
X602667Y165008D01*
Y164592D01*
X602792Y164217D01*
X603042Y163967D01*
X603333Y163883D01*
X603625Y163967D01*
X603833Y164175D01*
X603958Y164508D01*
X604000Y164800D01*
G01X601917Y167108D02*
X601667Y167358D01*
X601542Y167650D01*
X601500Y167983D01*
X601583Y168400D01*
X601792Y168692D01*
X602042Y168775D01*
X602292Y168733D01*
X602500Y168567D01*
X602917Y167733D01*
X603208Y167358D01*
X603625Y167108D01*
X604000Y167025D01*
Y168775D01*
G01X596100Y155600D02*
X598600D01*
G01X596100Y154642D02*
Y156558D01*
G01X598600Y157867D02*
X596100D01*
Y158867D01*
X596225Y159200D01*
X596517Y159450D01*
X596850Y159533D01*
X597183Y159450D01*
X597433Y159242D01*
X597558Y158867D01*
Y157867D01*
G01X598600Y161800D02*
X596100D01*
X596600Y161300D01*
G01X598600D02*
Y162300D01*
G01Y164900D02*
X598558Y165192D01*
X598433Y165525D01*
X598225Y165733D01*
X597933Y165817D01*
X597642Y165733D01*
X597392Y165483D01*
X597267Y165108D01*
Y164692D01*
X597183Y164442D01*
X596975Y164233D01*
X596683Y164150D01*
X596392Y164275D01*
X596183Y164567D01*
X596100Y164900D01*
X596183Y165233D01*
X596392Y165525D01*
X596683Y165650D01*
X596975Y165567D01*
X597183Y165358D01*
X597267Y165108D01*
Y164692D01*
X597392Y164317D01*
X597642Y164067D01*
X597933Y163983D01*
X598225Y164067D01*
X598433Y164275D01*
X598558Y164608D01*
X598600Y164900D01*
G01X598225Y167083D02*
X598433Y167333D01*
X598558Y167625D01*
X598600Y168000D01*
X598517Y168375D01*
X598350Y168667D01*
X598058Y168875D01*
X597725Y168917D01*
X597392Y168833D01*
X597183Y168625D01*
X597017Y168333D01*
X596975Y168042D01*
X597017Y167750D01*
X597183Y167375D01*
X596100Y167500D01*
Y168625D01*
G01X583400Y155500D02*
X585900D01*
G01X583400Y154542D02*
Y156458D01*
G01X585900Y157767D02*
X583400D01*
Y158767D01*
X583525Y159100D01*
X583817Y159350D01*
X584150Y159433D01*
X584483Y159350D01*
X584733Y159142D01*
X584858Y158767D01*
Y157767D01*
G01X585900Y161700D02*
X583400D01*
X583900Y161200D01*
G01X585900D02*
Y162200D01*
G01Y164717D02*
X585358Y164800D01*
X584900Y164925D01*
X584483Y165092D01*
X584025Y165300D01*
X583400Y165633D01*
Y163967D01*
G01X585900Y167900D02*
X585858Y168192D01*
X585733Y168525D01*
X585525Y168733D01*
X585233Y168817D01*
X584942Y168733D01*
X584692Y168483D01*
X584567Y168108D01*
Y167692D01*
X584483Y167442D01*
X584275Y167233D01*
X583983Y167150D01*
X583692Y167275D01*
X583483Y167567D01*
X583400Y167900D01*
X583483Y168233D01*
X583692Y168525D01*
X583983Y168650D01*
X584275Y168567D01*
X584483Y168358D01*
X584567Y168108D01*
Y167692D01*
X584692Y167317D01*
X584942Y167067D01*
X585233Y166983D01*
X585525Y167067D01*
X585733Y167275D01*
X585858Y167608D01*
X585900Y167900D01*
G01X585417Y366100D02*
Y368600D01*
X586458D01*
X586792Y368475D01*
X587000Y368308D01*
X587083Y367975D01*
X587000Y367642D01*
X586750Y367433D01*
X586458Y367308D01*
X585417D01*
G01X586458D02*
X587083Y366100D01*
G01X588558Y367142D02*
X588850Y367433D01*
X589100Y367600D01*
X589433Y367683D01*
X589725Y367600D01*
X589933Y367433D01*
X590100Y367183D01*
X590142Y366892D01*
X590100Y366642D01*
X589933Y366392D01*
X589683Y366183D01*
X589392Y366100D01*
X589058Y366183D01*
X588767Y366433D01*
X588600Y366808D01*
X588558Y367225D01*
X588642Y367767D01*
X588767Y368058D01*
X588975Y368350D01*
X589267Y368558D01*
X589558Y368600D01*
X589850Y368517D01*
X590058Y368308D01*
G01X591533Y366600D02*
X591783Y366308D01*
X592117Y366142D01*
X592492Y366100D01*
X592825Y366142D01*
X593158Y366350D01*
X593367Y366600D01*
X593408Y366850D01*
X593325Y367142D01*
X593033Y367350D01*
X592742Y367433D01*
X592367D01*
G01X592742D02*
X592992Y367558D01*
X593200Y367767D01*
X593283Y368017D01*
X593200Y368267D01*
X592992Y368475D01*
X592617Y368600D01*
X592242Y368558D01*
X591867Y368392D01*
G01X594842Y366392D02*
X595133Y366183D01*
X595467Y366100D01*
X595800Y366183D01*
X596092Y366433D01*
X596300Y366808D01*
X596383Y367183D01*
Y367642D01*
X596300Y368017D01*
X596092Y368350D01*
X595842Y368517D01*
X595550Y368600D01*
X595217Y368517D01*
X594967Y368350D01*
X594800Y368100D01*
X594717Y367767D01*
X594800Y367475D01*
X595008Y367183D01*
X595258Y367017D01*
X595550Y366975D01*
X595883Y367058D01*
X596133Y367267D01*
X596383Y367642D01*
G01X591500Y375300D02*
Y371300D01*
X598900D01*
G01X598617Y366600D02*
Y369100D01*
X599658D01*
X599992Y368975D01*
X600200Y368808D01*
X600283Y368475D01*
X600200Y368142D01*
X599950Y367933D01*
X599658Y367808D01*
X598617D01*
G01X599658D02*
X600283Y366600D01*
G01X601758Y367642D02*
X602050Y367933D01*
X602300Y368100D01*
X602633Y368183D01*
X602925Y368100D01*
X603133Y367933D01*
X603300Y367683D01*
X603342Y367392D01*
X603300Y367142D01*
X603133Y366892D01*
X602883Y366683D01*
X602592Y366600D01*
X602258Y366683D01*
X601967Y366933D01*
X601800Y367308D01*
X601758Y367725D01*
X601842Y368267D01*
X601967Y368558D01*
X602175Y368850D01*
X602467Y369058D01*
X602758Y369100D01*
X603050Y369017D01*
X603258Y368808D01*
G01X604733Y367100D02*
X604983Y366808D01*
X605317Y366642D01*
X605692Y366600D01*
X606025Y366642D01*
X606358Y366850D01*
X606567Y367100D01*
X606608Y367350D01*
X606525Y367642D01*
X606233Y367850D01*
X605942Y367933D01*
X605567D01*
G01X605942D02*
X606192Y368058D01*
X606400Y368267D01*
X606483Y368517D01*
X606400Y368767D01*
X606192Y368975D01*
X605817Y369100D01*
X605442Y369058D01*
X605067Y368892D01*
G01X608750Y366600D02*
X609042Y366642D01*
X609375Y366767D01*
X609583Y366975D01*
X609667Y367267D01*
X609583Y367558D01*
X609333Y367808D01*
X608958Y367933D01*
X608542D01*
X608292Y368017D01*
X608083Y368225D01*
X608000Y368517D01*
X608125Y368808D01*
X608417Y369017D01*
X608750Y369100D01*
X609083Y369017D01*
X609375Y368808D01*
X609500Y368517D01*
X609417Y368225D01*
X609208Y368017D01*
X608958Y367933D01*
X608542D01*
X608167Y367808D01*
X607917Y367558D01*
X607833Y367267D01*
X607917Y366975D01*
X608125Y366767D01*
X608458Y366642D01*
X608750Y366600D01*
G01X602308Y375437D02*
Y371437D01*
X609708D01*
G01X601000Y392349D02*
X600667Y392391D01*
X600375Y392557D01*
X600125Y392807D01*
X599958Y393099D01*
X599875Y393432D01*
Y393766D01*
X599958Y394099D01*
X600125Y394391D01*
X600375Y394641D01*
X600667Y394807D01*
X601000Y394849D01*
X601333Y394807D01*
X601625Y394641D01*
X601875Y394391D01*
X602042Y394099D01*
X602125Y393766D01*
Y393432D01*
X602042Y393099D01*
X601875Y392807D01*
X601625Y392557D01*
X601333Y392391D01*
X601000Y392349D01*
G01X601333Y393016D02*
X601833Y392349D01*
G01X604100D02*
Y394849D01*
X603600Y394349D01*
G01Y392349D02*
X604600D01*
G01X606408Y393391D02*
X606700Y393682D01*
X606950Y393849D01*
X607283Y393932D01*
X607575Y393849D01*
X607783Y393682D01*
X607950Y393432D01*
X607992Y393141D01*
X607950Y392891D01*
X607783Y392641D01*
X607533Y392432D01*
X607242Y392349D01*
X606908Y392432D01*
X606617Y392682D01*
X606450Y393057D01*
X606408Y393474D01*
X606492Y394016D01*
X606617Y394307D01*
X606825Y394599D01*
X607117Y394807D01*
X607408Y394849D01*
X607700Y394766D01*
X607908Y394557D01*
G01X597373Y376211D02*
X610373D01*
G01X597373Y390211D02*
Y376211D01*
G01X610373Y390211D02*
X597373D01*
G01X589600Y392149D02*
X589267Y392191D01*
X588975Y392357D01*
X588725Y392607D01*
X588558Y392899D01*
X588475Y393232D01*
Y393566D01*
X588558Y393899D01*
X588725Y394191D01*
X588975Y394441D01*
X589267Y394607D01*
X589600Y394649D01*
X589933Y394607D01*
X590225Y394441D01*
X590475Y394191D01*
X590642Y393899D01*
X590725Y393566D01*
Y393232D01*
X590642Y392899D01*
X590475Y392607D01*
X590225Y392357D01*
X589933Y392191D01*
X589600Y392149D01*
G01X589933Y392816D02*
X590433Y392149D01*
G01X592700D02*
Y394649D01*
X592200Y394149D01*
G01Y392149D02*
X593200D01*
G01X595717D02*
X595800Y392691D01*
X595925Y393149D01*
X596092Y393566D01*
X596300Y394024D01*
X596633Y394649D01*
X594967D01*
G01X596373Y376211D02*
Y390211D01*
G01X583373Y376211D02*
X596373D01*
G01X583373Y390211D02*
Y376211D01*
G01X596373Y390211D02*
X583373D01*
G01X602134Y348483D02*
X603926D01*
X604301Y348650D01*
X604551Y348983D01*
X604634Y349400D01*
X604551Y349817D01*
X604301Y350150D01*
X603926Y350317D01*
X602134D01*
G01X604634Y353000D02*
X602134D01*
X603926Y351458D01*
Y353542D01*
G01X604634Y356100D02*
X602134D01*
X603926Y354558D01*
Y356642D01*
G01X589367Y524959D02*
X589117Y525084D01*
X588825Y525167D01*
X588492D01*
X588117Y525042D01*
X587825Y524834D01*
X587617Y524584D01*
X587450Y524167D01*
X587408Y523792D01*
X587492Y523417D01*
X587617Y523167D01*
X587867Y522917D01*
X588158Y522750D01*
X588450Y522667D01*
X588742D01*
X589033Y522750D01*
X589283Y522875D01*
X589492Y523042D01*
G01X590758Y524750D02*
X591008Y525000D01*
X591300Y525125D01*
X591633Y525167D01*
X592050Y525084D01*
X592342Y524875D01*
X592425Y524625D01*
X592383Y524375D01*
X592217Y524167D01*
X591383Y523750D01*
X591008Y523459D01*
X590758Y523042D01*
X590675Y522667D01*
X592425D01*
G01X594650D02*
Y525167D01*
X594150Y524667D01*
G01Y522667D02*
X595150D01*
G01X597750Y525167D02*
X597417Y525084D01*
X597167Y524875D01*
X597000Y524625D01*
X596875Y524292D01*
X596833Y523917D01*
X596875Y523542D01*
X597000Y523209D01*
X597167Y522959D01*
X597417Y522750D01*
X597750Y522667D01*
X598083Y522750D01*
X598333Y522959D01*
X598500Y523209D01*
X598625Y523542D01*
X598667Y523917D01*
X598625Y524292D01*
X598500Y524625D01*
X598333Y524875D01*
X598083Y525084D01*
X597750Y525167D01*
G01X597767Y471459D02*
X597517Y471584D01*
X597225Y471667D01*
X596892D01*
X596517Y471542D01*
X596225Y471334D01*
X596017Y471084D01*
X595850Y470667D01*
X595808Y470292D01*
X595892Y469917D01*
X596017Y469667D01*
X596267Y469417D01*
X596558Y469250D01*
X596850Y469167D01*
X597142D01*
X597433Y469250D01*
X597683Y469375D01*
X597892Y469542D01*
G01X599158Y471250D02*
X599408Y471500D01*
X599700Y471625D01*
X600033Y471667D01*
X600450Y471584D01*
X600742Y471375D01*
X600825Y471125D01*
X600783Y470875D01*
X600617Y470667D01*
X599783Y470250D01*
X599408Y469959D01*
X599158Y469542D01*
X599075Y469167D01*
X600825D01*
G01X603050D02*
Y471667D01*
X602550Y471167D01*
G01Y469167D02*
X603550D01*
G01X606650D02*
Y471667D01*
X605108Y469875D01*
X607192D01*
G01X597767Y475959D02*
X597517Y476084D01*
X597225Y476167D01*
X596892D01*
X596517Y476042D01*
X596225Y475834D01*
X596017Y475584D01*
X595850Y475167D01*
X595808Y474792D01*
X595892Y474417D01*
X596017Y474167D01*
X596267Y473917D01*
X596558Y473750D01*
X596850Y473667D01*
X597142D01*
X597433Y473750D01*
X597683Y473875D01*
X597892Y474042D01*
G01X599158Y475750D02*
X599408Y476000D01*
X599700Y476125D01*
X600033Y476167D01*
X600450Y476084D01*
X600742Y475875D01*
X600825Y475625D01*
X600783Y475375D01*
X600617Y475167D01*
X599783Y474750D01*
X599408Y474459D01*
X599158Y474042D01*
X599075Y473667D01*
X600825D01*
G01X603050D02*
Y476167D01*
X602550Y475667D01*
G01Y473667D02*
X603550D01*
G01X605233Y474042D02*
X605483Y473834D01*
X605775Y473709D01*
X606150Y473667D01*
X606525Y473750D01*
X606817Y473917D01*
X607025Y474209D01*
X607067Y474542D01*
X606983Y474875D01*
X606775Y475084D01*
X606483Y475250D01*
X606192Y475292D01*
X605900Y475250D01*
X605525Y475084D01*
X605650Y476167D01*
X606775D01*
G01X597767Y480459D02*
X597517Y480584D01*
X597225Y480667D01*
X596892D01*
X596517Y480542D01*
X596225Y480334D01*
X596017Y480084D01*
X595850Y479667D01*
X595808Y479292D01*
X595892Y478917D01*
X596017Y478667D01*
X596267Y478417D01*
X596558Y478250D01*
X596850Y478167D01*
X597142D01*
X597433Y478250D01*
X597683Y478375D01*
X597892Y478542D01*
G01X599158Y480250D02*
X599408Y480500D01*
X599700Y480625D01*
X600033Y480667D01*
X600450Y480584D01*
X600742Y480375D01*
X600825Y480125D01*
X600783Y479875D01*
X600617Y479667D01*
X599783Y479250D01*
X599408Y478959D01*
X599158Y478542D01*
X599075Y478167D01*
X600825D01*
G01X603050D02*
Y480667D01*
X602550Y480167D01*
G01Y478167D02*
X603550D01*
G01X606067D02*
X606150Y478709D01*
X606275Y479167D01*
X606442Y479584D01*
X606650Y480042D01*
X606983Y480667D01*
X605317D01*
G01X587617Y527167D02*
Y529667D01*
X588658D01*
X588992Y529542D01*
X589200Y529375D01*
X589283Y529042D01*
X589200Y528709D01*
X588950Y528500D01*
X588658Y528375D01*
X587617D01*
G01X588658D02*
X589283Y527167D01*
G01X590633Y527542D02*
X590883Y527334D01*
X591175Y527209D01*
X591550Y527167D01*
X591925Y527250D01*
X592217Y527417D01*
X592425Y527709D01*
X592467Y528042D01*
X592383Y528375D01*
X592175Y528584D01*
X591883Y528750D01*
X591592Y528792D01*
X591300Y528750D01*
X590925Y528584D01*
X591050Y529667D01*
X592175D01*
G01X593858Y529250D02*
X594108Y529500D01*
X594400Y529625D01*
X594733Y529667D01*
X595150Y529584D01*
X595442Y529375D01*
X595525Y529125D01*
X595483Y528875D01*
X595317Y528667D01*
X594483Y528250D01*
X594108Y527959D01*
X593858Y527542D01*
X593775Y527167D01*
X595525D01*
G01X597750Y529667D02*
X597417Y529584D01*
X597167Y529375D01*
X597000Y529125D01*
X596875Y528792D01*
X596833Y528417D01*
X596875Y528042D01*
X597000Y527709D01*
X597167Y527459D01*
X597417Y527250D01*
X597750Y527167D01*
X598083Y527250D01*
X598333Y527459D01*
X598500Y527709D01*
X598625Y528042D01*
X598667Y528417D01*
X598625Y528792D01*
X598500Y529125D01*
X598333Y529375D01*
X598083Y529584D01*
X597750Y529667D01*
G01X599960Y525043D02*
X607760D01*
G01X599960Y532043D02*
Y525043D01*
G01X603700Y464916D02*
X604533D01*
Y464166D01*
X604283Y463916D01*
X603992Y463749D01*
X603575Y463666D01*
X603158Y463749D01*
X602867Y463916D01*
X602617Y464166D01*
X602450Y464458D01*
X602367Y464791D01*
Y465083D01*
X602450Y465333D01*
X602617Y465624D01*
X602867Y465874D01*
X603117Y466041D01*
X603450Y466166D01*
X603742D01*
X604075Y466083D01*
X604325Y465916D01*
G01X607050Y463666D02*
Y466166D01*
X605508Y464374D01*
X607592D01*
G01X598402Y501854D02*
Y499354D01*
X600068D01*
G01X602335D02*
Y501854D01*
X601835Y501354D01*
G01Y499354D02*
X602835D01*
G01X605435Y501854D02*
X605102Y501771D01*
X604852Y501562D01*
X604685Y501312D01*
X604560Y500979D01*
X604518Y500604D01*
X604560Y500229D01*
X604685Y499896D01*
X604852Y499646D01*
X605102Y499437D01*
X605435Y499354D01*
X605768Y499437D01*
X606018Y499646D01*
X606185Y499896D01*
X606310Y500229D01*
X606352Y500604D01*
X606310Y500979D01*
X606185Y501312D01*
X606018Y501562D01*
X605768Y501771D01*
X605435Y501854D01*
G01X599667Y557659D02*
X599417Y557784D01*
X599125Y557867D01*
X598792D01*
X598417Y557742D01*
X598125Y557534D01*
X597917Y557284D01*
X597750Y556867D01*
X597708Y556492D01*
X597792Y556117D01*
X597917Y555867D01*
X598167Y555617D01*
X598458Y555450D01*
X598750Y555367D01*
X599042D01*
X599333Y555450D01*
X599583Y555575D01*
X599792Y555742D01*
G01X601058Y557450D02*
X601308Y557700D01*
X601600Y557825D01*
X601933Y557867D01*
X602350Y557784D01*
X602642Y557575D01*
X602725Y557325D01*
X602683Y557075D01*
X602517Y556867D01*
X601683Y556450D01*
X601308Y556159D01*
X601058Y555742D01*
X600975Y555367D01*
X602725D01*
G01X604950Y557867D02*
X604617Y557784D01*
X604367Y557575D01*
X604200Y557325D01*
X604075Y556992D01*
X604033Y556617D01*
X604075Y556242D01*
X604200Y555909D01*
X604367Y555659D01*
X604617Y555450D01*
X604950Y555367D01*
X605283Y555450D01*
X605533Y555659D01*
X605700Y555909D01*
X605825Y556242D01*
X605867Y556617D01*
X605825Y556992D01*
X605700Y557325D01*
X605533Y557575D01*
X605283Y557784D01*
X604950Y557867D01*
G01X608050Y555367D02*
X608342Y555409D01*
X608675Y555534D01*
X608883Y555742D01*
X608967Y556034D01*
X608883Y556325D01*
X608633Y556575D01*
X608258Y556700D01*
X607842D01*
X607592Y556784D01*
X607383Y556992D01*
X607300Y557284D01*
X607425Y557575D01*
X607717Y557784D01*
X608050Y557867D01*
X608383Y557784D01*
X608675Y557575D01*
X608800Y557284D01*
X608717Y556992D01*
X608508Y556784D01*
X608258Y556700D01*
X607842D01*
X607467Y556575D01*
X607217Y556325D01*
X607133Y556034D01*
X607217Y555742D01*
X607425Y555534D01*
X607758Y555409D01*
X608050Y555367D01*
G01X594498Y542820D02*
X591998D01*
Y543861D01*
X592123Y544195D01*
X592290Y544403D01*
X592623Y544486D01*
X592956Y544403D01*
X593165Y544153D01*
X593290Y543861D01*
Y542820D01*
G01Y543861D02*
X594498Y544486D01*
G01X594123Y545836D02*
X594331Y546086D01*
X594456Y546378D01*
X594498Y546753D01*
X594415Y547128D01*
X594248Y547420D01*
X593956Y547628D01*
X593623Y547670D01*
X593290Y547586D01*
X593081Y547378D01*
X592915Y547086D01*
X592873Y546795D01*
X592915Y546503D01*
X593081Y546128D01*
X591998Y546253D01*
Y547378D01*
G01X592415Y549061D02*
X592165Y549311D01*
X592040Y549603D01*
X591998Y549936D01*
X592081Y550353D01*
X592290Y550645D01*
X592540Y550728D01*
X592790Y550686D01*
X592998Y550520D01*
X593415Y549686D01*
X593706Y549311D01*
X594123Y549061D01*
X594498Y548978D01*
Y550728D01*
G01X592415Y552161D02*
X592165Y552411D01*
X592040Y552703D01*
X591998Y553036D01*
X592081Y553453D01*
X592290Y553745D01*
X592540Y553828D01*
X592790Y553786D01*
X592998Y553620D01*
X593415Y552786D01*
X593706Y552411D01*
X594123Y552161D01*
X594498Y552078D01*
Y553828D01*
G01X601164Y538803D02*
X605164D01*
Y546203D01*
G01X597442Y535667D02*
X597317Y535417D01*
X597234Y535125D01*
Y534792D01*
X597359Y534417D01*
X597567Y534125D01*
X597817Y533917D01*
X598234Y533750D01*
X598609Y533708D01*
X598984Y533792D01*
X599234Y533917D01*
X599484Y534167D01*
X599651Y534458D01*
X599734Y534750D01*
Y535042D01*
X599651Y535333D01*
X599526Y535583D01*
X599359Y535792D01*
G01X597651Y537058D02*
X597401Y537308D01*
X597276Y537600D01*
X597234Y537933D01*
X597317Y538350D01*
X597526Y538642D01*
X597776Y538725D01*
X598026Y538683D01*
X598234Y538517D01*
X598651Y537683D01*
X598942Y537308D01*
X599359Y537058D01*
X599734Y536975D01*
Y538725D01*
G01Y540950D02*
X597234D01*
X597734Y540450D01*
G01X599734D02*
Y541450D01*
G01X599234Y543133D02*
X599526Y543383D01*
X599692Y543717D01*
X599734Y544092D01*
X599692Y544425D01*
X599484Y544758D01*
X599234Y544967D01*
X598984Y545008D01*
X598692Y544925D01*
X598484Y544633D01*
X598401Y544342D01*
Y543967D01*
G01Y544342D02*
X598276Y544592D01*
X598067Y544800D01*
X597817Y544883D01*
X597567Y544800D01*
X597359Y544592D01*
X597234Y544217D01*
X597276Y543842D01*
X597442Y543467D01*
G01X591500Y557217D02*
X592333D01*
Y556467D01*
X592083Y556217D01*
X591792Y556050D01*
X591375Y555967D01*
X590958Y556050D01*
X590667Y556217D01*
X590417Y556467D01*
X590250Y556759D01*
X590167Y557092D01*
Y557384D01*
X590250Y557634D01*
X590417Y557925D01*
X590667Y558175D01*
X590917Y558342D01*
X591250Y558467D01*
X591542D01*
X591875Y558384D01*
X592125Y558217D01*
G01X593433Y556342D02*
X593683Y556134D01*
X593975Y556009D01*
X594350Y555967D01*
X594725Y556050D01*
X595017Y556217D01*
X595225Y556509D01*
X595267Y556842D01*
X595183Y557175D01*
X594975Y557384D01*
X594683Y557550D01*
X594392Y557592D01*
X594100Y557550D01*
X593725Y557384D01*
X593850Y558467D01*
X594975D01*
G01X599960Y532043D02*
X605160D01*
G01X598817Y567092D02*
X598567Y567217D01*
X598275Y567300D01*
X597942D01*
X597567Y567175D01*
X597275Y566967D01*
X597067Y566717D01*
X596900Y566300D01*
X596858Y565925D01*
X596942Y565550D01*
X597067Y565300D01*
X597317Y565050D01*
X597608Y564883D01*
X597900Y564800D01*
X598192D01*
X598483Y564883D01*
X598733Y565008D01*
X598942Y565175D01*
G01X600042Y564800D02*
Y567300D01*
X601958Y564800D01*
Y567300D01*
G01X603183Y565175D02*
X603433Y564967D01*
X603725Y564842D01*
X604100Y564800D01*
X604475Y564883D01*
X604767Y565050D01*
X604975Y565342D01*
X605017Y565675D01*
X604933Y566008D01*
X604725Y566217D01*
X604433Y566383D01*
X604142Y566425D01*
X603850Y566383D01*
X603475Y566217D01*
X603600Y567300D01*
X604725D01*
G01X585000Y570600D02*
X615600D01*
Y614400D01*
X585000D01*
Y570600D01*
G01X603121Y-23326D02*
Y20974D01*
X605471D01*
Y129874D01*
X654371D01*
Y20974D01*
X656721D01*
Y-23326D01*
X603121D01*
G01X610686Y7664D02*
Y11664D01*
X612286D01*
X612819Y11464D01*
X613219Y10997D01*
X613352Y10464D01*
X613219Y9931D01*
X612886Y9531D01*
X612286Y9331D01*
X610686D01*
G01X615686Y7664D02*
Y10331D01*
G01Y9797D02*
X616019Y10064D01*
X616352Y10264D01*
X616819Y10331D01*
X617152Y10264D01*
X617552Y10064D01*
G01X620219Y9464D02*
X622352D01*
X622152Y9931D01*
X621819Y10197D01*
X621352Y10331D01*
X620886Y10264D01*
X620486Y10064D01*
X620219Y9597D01*
X620086Y9197D01*
Y8797D01*
X620219Y8397D01*
X620552Y7997D01*
X620952Y7731D01*
X621419Y7664D01*
X621886Y7797D01*
X622352Y8197D01*
G01X624819Y8131D02*
X625152Y7864D01*
X625619Y7664D01*
X626019D01*
X626419Y7797D01*
X626686Y7997D01*
X626819Y8264D01*
X626752Y8664D01*
X626486Y8864D01*
X625286Y9264D01*
X625019Y9731D01*
X625152Y10064D01*
X625419Y10264D01*
X625819Y10331D01*
X626219Y10264D01*
X626619Y10064D01*
G01X629419Y8131D02*
X629752Y7864D01*
X630219Y7664D01*
X630619D01*
X631019Y7797D01*
X631286Y7997D01*
X631419Y8264D01*
X631352Y8664D01*
X631086Y8864D01*
X629886Y9264D01*
X629619Y9731D01*
X629752Y10064D01*
X630019Y10264D01*
X630419Y10331D01*
X630819Y10264D01*
X631219Y10064D01*
G01X638352Y7664D02*
Y11664D01*
X640886D01*
G01X639952Y9731D02*
X638352D01*
G01X644219Y10331D02*
Y7664D01*
G01Y11397D02*
X644086Y11464D01*
Y11597D01*
X644219Y11664D01*
X644352Y11597D01*
Y11464D01*
X644219Y11397D01*
G01X648819Y11664D02*
Y7664D01*
G01X647886Y10331D02*
X649752D01*
G01X621033Y132166D02*
X619367D01*
Y134666D01*
X621033D01*
G01X620367Y133458D02*
X619367D01*
G01X622425Y132166D02*
X624175Y134666D01*
G01X622425D02*
X624175Y132166D01*
G01X626400Y134666D02*
Y132166D01*
G01X625442Y134666D02*
X627358D01*
G01X628708Y134249D02*
X628958Y134499D01*
X629250Y134624D01*
X629583Y134666D01*
X630000Y134583D01*
X630292Y134374D01*
X630375Y134124D01*
X630333Y133874D01*
X630167Y133666D01*
X629333Y133249D01*
X628958Y132958D01*
X628708Y132541D01*
X628625Y132166D01*
X630375D01*
G01X640334Y168267D02*
X637834D01*
Y169308D01*
X637959Y169642D01*
X638126Y169850D01*
X638459Y169933D01*
X638792Y169850D01*
X639001Y169600D01*
X639126Y169308D01*
Y168267D01*
G01Y169308D02*
X640334Y169933D01*
G01Y172700D02*
X637834D01*
X639626Y171158D01*
Y173242D01*
G01X640334Y175800D02*
X637834D01*
X639626Y174258D01*
Y176342D01*
G01X637040Y155710D02*
X641040D01*
Y163110D01*
G01X647800Y145800D02*
X650300D01*
G01X647800Y144842D02*
Y146758D01*
G01X650300Y148067D02*
X647800D01*
Y149067D01*
X647925Y149400D01*
X648217Y149650D01*
X648550Y149733D01*
X648883Y149650D01*
X649133Y149442D01*
X649258Y149067D01*
Y148067D01*
G01X650300Y152000D02*
X647800D01*
X648300Y151500D01*
G01X650300D02*
Y152500D01*
G01Y155017D02*
X649758Y155100D01*
X649300Y155225D01*
X648883Y155392D01*
X648425Y155600D01*
X647800Y155933D01*
Y154267D01*
G01Y158200D02*
X647883Y157867D01*
X648092Y157617D01*
X648342Y157450D01*
X648675Y157325D01*
X649050Y157283D01*
X649425Y157325D01*
X649758Y157450D01*
X650008Y157617D01*
X650217Y157867D01*
X650300Y158200D01*
X650217Y158533D01*
X650008Y158783D01*
X649758Y158950D01*
X649425Y159075D01*
X649050Y159117D01*
X648675Y159075D01*
X648342Y158950D01*
X648092Y158783D01*
X647883Y158533D01*
X647800Y158200D01*
G01X644200Y141700D02*
X646700D01*
G01X644200Y140742D02*
Y142658D01*
G01X646700Y143967D02*
X644200D01*
Y144967D01*
X644325Y145300D01*
X644617Y145550D01*
X644950Y145633D01*
X645283Y145550D01*
X645533Y145342D01*
X645658Y144967D01*
Y143967D01*
G01X646700Y147900D02*
X644200D01*
X644700Y147400D01*
G01X646700D02*
Y148400D01*
G01Y150917D02*
X646158Y151000D01*
X645700Y151125D01*
X645283Y151292D01*
X644825Y151500D01*
X644200Y151833D01*
Y150167D01*
G01X646200Y153183D02*
X646492Y153433D01*
X646658Y153767D01*
X646700Y154142D01*
X646658Y154475D01*
X646450Y154808D01*
X646200Y155017D01*
X645950Y155058D01*
X645658Y154975D01*
X645450Y154683D01*
X645367Y154392D01*
Y154017D01*
G01Y154392D02*
X645242Y154642D01*
X645033Y154850D01*
X644783Y154933D01*
X644533Y154850D01*
X644325Y154642D01*
X644200Y154267D01*
X644242Y153892D01*
X644408Y153517D01*
G01X663500Y145700D02*
X666000D01*
G01X663500Y144742D02*
Y146658D01*
G01X666000Y147967D02*
X663500D01*
Y148967D01*
X663625Y149300D01*
X663917Y149550D01*
X664250Y149633D01*
X664583Y149550D01*
X664833Y149342D01*
X664958Y148967D01*
Y147967D01*
G01X666000Y151900D02*
X663500D01*
X664000Y151400D01*
G01X666000D02*
Y152400D01*
G01Y154917D02*
X665458Y155000D01*
X665000Y155125D01*
X664583Y155292D01*
X664125Y155500D01*
X663500Y155833D01*
Y154167D01*
G01X666000Y158100D02*
X663500D01*
X664000Y157600D01*
G01X666000D02*
Y158600D01*
G01X659500Y141900D02*
X662000D01*
G01X659500Y140942D02*
Y142858D01*
G01X662000Y144167D02*
X659500D01*
Y145167D01*
X659625Y145500D01*
X659917Y145750D01*
X660250Y145833D01*
X660583Y145750D01*
X660833Y145542D01*
X660958Y145167D01*
Y144167D01*
G01X662000Y148100D02*
X659500D01*
X660000Y147600D01*
G01X662000D02*
Y148600D01*
G01Y151117D02*
X661458Y151200D01*
X661000Y151325D01*
X660583Y151492D01*
X660125Y151700D01*
X659500Y152033D01*
Y150367D01*
G01X659917Y153508D02*
X659667Y153758D01*
X659542Y154050D01*
X659500Y154383D01*
X659583Y154800D01*
X659792Y155092D01*
X660042Y155175D01*
X660292Y155133D01*
X660500Y154967D01*
X660917Y154133D01*
X661208Y153758D01*
X661625Y153508D01*
X662000Y153425D01*
Y155175D01*
G01X655500Y145700D02*
X658000D01*
G01X655500Y144742D02*
Y146658D01*
G01X658000Y147967D02*
X655500D01*
Y148967D01*
X655625Y149300D01*
X655917Y149550D01*
X656250Y149633D01*
X656583Y149550D01*
X656833Y149342D01*
X656958Y148967D01*
Y147967D01*
G01X658000Y151900D02*
X655500D01*
X656000Y151400D01*
G01X658000D02*
Y152400D01*
G01Y154917D02*
X657458Y155000D01*
X657000Y155125D01*
X656583Y155292D01*
X656125Y155500D01*
X655500Y155833D01*
Y154167D01*
G01X658000Y158600D02*
X655500D01*
X657292Y157058D01*
Y159142D01*
G01X651700Y141600D02*
X654200D01*
G01X651700Y140642D02*
Y142558D01*
G01X654200Y143867D02*
X651700D01*
Y144867D01*
X651825Y145200D01*
X652117Y145450D01*
X652450Y145533D01*
X652783Y145450D01*
X653033Y145242D01*
X653158Y144867D01*
Y143867D01*
G01X654200Y147800D02*
X651700D01*
X652200Y147300D01*
G01X654200D02*
Y148300D01*
G01Y150817D02*
X653658Y150900D01*
X653200Y151025D01*
X652783Y151192D01*
X652325Y151400D01*
X651700Y151733D01*
Y150067D01*
G01X653158Y153208D02*
X652867Y153500D01*
X652700Y153750D01*
X652617Y154083D01*
X652700Y154375D01*
X652867Y154583D01*
X653117Y154750D01*
X653408Y154792D01*
X653658Y154750D01*
X653908Y154583D01*
X654117Y154333D01*
X654200Y154042D01*
X654117Y153708D01*
X653867Y153417D01*
X653492Y153250D01*
X653075Y153208D01*
X652533Y153292D01*
X652242Y153417D01*
X651950Y153625D01*
X651742Y153917D01*
X651700Y154208D01*
X651783Y154500D01*
X651992Y154708D01*
G01X667200Y141800D02*
X669700D01*
G01X667200Y140842D02*
Y142758D01*
G01X669700Y144067D02*
X667200D01*
Y145067D01*
X667325Y145400D01*
X667617Y145650D01*
X667950Y145733D01*
X668283Y145650D01*
X668533Y145442D01*
X668658Y145067D01*
Y144067D01*
G01X669700Y148000D02*
X667200D01*
X667700Y147500D01*
G01X669700D02*
Y148500D01*
G01Y151017D02*
X669158Y151100D01*
X668700Y151225D01*
X668283Y151392D01*
X667825Y151600D01*
X667200Y151933D01*
Y150267D01*
G01X669700Y154117D02*
X669158Y154200D01*
X668700Y154325D01*
X668283Y154492D01*
X667825Y154700D01*
X667200Y155033D01*
Y153367D01*
G01X612400Y155500D02*
X614900D01*
G01X612400Y154542D02*
Y156458D01*
G01X614900Y157767D02*
X612400D01*
Y158767D01*
X612525Y159100D01*
X612817Y159350D01*
X613150Y159433D01*
X613483Y159350D01*
X613733Y159142D01*
X613858Y158767D01*
Y157767D01*
G01X614900Y161700D02*
X612400D01*
X612900Y161200D01*
G01X614900D02*
Y162200D01*
G01Y164717D02*
X614358Y164800D01*
X613900Y164925D01*
X613483Y165092D01*
X613025Y165300D01*
X612400Y165633D01*
Y163967D01*
G01X614608Y167192D02*
X614817Y167483D01*
X614900Y167817D01*
X614817Y168150D01*
X614567Y168442D01*
X614192Y168650D01*
X613817Y168733D01*
X613358D01*
X612983Y168650D01*
X612650Y168442D01*
X612483Y168192D01*
X612400Y167900D01*
X612483Y167567D01*
X612650Y167317D01*
X612900Y167150D01*
X613233Y167067D01*
X613525Y167150D01*
X613817Y167358D01*
X613983Y167608D01*
X614025Y167900D01*
X613942Y168233D01*
X613733Y168483D01*
X613358Y168733D01*
G01X607000Y155600D02*
X609500D01*
G01X607000Y154642D02*
Y156558D01*
G01X609500Y157867D02*
X607000D01*
Y158867D01*
X607125Y159200D01*
X607417Y159450D01*
X607750Y159533D01*
X608083Y159450D01*
X608333Y159242D01*
X608458Y158867D01*
Y157867D01*
G01X609500Y161800D02*
X607000D01*
X607500Y161300D01*
G01X609500D02*
Y162300D01*
G01Y164900D02*
X609458Y165192D01*
X609333Y165525D01*
X609125Y165733D01*
X608833Y165817D01*
X608542Y165733D01*
X608292Y165483D01*
X608167Y165108D01*
Y164692D01*
X608083Y164442D01*
X607875Y164233D01*
X607583Y164150D01*
X607292Y164275D01*
X607083Y164567D01*
X607000Y164900D01*
X607083Y165233D01*
X607292Y165525D01*
X607583Y165650D01*
X607875Y165567D01*
X608083Y165358D01*
X608167Y165108D01*
Y164692D01*
X608292Y164317D01*
X608542Y164067D01*
X608833Y163983D01*
X609125Y164067D01*
X609333Y164275D01*
X609458Y164608D01*
X609500Y164900D01*
G01Y168000D02*
X607000D01*
X607500Y167500D01*
G01X609500D02*
Y168500D01*
G01X622934Y162500D02*
X625434D01*
G01X622934Y161542D02*
Y163458D01*
G01X625434Y164767D02*
X622934D01*
Y165767D01*
X623059Y166100D01*
X623351Y166350D01*
X623684Y166433D01*
X624017Y166350D01*
X624267Y166142D01*
X624392Y165767D01*
Y164767D01*
G01X625434Y168700D02*
X622934D01*
X623434Y168200D01*
G01X625434D02*
Y169200D01*
G01Y171800D02*
X625392Y172092D01*
X625267Y172425D01*
X625059Y172633D01*
X624767Y172717D01*
X624476Y172633D01*
X624226Y172383D01*
X624101Y172008D01*
Y171592D01*
X624017Y171342D01*
X623809Y171133D01*
X623517Y171050D01*
X623226Y171175D01*
X623017Y171467D01*
X622934Y171800D01*
X623017Y172133D01*
X623226Y172425D01*
X623517Y172550D01*
X623809Y172467D01*
X624017Y172258D01*
X624101Y172008D01*
Y171592D01*
X624226Y171217D01*
X624476Y170967D01*
X624767Y170883D01*
X625059Y170967D01*
X625267Y171175D01*
X625392Y171508D01*
X625434Y171800D01*
G01X624934Y173983D02*
X625226Y174233D01*
X625392Y174567D01*
X625434Y174942D01*
X625392Y175275D01*
X625184Y175608D01*
X624934Y175817D01*
X624684Y175858D01*
X624392Y175775D01*
X624184Y175483D01*
X624101Y175192D01*
Y174817D01*
G01Y175192D02*
X623976Y175442D01*
X623767Y175650D01*
X623517Y175733D01*
X623267Y175650D01*
X623059Y175442D01*
X622934Y175067D01*
X622976Y174692D01*
X623142Y174317D01*
G01X617700Y155700D02*
X620200D01*
G01X617700Y154742D02*
Y156658D01*
G01X620200Y157967D02*
X617700D01*
Y158967D01*
X617825Y159300D01*
X618117Y159550D01*
X618450Y159633D01*
X618783Y159550D01*
X619033Y159342D01*
X619158Y158967D01*
Y157967D01*
G01X620200Y161900D02*
X617700D01*
X618200Y161400D01*
G01X620200D02*
Y162400D01*
G01Y165000D02*
X620158Y165292D01*
X620033Y165625D01*
X619825Y165833D01*
X619533Y165917D01*
X619242Y165833D01*
X618992Y165583D01*
X618867Y165208D01*
Y164792D01*
X618783Y164542D01*
X618575Y164333D01*
X618283Y164250D01*
X617992Y164375D01*
X617783Y164667D01*
X617700Y165000D01*
X617783Y165333D01*
X617992Y165625D01*
X618283Y165750D01*
X618575Y165667D01*
X618783Y165458D01*
X618867Y165208D01*
Y164792D01*
X618992Y164417D01*
X619242Y164167D01*
X619533Y164083D01*
X619825Y164167D01*
X620033Y164375D01*
X620158Y164708D01*
X620200Y165000D01*
G01Y168600D02*
X617700D01*
X619492Y167058D01*
Y169142D01*
G01X631468Y174047D02*
X631343Y173797D01*
X631260Y173505D01*
Y173172D01*
X631385Y172797D01*
X631593Y172505D01*
X631843Y172297D01*
X632260Y172130D01*
X632635Y172088D01*
X633010Y172172D01*
X633260Y172297D01*
X633510Y172547D01*
X633677Y172838D01*
X633760Y173130D01*
Y173422D01*
X633677Y173713D01*
X633552Y173963D01*
X633385Y174172D01*
G01Y175313D02*
X633593Y175563D01*
X633718Y175855D01*
X633760Y176230D01*
X633677Y176605D01*
X633510Y176897D01*
X633218Y177105D01*
X632885Y177147D01*
X632552Y177063D01*
X632343Y176855D01*
X632177Y176563D01*
X632135Y176272D01*
X632177Y175980D01*
X632343Y175605D01*
X631260Y175730D01*
Y176855D01*
G01X631677Y178538D02*
X631427Y178788D01*
X631302Y179080D01*
X631260Y179413D01*
X631343Y179830D01*
X631552Y180122D01*
X631802Y180205D01*
X632052Y180163D01*
X632260Y179997D01*
X632677Y179163D01*
X632968Y178788D01*
X633385Y178538D01*
X633760Y178455D01*
Y180205D01*
G01Y182347D02*
X633218Y182430D01*
X632760Y182555D01*
X632343Y182722D01*
X631885Y182930D01*
X631260Y183263D01*
Y181597D01*
G01X628460Y162380D02*
Y167880D01*
X636460D01*
Y162280D01*
G01X628460Y150280D02*
Y155780D01*
G01Y150280D02*
X636460D01*
Y155780D01*
G01X666317Y254200D02*
Y256700D01*
X667358D01*
X667692Y256575D01*
X667900Y256408D01*
X667983Y256075D01*
X667900Y255742D01*
X667650Y255533D01*
X667358Y255408D01*
X666317D01*
G01X667358D02*
X667983Y254200D01*
G01X669333Y254575D02*
X669583Y254367D01*
X669875Y254242D01*
X670250Y254200D01*
X670625Y254283D01*
X670917Y254450D01*
X671125Y254742D01*
X671167Y255075D01*
X671083Y255408D01*
X670875Y255617D01*
X670583Y255783D01*
X670292Y255825D01*
X670000Y255783D01*
X669625Y255617D01*
X669750Y256700D01*
X670875D01*
G01X673350Y254200D02*
X673642Y254242D01*
X673975Y254367D01*
X674183Y254575D01*
X674267Y254867D01*
X674183Y255158D01*
X673933Y255408D01*
X673558Y255533D01*
X673142D01*
X672892Y255617D01*
X672683Y255825D01*
X672600Y256117D01*
X672725Y256408D01*
X673017Y256617D01*
X673350Y256700D01*
X673683Y256617D01*
X673975Y256408D01*
X674100Y256117D01*
X674017Y255825D01*
X673808Y255617D01*
X673558Y255533D01*
X673142D01*
X672767Y255408D01*
X672517Y255158D01*
X672433Y254867D01*
X672517Y254575D01*
X672725Y254367D01*
X673058Y254242D01*
X673350Y254200D01*
G01X676450D02*
Y256700D01*
X675950Y256200D01*
G01Y254200D02*
X676950D01*
G01X651517Y243667D02*
Y246167D01*
X652558D01*
X652892Y246042D01*
X653100Y245875D01*
X653183Y245542D01*
X653100Y245209D01*
X652850Y245000D01*
X652558Y244875D01*
X651517D01*
G01X652558D02*
X653183Y243667D01*
G01X654533Y244042D02*
X654783Y243834D01*
X655075Y243709D01*
X655450Y243667D01*
X655825Y243750D01*
X656117Y243917D01*
X656325Y244209D01*
X656367Y244542D01*
X656283Y244875D01*
X656075Y245084D01*
X655783Y245250D01*
X655492Y245292D01*
X655200Y245250D01*
X654825Y245084D01*
X654950Y246167D01*
X656075D01*
G01X658467Y243667D02*
X658550Y244209D01*
X658675Y244667D01*
X658842Y245084D01*
X659050Y245542D01*
X659383Y246167D01*
X657717D01*
G01X660858Y245750D02*
X661108Y246000D01*
X661400Y246125D01*
X661733Y246167D01*
X662150Y246084D01*
X662442Y245875D01*
X662525Y245625D01*
X662483Y245375D01*
X662317Y245167D01*
X661483Y244750D01*
X661108Y244459D01*
X660858Y244042D01*
X660775Y243667D01*
X662525D01*
G01X665509Y247503D02*
Y250003D01*
X666550D01*
X666884Y249878D01*
X667092Y249711D01*
X667175Y249378D01*
X667092Y249045D01*
X666842Y248836D01*
X666550Y248711D01*
X665509D01*
G01X666550D02*
X667175Y247503D01*
G01X668525Y247878D02*
X668775Y247670D01*
X669067Y247545D01*
X669442Y247503D01*
X669817Y247586D01*
X670109Y247753D01*
X670317Y248045D01*
X670359Y248378D01*
X670275Y248711D01*
X670067Y248920D01*
X669775Y249086D01*
X669484Y249128D01*
X669192Y249086D01*
X668817Y248920D01*
X668942Y250003D01*
X670067D01*
G01X672459Y247503D02*
X672542Y248045D01*
X672667Y248503D01*
X672834Y248920D01*
X673042Y249378D01*
X673375Y250003D01*
X671709D01*
G01X676142Y247503D02*
Y250003D01*
X674600Y248211D01*
X676684D01*
G01X665517Y243667D02*
Y246167D01*
X666558D01*
X666892Y246042D01*
X667100Y245875D01*
X667183Y245542D01*
X667100Y245209D01*
X666850Y245000D01*
X666558Y244875D01*
X665517D01*
G01X666558D02*
X667183Y243667D01*
G01X668658Y244709D02*
X668950Y245000D01*
X669200Y245167D01*
X669533Y245250D01*
X669825Y245167D01*
X670033Y245000D01*
X670200Y244750D01*
X670242Y244459D01*
X670200Y244209D01*
X670033Y243959D01*
X669783Y243750D01*
X669492Y243667D01*
X669158Y243750D01*
X668867Y244000D01*
X668700Y244375D01*
X668658Y244792D01*
X668742Y245334D01*
X668867Y245625D01*
X669075Y245917D01*
X669367Y246125D01*
X669658Y246167D01*
X669950Y246084D01*
X670158Y245875D01*
G01X671758Y245750D02*
X672008Y246000D01*
X672300Y246125D01*
X672633Y246167D01*
X673050Y246084D01*
X673342Y245875D01*
X673425Y245625D01*
X673383Y245375D01*
X673217Y245167D01*
X672383Y244750D01*
X672008Y244459D01*
X671758Y244042D01*
X671675Y243667D01*
X673425D01*
G01X676150D02*
Y246167D01*
X674608Y244375D01*
X676692D01*
G01X651517Y248667D02*
Y251167D01*
X652558D01*
X652892Y251042D01*
X653100Y250875D01*
X653183Y250542D01*
X653100Y250209D01*
X652850Y250000D01*
X652558Y249875D01*
X651517D01*
G01X652558D02*
X653183Y248667D01*
G01X654658Y249709D02*
X654950Y250000D01*
X655200Y250167D01*
X655533Y250250D01*
X655825Y250167D01*
X656033Y250000D01*
X656200Y249750D01*
X656242Y249459D01*
X656200Y249209D01*
X656033Y248959D01*
X655783Y248750D01*
X655492Y248667D01*
X655158Y248750D01*
X654867Y249000D01*
X654700Y249375D01*
X654658Y249792D01*
X654742Y250334D01*
X654867Y250625D01*
X655075Y250917D01*
X655367Y251125D01*
X655658Y251167D01*
X655950Y251084D01*
X656158Y250875D01*
G01X659050Y248667D02*
Y251167D01*
X657508Y249375D01*
X659592D01*
G01X660942Y248959D02*
X661233Y248750D01*
X661567Y248667D01*
X661900Y248750D01*
X662192Y249000D01*
X662400Y249375D01*
X662483Y249750D01*
Y250209D01*
X662400Y250584D01*
X662192Y250917D01*
X661942Y251084D01*
X661650Y251167D01*
X661317Y251084D01*
X661067Y250917D01*
X660900Y250667D01*
X660817Y250334D01*
X660900Y250042D01*
X661108Y249750D01*
X661358Y249584D01*
X661650Y249542D01*
X661983Y249625D01*
X662233Y249834D01*
X662483Y250209D01*
G01X665517Y228667D02*
Y231167D01*
X666558D01*
X666892Y231042D01*
X667100Y230875D01*
X667183Y230542D01*
X667100Y230209D01*
X666850Y230000D01*
X666558Y229875D01*
X665517D01*
G01X666558D02*
X667183Y228667D01*
G01X668658Y229709D02*
X668950Y230000D01*
X669200Y230167D01*
X669533Y230250D01*
X669825Y230167D01*
X670033Y230000D01*
X670200Y229750D01*
X670242Y229459D01*
X670200Y229209D01*
X670033Y228959D01*
X669783Y228750D01*
X669492Y228667D01*
X669158Y228750D01*
X668867Y229000D01*
X668700Y229375D01*
X668658Y229792D01*
X668742Y230334D01*
X668867Y230625D01*
X669075Y230917D01*
X669367Y231125D01*
X669658Y231167D01*
X669950Y231084D01*
X670158Y230875D01*
G01X671758Y229709D02*
X672050Y230000D01*
X672300Y230167D01*
X672633Y230250D01*
X672925Y230167D01*
X673133Y230000D01*
X673300Y229750D01*
X673342Y229459D01*
X673300Y229209D01*
X673133Y228959D01*
X672883Y228750D01*
X672592Y228667D01*
X672258Y228750D01*
X671967Y229000D01*
X671800Y229375D01*
X671758Y229792D01*
X671842Y230334D01*
X671967Y230625D01*
X672175Y230917D01*
X672467Y231125D01*
X672758Y231167D01*
X673050Y231084D01*
X673258Y230875D01*
G01X674733Y229167D02*
X674983Y228875D01*
X675317Y228709D01*
X675692Y228667D01*
X676025Y228709D01*
X676358Y228917D01*
X676567Y229167D01*
X676608Y229417D01*
X676525Y229709D01*
X676233Y229917D01*
X675942Y230000D01*
X675567D01*
G01X675942D02*
X676192Y230125D01*
X676400Y230334D01*
X676483Y230584D01*
X676400Y230834D01*
X676192Y231042D01*
X675817Y231167D01*
X675442Y231125D01*
X675067Y230959D01*
G01X665517Y233667D02*
Y236167D01*
X666558D01*
X666892Y236042D01*
X667100Y235875D01*
X667183Y235542D01*
X667100Y235209D01*
X666850Y235000D01*
X666558Y234875D01*
X665517D01*
G01X666558D02*
X667183Y233667D01*
G01X668658Y234709D02*
X668950Y235000D01*
X669200Y235167D01*
X669533Y235250D01*
X669825Y235167D01*
X670033Y235000D01*
X670200Y234750D01*
X670242Y234459D01*
X670200Y234209D01*
X670033Y233959D01*
X669783Y233750D01*
X669492Y233667D01*
X669158Y233750D01*
X668867Y234000D01*
X668700Y234375D01*
X668658Y234792D01*
X668742Y235334D01*
X668867Y235625D01*
X669075Y235917D01*
X669367Y236125D01*
X669658Y236167D01*
X669950Y236084D01*
X670158Y235875D01*
G01X671758Y234709D02*
X672050Y235000D01*
X672300Y235167D01*
X672633Y235250D01*
X672925Y235167D01*
X673133Y235000D01*
X673300Y234750D01*
X673342Y234459D01*
X673300Y234209D01*
X673133Y233959D01*
X672883Y233750D01*
X672592Y233667D01*
X672258Y233750D01*
X671967Y234000D01*
X671800Y234375D01*
X671758Y234792D01*
X671842Y235334D01*
X671967Y235625D01*
X672175Y235917D01*
X672467Y236125D01*
X672758Y236167D01*
X673050Y236084D01*
X673258Y235875D01*
G01X676150Y233667D02*
Y236167D01*
X674608Y234375D01*
X676692D01*
G01X665317Y237817D02*
Y240317D01*
X666358D01*
X666692Y240192D01*
X666900Y240025D01*
X666983Y239692D01*
X666900Y239359D01*
X666650Y239150D01*
X666358Y239025D01*
X665317D01*
G01X666358D02*
X666983Y237817D01*
G01X668333Y238192D02*
X668583Y237984D01*
X668875Y237859D01*
X669250Y237817D01*
X669625Y237900D01*
X669917Y238067D01*
X670125Y238359D01*
X670167Y238692D01*
X670083Y239025D01*
X669875Y239234D01*
X669583Y239400D01*
X669292Y239442D01*
X669000Y239400D01*
X668625Y239234D01*
X668750Y240317D01*
X669875D01*
G01X672267Y237817D02*
X672350Y238359D01*
X672475Y238817D01*
X672642Y239234D01*
X672850Y239692D01*
X673183Y240317D01*
X671517D01*
G01X674742Y238109D02*
X675033Y237900D01*
X675367Y237817D01*
X675700Y237900D01*
X675992Y238150D01*
X676200Y238525D01*
X676283Y238900D01*
Y239359D01*
X676200Y239734D01*
X675992Y240067D01*
X675742Y240234D01*
X675450Y240317D01*
X675117Y240234D01*
X674867Y240067D01*
X674700Y239817D01*
X674617Y239484D01*
X674700Y239192D01*
X674908Y238900D01*
X675158Y238734D01*
X675450Y238692D01*
X675783Y238775D01*
X676033Y238984D01*
X676283Y239359D01*
G01X651517Y238667D02*
Y241167D01*
X652558D01*
X652892Y241042D01*
X653100Y240875D01*
X653183Y240542D01*
X653100Y240209D01*
X652850Y240000D01*
X652558Y239875D01*
X651517D01*
G01X652558D02*
X653183Y238667D01*
G01X654533Y239042D02*
X654783Y238834D01*
X655075Y238709D01*
X655450Y238667D01*
X655825Y238750D01*
X656117Y238917D01*
X656325Y239209D01*
X656367Y239542D01*
X656283Y239875D01*
X656075Y240084D01*
X655783Y240250D01*
X655492Y240292D01*
X655200Y240250D01*
X654825Y240084D01*
X654950Y241167D01*
X656075D01*
G01X658550Y238667D02*
X658842Y238709D01*
X659175Y238834D01*
X659383Y239042D01*
X659467Y239334D01*
X659383Y239625D01*
X659133Y239875D01*
X658758Y240000D01*
X658342D01*
X658092Y240084D01*
X657883Y240292D01*
X657800Y240584D01*
X657925Y240875D01*
X658217Y241084D01*
X658550Y241167D01*
X658883Y241084D01*
X659175Y240875D01*
X659300Y240584D01*
X659217Y240292D01*
X659008Y240084D01*
X658758Y240000D01*
X658342D01*
X657967Y239875D01*
X657717Y239625D01*
X657633Y239334D01*
X657717Y239042D01*
X657925Y238834D01*
X658258Y238709D01*
X658550Y238667D01*
G01X660858Y240750D02*
X661108Y241000D01*
X661400Y241125D01*
X661733Y241167D01*
X662150Y241084D01*
X662442Y240875D01*
X662525Y240625D01*
X662483Y240375D01*
X662317Y240167D01*
X661483Y239750D01*
X661108Y239459D01*
X660858Y239042D01*
X660775Y238667D01*
X662525D01*
G01X666817Y263900D02*
Y266400D01*
X667858D01*
X668192Y266275D01*
X668400Y266108D01*
X668483Y265775D01*
X668400Y265442D01*
X668150Y265233D01*
X667858Y265108D01*
X666817D01*
G01X667858D02*
X668483Y263900D01*
G01X669958Y264942D02*
X670250Y265233D01*
X670500Y265400D01*
X670833Y265483D01*
X671125Y265400D01*
X671333Y265233D01*
X671500Y264983D01*
X671542Y264692D01*
X671500Y264442D01*
X671333Y264192D01*
X671083Y263983D01*
X670792Y263900D01*
X670458Y263983D01*
X670167Y264233D01*
X670000Y264608D01*
X669958Y265025D01*
X670042Y265567D01*
X670167Y265858D01*
X670375Y266150D01*
X670667Y266358D01*
X670958Y266400D01*
X671250Y266317D01*
X671458Y266108D01*
G01X674350Y263900D02*
Y266400D01*
X672808Y264608D01*
X674892D01*
G01X676867Y263900D02*
X676950Y264442D01*
X677075Y264900D01*
X677242Y265317D01*
X677450Y265775D01*
X677783Y266400D01*
X676117D01*
G01X666417Y258300D02*
Y260800D01*
X667458D01*
X667792Y260675D01*
X668000Y260508D01*
X668083Y260175D01*
X668000Y259842D01*
X667750Y259633D01*
X667458Y259508D01*
X666417D01*
G01X667458D02*
X668083Y258300D01*
G01X669433Y258675D02*
X669683Y258467D01*
X669975Y258342D01*
X670350Y258300D01*
X670725Y258383D01*
X671017Y258550D01*
X671225Y258842D01*
X671267Y259175D01*
X671183Y259508D01*
X670975Y259717D01*
X670683Y259883D01*
X670392Y259925D01*
X670100Y259883D01*
X669725Y259717D01*
X669850Y260800D01*
X670975D01*
G01X673367Y258300D02*
X673450Y258842D01*
X673575Y259300D01*
X673742Y259717D01*
X673950Y260175D01*
X674283Y260800D01*
X672617D01*
G01X676550Y258300D02*
X676842Y258342D01*
X677175Y258467D01*
X677383Y258675D01*
X677467Y258967D01*
X677383Y259258D01*
X677133Y259508D01*
X676758Y259633D01*
X676342D01*
X676092Y259717D01*
X675883Y259925D01*
X675800Y260217D01*
X675925Y260508D01*
X676217Y260717D01*
X676550Y260800D01*
X676883Y260717D01*
X677175Y260508D01*
X677300Y260217D01*
X677217Y259925D01*
X677008Y259717D01*
X676758Y259633D01*
X676342D01*
X675967Y259508D01*
X675717Y259258D01*
X675633Y258967D01*
X675717Y258675D01*
X675925Y258467D01*
X676258Y258342D01*
X676550Y258300D01*
G01X632542Y325767D02*
X632417Y325517D01*
X632334Y325225D01*
Y324892D01*
X632459Y324517D01*
X632667Y324225D01*
X632917Y324017D01*
X633334Y323850D01*
X633709Y323808D01*
X634084Y323892D01*
X634334Y324017D01*
X634584Y324267D01*
X634751Y324558D01*
X634834Y324850D01*
Y325142D01*
X634751Y325433D01*
X634626Y325683D01*
X634459Y325892D01*
G01X634834Y328450D02*
X632334D01*
X634126Y326908D01*
Y328992D01*
G01X634834Y331050D02*
X634792Y331342D01*
X634667Y331675D01*
X634459Y331883D01*
X634167Y331967D01*
X633876Y331883D01*
X633626Y331633D01*
X633501Y331258D01*
Y330842D01*
X633417Y330592D01*
X633209Y330383D01*
X632917Y330300D01*
X632626Y330425D01*
X632417Y330717D01*
X632334Y331050D01*
X632417Y331383D01*
X632626Y331675D01*
X632917Y331800D01*
X633209Y331717D01*
X633417Y331508D01*
X633501Y331258D01*
Y330842D01*
X633626Y330467D01*
X633876Y330217D01*
X634167Y330133D01*
X634459Y330217D01*
X634667Y330425D01*
X634792Y330758D01*
X634834Y331050D01*
G01Y334150D02*
X632334D01*
X632834Y333650D01*
G01X634834D02*
Y334650D01*
G01X613042Y318267D02*
X612917Y318017D01*
X612834Y317725D01*
Y317392D01*
X612959Y317017D01*
X613167Y316725D01*
X613417Y316517D01*
X613834Y316350D01*
X614209Y316308D01*
X614584Y316392D01*
X614834Y316517D01*
X615084Y316767D01*
X615251Y317058D01*
X615334Y317350D01*
Y317642D01*
X615251Y317933D01*
X615126Y318183D01*
X614959Y318392D01*
G01X615334Y320950D02*
X612834D01*
X614626Y319408D01*
Y321492D01*
G01X615334Y323550D02*
X615292Y323842D01*
X615167Y324175D01*
X614959Y324383D01*
X614667Y324467D01*
X614376Y324383D01*
X614126Y324133D01*
X614001Y323758D01*
Y323342D01*
X613917Y323092D01*
X613709Y322883D01*
X613417Y322800D01*
X613126Y322925D01*
X612917Y323217D01*
X612834Y323550D01*
X612917Y323883D01*
X613126Y324175D01*
X613417Y324300D01*
X613709Y324217D01*
X613917Y324008D01*
X614001Y323758D01*
Y323342D01*
X614126Y322967D01*
X614376Y322717D01*
X614667Y322633D01*
X614959Y322717D01*
X615167Y322925D01*
X615292Y323258D01*
X615334Y323550D01*
G01X614834Y325733D02*
X615126Y325983D01*
X615292Y326317D01*
X615334Y326692D01*
X615292Y327025D01*
X615084Y327358D01*
X614834Y327567D01*
X614584Y327608D01*
X614292Y327525D01*
X614084Y327233D01*
X614001Y326942D01*
Y326567D01*
G01Y326942D02*
X613876Y327192D01*
X613667Y327400D01*
X613417Y327483D01*
X613167Y327400D01*
X612959Y327192D01*
X612834Y326817D01*
X612876Y326442D01*
X613042Y326067D01*
G01X666764Y276330D02*
Y278830D01*
X667805D01*
X668139Y278705D01*
X668347Y278538D01*
X668430Y278205D01*
X668347Y277872D01*
X668097Y277663D01*
X667805Y277538D01*
X666764D01*
G01X667805D02*
X668430Y276330D01*
G01X669780Y276705D02*
X670030Y276497D01*
X670322Y276372D01*
X670697Y276330D01*
X671072Y276413D01*
X671364Y276580D01*
X671572Y276872D01*
X671614Y277205D01*
X671530Y277538D01*
X671322Y277747D01*
X671030Y277913D01*
X670739Y277955D01*
X670447Y277913D01*
X670072Y277747D01*
X670197Y278830D01*
X671322D01*
G01X673797Y276330D02*
X674089Y276372D01*
X674422Y276497D01*
X674630Y276705D01*
X674714Y276997D01*
X674630Y277288D01*
X674380Y277538D01*
X674005Y277663D01*
X673589D01*
X673339Y277747D01*
X673130Y277955D01*
X673047Y278247D01*
X673172Y278538D01*
X673464Y278747D01*
X673797Y278830D01*
X674130Y278747D01*
X674422Y278538D01*
X674547Y278247D01*
X674464Y277955D01*
X674255Y277747D01*
X674005Y277663D01*
X673589D01*
X673214Y277538D01*
X672964Y277288D01*
X672880Y276997D01*
X672964Y276705D01*
X673172Y276497D01*
X673505Y276372D01*
X673797Y276330D01*
G01X676897Y278830D02*
X676564Y278747D01*
X676314Y278538D01*
X676147Y278288D01*
X676022Y277955D01*
X675980Y277580D01*
X676022Y277205D01*
X676147Y276872D01*
X676314Y276622D01*
X676564Y276413D01*
X676897Y276330D01*
X677230Y276413D01*
X677480Y276622D01*
X677647Y276872D01*
X677772Y277205D01*
X677814Y277580D01*
X677772Y277955D01*
X677647Y278288D01*
X677480Y278538D01*
X677230Y278747D01*
X676897Y278830D01*
G01X666764Y268030D02*
Y270530D01*
X667805D01*
X668139Y270405D01*
X668347Y270238D01*
X668430Y269905D01*
X668347Y269572D01*
X668097Y269363D01*
X667805Y269238D01*
X666764D01*
G01X667805D02*
X668430Y268030D01*
G01X669780Y268405D02*
X670030Y268197D01*
X670322Y268072D01*
X670697Y268030D01*
X671072Y268113D01*
X671364Y268280D01*
X671572Y268572D01*
X671614Y268905D01*
X671530Y269238D01*
X671322Y269447D01*
X671030Y269613D01*
X670739Y269655D01*
X670447Y269613D01*
X670072Y269447D01*
X670197Y270530D01*
X671322D01*
G01X673797Y268030D02*
X674089Y268072D01*
X674422Y268197D01*
X674630Y268405D01*
X674714Y268697D01*
X674630Y268988D01*
X674380Y269238D01*
X674005Y269363D01*
X673589D01*
X673339Y269447D01*
X673130Y269655D01*
X673047Y269947D01*
X673172Y270238D01*
X673464Y270447D01*
X673797Y270530D01*
X674130Y270447D01*
X674422Y270238D01*
X674547Y269947D01*
X674464Y269655D01*
X674255Y269447D01*
X674005Y269363D01*
X673589D01*
X673214Y269238D01*
X672964Y268988D01*
X672880Y268697D01*
X672964Y268405D01*
X673172Y268197D01*
X673505Y268072D01*
X673797Y268030D01*
G01X675980Y268405D02*
X676230Y268197D01*
X676522Y268072D01*
X676897Y268030D01*
X677272Y268113D01*
X677564Y268280D01*
X677772Y268572D01*
X677814Y268905D01*
X677730Y269238D01*
X677522Y269447D01*
X677230Y269613D01*
X676939Y269655D01*
X676647Y269613D01*
X676272Y269447D01*
X676397Y270530D01*
X677522D01*
G01X666617Y284700D02*
Y287200D01*
X667658D01*
X667992Y287075D01*
X668200Y286908D01*
X668283Y286575D01*
X668200Y286242D01*
X667950Y286033D01*
X667658Y285908D01*
X666617D01*
G01X667658D02*
X668283Y284700D01*
G01X669633Y285075D02*
X669883Y284867D01*
X670175Y284742D01*
X670550Y284700D01*
X670925Y284783D01*
X671217Y284950D01*
X671425Y285242D01*
X671467Y285575D01*
X671383Y285908D01*
X671175Y286117D01*
X670883Y286283D01*
X670592Y286325D01*
X670300Y286283D01*
X669925Y286117D01*
X670050Y287200D01*
X671175D01*
G01X673650Y284700D02*
X673942Y284742D01*
X674275Y284867D01*
X674483Y285075D01*
X674567Y285367D01*
X674483Y285658D01*
X674233Y285908D01*
X673858Y286033D01*
X673442D01*
X673192Y286117D01*
X672983Y286325D01*
X672900Y286617D01*
X673025Y286908D01*
X673317Y287117D01*
X673650Y287200D01*
X673983Y287117D01*
X674275Y286908D01*
X674400Y286617D01*
X674317Y286325D01*
X674108Y286117D01*
X673858Y286033D01*
X673442D01*
X673067Y285908D01*
X672817Y285658D01*
X672733Y285367D01*
X672817Y285075D01*
X673025Y284867D01*
X673358Y284742D01*
X673650Y284700D01*
G01X675958Y285742D02*
X676250Y286033D01*
X676500Y286200D01*
X676833Y286283D01*
X677125Y286200D01*
X677333Y286033D01*
X677500Y285783D01*
X677542Y285492D01*
X677500Y285242D01*
X677333Y284992D01*
X677083Y284783D01*
X676792Y284700D01*
X676458Y284783D01*
X676167Y285033D01*
X676000Y285408D01*
X675958Y285825D01*
X676042Y286367D01*
X676167Y286658D01*
X676375Y286950D01*
X676667Y287158D01*
X676958Y287200D01*
X677250Y287117D01*
X677458Y286908D01*
G01X666764Y280530D02*
Y283030D01*
X667805D01*
X668139Y282905D01*
X668347Y282738D01*
X668430Y282405D01*
X668347Y282072D01*
X668097Y281863D01*
X667805Y281738D01*
X666764D01*
G01X667805D02*
X668430Y280530D01*
G01X669780Y280905D02*
X670030Y280697D01*
X670322Y280572D01*
X670697Y280530D01*
X671072Y280613D01*
X671364Y280780D01*
X671572Y281072D01*
X671614Y281405D01*
X671530Y281738D01*
X671322Y281947D01*
X671030Y282113D01*
X670739Y282155D01*
X670447Y282113D01*
X670072Y281947D01*
X670197Y283030D01*
X671322D01*
G01X673797Y280530D02*
X674089Y280572D01*
X674422Y280697D01*
X674630Y280905D01*
X674714Y281197D01*
X674630Y281488D01*
X674380Y281738D01*
X674005Y281863D01*
X673589D01*
X673339Y281947D01*
X673130Y282155D01*
X673047Y282447D01*
X673172Y282738D01*
X673464Y282947D01*
X673797Y283030D01*
X674130Y282947D01*
X674422Y282738D01*
X674547Y282447D01*
X674464Y282155D01*
X674255Y281947D01*
X674005Y281863D01*
X673589D01*
X673214Y281738D01*
X672964Y281488D01*
X672880Y281197D01*
X672964Y280905D01*
X673172Y280697D01*
X673505Y280572D01*
X673797Y280530D01*
G01X676814D02*
X676897Y281072D01*
X677022Y281530D01*
X677189Y281947D01*
X677397Y282405D01*
X677730Y283030D01*
X676064D01*
G01X667717Y305767D02*
Y308267D01*
X668758D01*
X669092Y308142D01*
X669300Y307975D01*
X669383Y307642D01*
X669300Y307309D01*
X669050Y307100D01*
X668758Y306975D01*
X667717D01*
G01X668758D02*
X669383Y305767D01*
G01X670858Y306809D02*
X671150Y307100D01*
X671400Y307267D01*
X671733Y307350D01*
X672025Y307267D01*
X672233Y307100D01*
X672400Y306850D01*
X672442Y306559D01*
X672400Y306309D01*
X672233Y306059D01*
X671983Y305850D01*
X671692Y305767D01*
X671358Y305850D01*
X671067Y306100D01*
X670900Y306475D01*
X670858Y306892D01*
X670942Y307434D01*
X671067Y307725D01*
X671275Y308017D01*
X671567Y308225D01*
X671858Y308267D01*
X672150Y308184D01*
X672358Y307975D01*
G01X674750Y305767D02*
Y308267D01*
X674250Y307767D01*
G01Y305767D02*
X675250D01*
G01X677142Y306059D02*
X677433Y305850D01*
X677767Y305767D01*
X678100Y305850D01*
X678392Y306100D01*
X678600Y306475D01*
X678683Y306850D01*
Y307309D01*
X678600Y307684D01*
X678392Y308017D01*
X678142Y308184D01*
X677850Y308267D01*
X677517Y308184D01*
X677267Y308017D01*
X677100Y307767D01*
X677017Y307434D01*
X677100Y307142D01*
X677308Y306850D01*
X677558Y306684D01*
X677850Y306642D01*
X678183Y306725D01*
X678433Y306934D01*
X678683Y307309D01*
G01X666764Y272230D02*
Y274730D01*
X667805D01*
X668139Y274605D01*
X668347Y274438D01*
X668430Y274105D01*
X668347Y273772D01*
X668097Y273563D01*
X667805Y273438D01*
X666764D01*
G01X667805D02*
X668430Y272230D01*
G01X669780Y272605D02*
X670030Y272397D01*
X670322Y272272D01*
X670697Y272230D01*
X671072Y272313D01*
X671364Y272480D01*
X671572Y272772D01*
X671614Y273105D01*
X671530Y273438D01*
X671322Y273647D01*
X671030Y273813D01*
X670739Y273855D01*
X670447Y273813D01*
X670072Y273647D01*
X670197Y274730D01*
X671322D01*
G01X673714Y272230D02*
X673797Y272772D01*
X673922Y273230D01*
X674089Y273647D01*
X674297Y274105D01*
X674630Y274730D01*
X672964D01*
G01X676105Y273272D02*
X676397Y273563D01*
X676647Y273730D01*
X676980Y273813D01*
X677272Y273730D01*
X677480Y273563D01*
X677647Y273313D01*
X677689Y273022D01*
X677647Y272772D01*
X677480Y272522D01*
X677230Y272313D01*
X676939Y272230D01*
X676605Y272313D01*
X676314Y272563D01*
X676147Y272938D01*
X676105Y273355D01*
X676189Y273897D01*
X676314Y274188D01*
X676522Y274480D01*
X676814Y274688D01*
X677105Y274730D01*
X677397Y274647D01*
X677605Y274438D01*
G01X624334Y322517D02*
X621834D01*
Y323558D01*
X621959Y323892D01*
X622126Y324100D01*
X622459Y324183D01*
X622792Y324100D01*
X623001Y323850D01*
X623126Y323558D01*
Y322517D01*
G01Y323558D02*
X624334Y324183D01*
G01X623292Y325658D02*
X623001Y325950D01*
X622834Y326200D01*
X622751Y326533D01*
X622834Y326825D01*
X623001Y327033D01*
X623251Y327200D01*
X623542Y327242D01*
X623792Y327200D01*
X624042Y327033D01*
X624251Y326783D01*
X624334Y326492D01*
X624251Y326158D01*
X624001Y325867D01*
X623626Y325700D01*
X623209Y325658D01*
X622667Y325742D01*
X622376Y325867D01*
X622084Y326075D01*
X621876Y326367D01*
X621834Y326658D01*
X621917Y326950D01*
X622126Y327158D01*
G01X624042Y328842D02*
X624251Y329133D01*
X624334Y329467D01*
X624251Y329800D01*
X624001Y330092D01*
X623626Y330300D01*
X623251Y330383D01*
X622792D01*
X622417Y330300D01*
X622084Y330092D01*
X621917Y329842D01*
X621834Y329550D01*
X621917Y329217D01*
X622084Y328967D01*
X622334Y328800D01*
X622667Y328717D01*
X622959Y328800D01*
X623251Y329008D01*
X623417Y329258D01*
X623459Y329550D01*
X623376Y329883D01*
X623167Y330133D01*
X622792Y330383D01*
G01X623834Y331733D02*
X624126Y331983D01*
X624292Y332317D01*
X624334Y332692D01*
X624292Y333025D01*
X624084Y333358D01*
X623834Y333567D01*
X623584Y333608D01*
X623292Y333525D01*
X623084Y333233D01*
X623001Y332942D01*
Y332567D01*
G01Y332942D02*
X622876Y333192D01*
X622667Y333400D01*
X622417Y333483D01*
X622167Y333400D01*
X621959Y333192D01*
X621834Y332817D01*
X621876Y332442D01*
X622042Y332067D01*
G01X610834Y316517D02*
X608334D01*
Y317558D01*
X608459Y317892D01*
X608626Y318100D01*
X608959Y318183D01*
X609292Y318100D01*
X609501Y317850D01*
X609626Y317558D01*
Y316517D01*
G01Y317558D02*
X610834Y318183D01*
G01X609792Y319658D02*
X609501Y319950D01*
X609334Y320200D01*
X609251Y320533D01*
X609334Y320825D01*
X609501Y321033D01*
X609751Y321200D01*
X610042Y321242D01*
X610292Y321200D01*
X610542Y321033D01*
X610751Y320783D01*
X610834Y320492D01*
X610751Y320158D01*
X610501Y319867D01*
X610126Y319700D01*
X609709Y319658D01*
X609167Y319742D01*
X608876Y319867D01*
X608584Y320075D01*
X608376Y320367D01*
X608334Y320658D01*
X608417Y320950D01*
X608626Y321158D01*
G01X610542Y322842D02*
X610751Y323133D01*
X610834Y323467D01*
X610751Y323800D01*
X610501Y324092D01*
X610126Y324300D01*
X609751Y324383D01*
X609292D01*
X608917Y324300D01*
X608584Y324092D01*
X608417Y323842D01*
X608334Y323550D01*
X608417Y323217D01*
X608584Y322967D01*
X608834Y322800D01*
X609167Y322717D01*
X609459Y322800D01*
X609751Y323008D01*
X609917Y323258D01*
X609959Y323550D01*
X609876Y323883D01*
X609667Y324133D01*
X609292Y324383D01*
G01X610834Y327150D02*
X608334D01*
X610126Y325608D01*
Y327692D01*
G01X645067Y371892D02*
X644817Y372017D01*
X644525Y372100D01*
X644192D01*
X643817Y371975D01*
X643525Y371767D01*
X643317Y371517D01*
X643150Y371100D01*
X643108Y370725D01*
X643192Y370350D01*
X643317Y370100D01*
X643567Y369850D01*
X643858Y369683D01*
X644150Y369600D01*
X644442D01*
X644733Y369683D01*
X644983Y369808D01*
X645192Y369975D01*
G01X647750Y369600D02*
Y372100D01*
X646208Y370308D01*
X648292D01*
G01X650350Y369600D02*
X650642Y369642D01*
X650975Y369767D01*
X651183Y369975D01*
X651267Y370267D01*
X651183Y370558D01*
X650933Y370808D01*
X650558Y370933D01*
X650142D01*
X649892Y371017D01*
X649683Y371225D01*
X649600Y371517D01*
X649725Y371808D01*
X650017Y372017D01*
X650350Y372100D01*
X650683Y372017D01*
X650975Y371808D01*
X651100Y371517D01*
X651017Y371225D01*
X650808Y371017D01*
X650558Y370933D01*
X650142D01*
X649767Y370808D01*
X649517Y370558D01*
X649433Y370267D01*
X649517Y369975D01*
X649725Y369767D01*
X650058Y369642D01*
X650350Y369600D01*
G01X652658Y371683D02*
X652908Y371933D01*
X653200Y372058D01*
X653533Y372100D01*
X653950Y372017D01*
X654242Y371808D01*
X654325Y371558D01*
X654283Y371308D01*
X654117Y371100D01*
X653283Y370683D01*
X652908Y370392D01*
X652658Y369975D01*
X652575Y369600D01*
X654325D01*
G01X616908Y386767D02*
X616783Y386517D01*
X616700Y386225D01*
Y385892D01*
X616825Y385517D01*
X617033Y385225D01*
X617283Y385017D01*
X617700Y384850D01*
X618075Y384808D01*
X618450Y384892D01*
X618700Y385017D01*
X618950Y385267D01*
X619117Y385558D01*
X619200Y385850D01*
Y386142D01*
X619117Y386433D01*
X618992Y386683D01*
X618825Y386892D01*
G01X619200Y389450D02*
X616700D01*
X618492Y387908D01*
Y389992D01*
G01X619200Y392050D02*
X619158Y392342D01*
X619033Y392675D01*
X618825Y392883D01*
X618533Y392967D01*
X618242Y392883D01*
X617992Y392633D01*
X617867Y392258D01*
Y391842D01*
X617783Y391592D01*
X617575Y391383D01*
X617283Y391300D01*
X616992Y391425D01*
X616783Y391717D01*
X616700Y392050D01*
X616783Y392383D01*
X616992Y392675D01*
X617283Y392800D01*
X617575Y392717D01*
X617783Y392508D01*
X617867Y392258D01*
Y391842D01*
X617992Y391467D01*
X618242Y391217D01*
X618533Y391133D01*
X618825Y391217D01*
X619033Y391425D01*
X619158Y391758D01*
X619200Y392050D01*
G01Y395650D02*
X616700D01*
X618492Y394108D01*
Y396192D01*
G01X646100Y352617D02*
X643600D01*
Y353658D01*
X643725Y353992D01*
X643892Y354200D01*
X644225Y354283D01*
X644558Y354200D01*
X644767Y353950D01*
X644892Y353658D01*
Y352617D01*
G01Y353658D02*
X646100Y354283D01*
G01X645058Y355758D02*
X644767Y356050D01*
X644600Y356300D01*
X644517Y356633D01*
X644600Y356925D01*
X644767Y357133D01*
X645017Y357300D01*
X645308Y357342D01*
X645558Y357300D01*
X645808Y357133D01*
X646017Y356883D01*
X646100Y356592D01*
X646017Y356258D01*
X645767Y355967D01*
X645392Y355800D01*
X644975Y355758D01*
X644433Y355842D01*
X644142Y355967D01*
X643850Y356175D01*
X643642Y356467D01*
X643600Y356758D01*
X643683Y357050D01*
X643892Y357258D01*
G01X646100Y359650D02*
X646058Y359942D01*
X645933Y360275D01*
X645725Y360483D01*
X645433Y360567D01*
X645142Y360483D01*
X644892Y360233D01*
X644767Y359858D01*
Y359442D01*
X644683Y359192D01*
X644475Y358983D01*
X644183Y358900D01*
X643892Y359025D01*
X643683Y359317D01*
X643600Y359650D01*
X643683Y359983D01*
X643892Y360275D01*
X644183Y360400D01*
X644475Y360317D01*
X644683Y360108D01*
X644767Y359858D01*
Y359442D01*
X644892Y359067D01*
X645142Y358817D01*
X645433Y358733D01*
X645725Y358817D01*
X645933Y359025D01*
X646058Y359358D01*
X646100Y359650D01*
G01X645808Y362042D02*
X646017Y362333D01*
X646100Y362667D01*
X646017Y363000D01*
X645767Y363292D01*
X645392Y363500D01*
X645017Y363583D01*
X644558D01*
X644183Y363500D01*
X643850Y363292D01*
X643683Y363042D01*
X643600Y362750D01*
X643683Y362417D01*
X643850Y362167D01*
X644100Y362000D01*
X644433Y361917D01*
X644725Y362000D01*
X645017Y362208D01*
X645183Y362458D01*
X645225Y362750D01*
X645142Y363083D01*
X644933Y363333D01*
X644558Y363583D01*
G01X641067Y363991D02*
X637067D01*
Y356591D01*
G01X658600Y369717D02*
X656100D01*
Y370758D01*
X656225Y371092D01*
X656392Y371300D01*
X656725Y371383D01*
X657058Y371300D01*
X657267Y371050D01*
X657392Y370758D01*
Y369717D01*
G01Y370758D02*
X658600Y371383D01*
G01X657558Y372858D02*
X657267Y373150D01*
X657100Y373400D01*
X657017Y373733D01*
X657100Y374025D01*
X657267Y374233D01*
X657517Y374400D01*
X657808Y374442D01*
X658058Y374400D01*
X658308Y374233D01*
X658517Y373983D01*
X658600Y373692D01*
X658517Y373358D01*
X658267Y373067D01*
X657892Y372900D01*
X657475Y372858D01*
X656933Y372942D01*
X656642Y373067D01*
X656350Y373275D01*
X656142Y373567D01*
X656100Y373858D01*
X656183Y374150D01*
X656392Y374358D01*
G01X658308Y376042D02*
X658517Y376333D01*
X658600Y376667D01*
X658517Y377000D01*
X658267Y377292D01*
X657892Y377500D01*
X657517Y377583D01*
X657058D01*
X656683Y377500D01*
X656350Y377292D01*
X656183Y377042D01*
X656100Y376750D01*
X656183Y376417D01*
X656350Y376167D01*
X656600Y376000D01*
X656933Y375917D01*
X657225Y376000D01*
X657517Y376208D01*
X657683Y376458D01*
X657725Y376750D01*
X657642Y377083D01*
X657433Y377333D01*
X657058Y377583D01*
G01X656100Y379850D02*
X656183Y379517D01*
X656392Y379267D01*
X656642Y379100D01*
X656975Y378975D01*
X657350Y378933D01*
X657725Y378975D01*
X658058Y379100D01*
X658308Y379267D01*
X658517Y379517D01*
X658600Y379850D01*
X658517Y380183D01*
X658308Y380433D01*
X658058Y380600D01*
X657725Y380725D01*
X657350Y380767D01*
X656975Y380725D01*
X656642Y380600D01*
X656392Y380433D01*
X656183Y380183D01*
X656100Y379850D01*
G01X632661Y365356D02*
X636661D01*
Y372756D01*
G01X622900Y385017D02*
X620400D01*
Y386058D01*
X620525Y386392D01*
X620692Y386600D01*
X621025Y386683D01*
X621358Y386600D01*
X621567Y386350D01*
X621692Y386058D01*
Y385017D01*
G01Y386058D02*
X622900Y386683D01*
G01X621858Y388158D02*
X621567Y388450D01*
X621400Y388700D01*
X621317Y389033D01*
X621400Y389325D01*
X621567Y389533D01*
X621817Y389700D01*
X622108Y389742D01*
X622358Y389700D01*
X622608Y389533D01*
X622817Y389283D01*
X622900Y388992D01*
X622817Y388658D01*
X622567Y388367D01*
X622192Y388200D01*
X621775Y388158D01*
X621233Y388242D01*
X620942Y388367D01*
X620650Y388575D01*
X620442Y388867D01*
X620400Y389158D01*
X620483Y389450D01*
X620692Y389658D01*
G01X622608Y391342D02*
X622817Y391633D01*
X622900Y391967D01*
X622817Y392300D01*
X622567Y392592D01*
X622192Y392800D01*
X621817Y392883D01*
X621358D01*
X620983Y392800D01*
X620650Y392592D01*
X620483Y392342D01*
X620400Y392050D01*
X620483Y391717D01*
X620650Y391467D01*
X620900Y391300D01*
X621233Y391217D01*
X621525Y391300D01*
X621817Y391508D01*
X621983Y391758D01*
X622025Y392050D01*
X621942Y392383D01*
X621733Y392633D01*
X621358Y392883D01*
G01X622900Y395150D02*
X620400D01*
X620900Y394650D01*
G01X622900D02*
Y395650D01*
G01X618822Y370464D02*
X622822D01*
Y377864D01*
G01X615500Y385017D02*
X613000D01*
Y386058D01*
X613125Y386392D01*
X613292Y386600D01*
X613625Y386683D01*
X613958Y386600D01*
X614167Y386350D01*
X614292Y386058D01*
Y385017D01*
G01Y386058D02*
X615500Y386683D01*
G01X614458Y388158D02*
X614167Y388450D01*
X614000Y388700D01*
X613917Y389033D01*
X614000Y389325D01*
X614167Y389533D01*
X614417Y389700D01*
X614708Y389742D01*
X614958Y389700D01*
X615208Y389533D01*
X615417Y389283D01*
X615500Y388992D01*
X615417Y388658D01*
X615167Y388367D01*
X614792Y388200D01*
X614375Y388158D01*
X613833Y388242D01*
X613542Y388367D01*
X613250Y388575D01*
X613042Y388867D01*
X613000Y389158D01*
X613083Y389450D01*
X613292Y389658D01*
G01X615208Y391342D02*
X615417Y391633D01*
X615500Y391967D01*
X615417Y392300D01*
X615167Y392592D01*
X614792Y392800D01*
X614417Y392883D01*
X613958D01*
X613583Y392800D01*
X613250Y392592D01*
X613083Y392342D01*
X613000Y392050D01*
X613083Y391717D01*
X613250Y391467D01*
X613500Y391300D01*
X613833Y391217D01*
X614125Y391300D01*
X614417Y391508D01*
X614583Y391758D01*
X614625Y392050D01*
X614542Y392383D01*
X614333Y392633D01*
X613958Y392883D01*
G01X613417Y394358D02*
X613167Y394608D01*
X613042Y394900D01*
X613000Y395233D01*
X613083Y395650D01*
X613292Y395942D01*
X613542Y396025D01*
X613792Y395983D01*
X614000Y395817D01*
X614417Y394983D01*
X614708Y394608D01*
X615125Y394358D01*
X615500Y394275D01*
Y396025D01*
G01X615223Y377927D02*
X611223D01*
Y370527D01*
G01X621239Y335479D02*
X625239D01*
Y342879D01*
G01X606500Y334000D02*
X610500D01*
Y341400D01*
G01X639147Y402197D02*
X635147D01*
Y394797D01*
G01X643317Y373300D02*
Y375800D01*
X644358D01*
X644692Y375675D01*
X644900Y375508D01*
X644983Y375175D01*
X644900Y374842D01*
X644650Y374633D01*
X644358Y374508D01*
X643317D01*
G01X644358D02*
X644983Y373300D01*
G01X647250D02*
X647542Y373342D01*
X647875Y373467D01*
X648083Y373675D01*
X648167Y373967D01*
X648083Y374258D01*
X647833Y374508D01*
X647458Y374633D01*
X647042D01*
X646792Y374717D01*
X646583Y374925D01*
X646500Y375217D01*
X646625Y375508D01*
X646917Y375717D01*
X647250Y375800D01*
X647583Y375717D01*
X647875Y375508D01*
X648000Y375217D01*
X647917Y374925D01*
X647708Y374717D01*
X647458Y374633D01*
X647042D01*
X646667Y374508D01*
X646417Y374258D01*
X646333Y373967D01*
X646417Y373675D01*
X646625Y373467D01*
X646958Y373342D01*
X647250Y373300D01*
G01X649433Y373800D02*
X649683Y373508D01*
X650017Y373342D01*
X650392Y373300D01*
X650725Y373342D01*
X651058Y373550D01*
X651267Y373800D01*
X651308Y374050D01*
X651225Y374342D01*
X650933Y374550D01*
X650642Y374633D01*
X650267D01*
G01X650642D02*
X650892Y374758D01*
X651100Y374967D01*
X651183Y375217D01*
X651100Y375467D01*
X650892Y375675D01*
X650517Y375800D01*
X650142Y375758D01*
X649767Y375592D01*
G01X652533Y373800D02*
X652783Y373508D01*
X653117Y373342D01*
X653492Y373300D01*
X653825Y373342D01*
X654158Y373550D01*
X654367Y373800D01*
X654408Y374050D01*
X654325Y374342D01*
X654033Y374550D01*
X653742Y374633D01*
X653367D01*
G01X653742D02*
X653992Y374758D01*
X654200Y374967D01*
X654283Y375217D01*
X654200Y375467D01*
X653992Y375675D01*
X653617Y375800D01*
X653242Y375758D01*
X652867Y375592D01*
G01X628322Y377305D02*
Y373305D01*
X635722D01*
G01X643317Y377000D02*
Y379500D01*
X644358D01*
X644692Y379375D01*
X644900Y379208D01*
X644983Y378875D01*
X644900Y378542D01*
X644650Y378333D01*
X644358Y378208D01*
X643317D01*
G01X644358D02*
X644983Y377000D01*
G01X646333Y377375D02*
X646583Y377167D01*
X646875Y377042D01*
X647250Y377000D01*
X647625Y377083D01*
X647917Y377250D01*
X648125Y377542D01*
X648167Y377875D01*
X648083Y378208D01*
X647875Y378417D01*
X647583Y378583D01*
X647292Y378625D01*
X647000Y378583D01*
X646625Y378417D01*
X646750Y379500D01*
X647875D01*
G01X649642Y377292D02*
X649933Y377083D01*
X650267Y377000D01*
X650600Y377083D01*
X650892Y377333D01*
X651100Y377708D01*
X651183Y378083D01*
Y378542D01*
X651100Y378917D01*
X650892Y379250D01*
X650642Y379417D01*
X650350Y379500D01*
X650017Y379417D01*
X649767Y379250D01*
X649600Y379000D01*
X649517Y378667D01*
X649600Y378375D01*
X649808Y378083D01*
X650058Y377917D01*
X650350Y377875D01*
X650683Y377958D01*
X650933Y378167D01*
X651183Y378542D01*
G01X653367Y377000D02*
X653450Y377542D01*
X653575Y378000D01*
X653742Y378417D01*
X653950Y378875D01*
X654283Y379500D01*
X652617D01*
G01X635722Y377591D02*
Y381591D01*
X628322D01*
G01X658334Y388400D02*
X658292Y388067D01*
X658126Y387775D01*
X657876Y387525D01*
X657584Y387358D01*
X657251Y387275D01*
X656917D01*
X656584Y387358D01*
X656292Y387525D01*
X656042Y387775D01*
X655876Y388067D01*
X655834Y388400D01*
X655876Y388733D01*
X656042Y389025D01*
X656292Y389275D01*
X656584Y389442D01*
X656917Y389525D01*
X657251D01*
X657584Y389442D01*
X657876Y389275D01*
X658126Y389025D01*
X658292Y388733D01*
X658334Y388400D01*
G01X657667Y388733D02*
X658334Y389233D01*
G01Y391500D02*
X655834D01*
X656334Y391000D01*
G01X658334D02*
Y392000D01*
G01X657959Y393683D02*
X658167Y393933D01*
X658292Y394225D01*
X658334Y394600D01*
X658251Y394975D01*
X658084Y395267D01*
X657792Y395475D01*
X657459Y395517D01*
X657126Y395433D01*
X656917Y395225D01*
X656751Y394933D01*
X656709Y394642D01*
X656751Y394350D01*
X656917Y393975D01*
X655834Y394100D01*
Y395225D01*
G01X639720Y402244D02*
Y388244D01*
G01X652720D02*
Y402244D01*
G01X639720Y388244D02*
X652720D01*
G01X610373Y376211D02*
Y390211D01*
G01X635234Y346683D02*
X637026D01*
X637401Y346850D01*
X637651Y347183D01*
X637734Y347600D01*
X637651Y348017D01*
X637401Y348350D01*
X637026Y348517D01*
X635234D01*
G01X637734Y351200D02*
X635234D01*
X637026Y349658D01*
Y351742D01*
G01X637234Y352883D02*
X637526Y353133D01*
X637692Y353467D01*
X637734Y353842D01*
X637692Y354175D01*
X637484Y354508D01*
X637234Y354717D01*
X636984Y354758D01*
X636692Y354675D01*
X636484Y354383D01*
X636401Y354092D01*
Y353717D01*
G01Y354092D02*
X636276Y354342D01*
X636067Y354550D01*
X635817Y354633D01*
X635567Y354550D01*
X635359Y354342D01*
X635234Y353967D01*
X635276Y353592D01*
X635442Y353217D01*
G01X633934Y351900D02*
X623734D01*
G01X633934Y356500D02*
Y351900D01*
G01X623034Y356500D02*
X633934D01*
G01X623034D02*
Y345200D01*
G01X624234Y354200D02*
X623034Y355400D01*
G01X624234Y354200D02*
X623034Y353000D01*
G01X611092Y355816D02*
X611242D01*
X612492Y354566D01*
X611292Y353366D01*
X611042D01*
G01X611092Y345816D02*
Y363016D01*
X620992D01*
Y345816D01*
X611092D01*
G01X667600Y441200D02*
Y445200D01*
X660200D01*
G01X653334Y418517D02*
X650834D01*
Y419558D01*
X650959Y419892D01*
X651126Y420100D01*
X651459Y420183D01*
X651792Y420100D01*
X652001Y419850D01*
X652126Y419558D01*
Y418517D01*
G01Y419558D02*
X653334Y420183D01*
G01X652292Y421658D02*
X652001Y421950D01*
X651834Y422200D01*
X651751Y422533D01*
X651834Y422825D01*
X652001Y423033D01*
X652251Y423200D01*
X652542Y423242D01*
X652792Y423200D01*
X653042Y423033D01*
X653251Y422783D01*
X653334Y422492D01*
X653251Y422158D01*
X653001Y421867D01*
X652626Y421700D01*
X652209Y421658D01*
X651667Y421742D01*
X651376Y421867D01*
X651084Y422075D01*
X650876Y422367D01*
X650834Y422658D01*
X650917Y422950D01*
X651126Y423158D01*
G01X651251Y424758D02*
X651001Y425008D01*
X650876Y425300D01*
X650834Y425633D01*
X650917Y426050D01*
X651126Y426342D01*
X651376Y426425D01*
X651626Y426383D01*
X651834Y426217D01*
X652251Y425383D01*
X652542Y425008D01*
X652959Y424758D01*
X653334Y424675D01*
Y426425D01*
G01X652834Y427733D02*
X653126Y427983D01*
X653292Y428317D01*
X653334Y428692D01*
X653292Y429025D01*
X653084Y429358D01*
X652834Y429567D01*
X652584Y429608D01*
X652292Y429525D01*
X652084Y429233D01*
X652001Y428942D01*
Y428567D01*
G01Y428942D02*
X651876Y429192D01*
X651667Y429400D01*
X651417Y429483D01*
X651167Y429400D01*
X650959Y429192D01*
X650834Y428817D01*
X650876Y428442D01*
X651042Y428067D01*
G01X648469Y422886D02*
X644469D01*
Y415486D01*
G01X637834Y408517D02*
X635334D01*
Y409558D01*
X635459Y409892D01*
X635626Y410100D01*
X635959Y410183D01*
X636292Y410100D01*
X636501Y409850D01*
X636626Y409558D01*
Y408517D01*
G01Y409558D02*
X637834Y410183D01*
G01X636792Y411658D02*
X636501Y411950D01*
X636334Y412200D01*
X636251Y412533D01*
X636334Y412825D01*
X636501Y413033D01*
X636751Y413200D01*
X637042Y413242D01*
X637292Y413200D01*
X637542Y413033D01*
X637751Y412783D01*
X637834Y412492D01*
X637751Y412158D01*
X637501Y411867D01*
X637126Y411700D01*
X636709Y411658D01*
X636167Y411742D01*
X635876Y411867D01*
X635584Y412075D01*
X635376Y412367D01*
X635334Y412658D01*
X635417Y412950D01*
X635626Y413158D01*
G01X635751Y414758D02*
X635501Y415008D01*
X635376Y415300D01*
X635334Y415633D01*
X635417Y416050D01*
X635626Y416342D01*
X635876Y416425D01*
X636126Y416383D01*
X636334Y416217D01*
X636751Y415383D01*
X637042Y415008D01*
X637459Y414758D01*
X637834Y414675D01*
Y416425D01*
G01X636792Y417858D02*
X636501Y418150D01*
X636334Y418400D01*
X636251Y418733D01*
X636334Y419025D01*
X636501Y419233D01*
X636751Y419400D01*
X637042Y419442D01*
X637292Y419400D01*
X637542Y419233D01*
X637751Y418983D01*
X637834Y418692D01*
X637751Y418358D01*
X637501Y418067D01*
X637126Y417900D01*
X636709Y417858D01*
X636167Y417942D01*
X635876Y418067D01*
X635584Y418275D01*
X635376Y418567D01*
X635334Y418858D01*
X635417Y419150D01*
X635626Y419358D01*
G01X652720Y402244D02*
X639720D01*
G01X656546Y446121D02*
X658346Y448221D01*
X660546Y446121D01*
G01X664146Y446021D02*
Y465221D01*
X652946D01*
Y446021D01*
X664146D01*
Y446421D01*
G01X650834Y404517D02*
X653334D01*
Y406183D01*
G01Y409283D02*
Y407617D01*
X650834D01*
Y409283D01*
G01X652042Y408617D02*
Y407617D01*
G01X653334Y410633D02*
X650834D01*
Y411467D01*
X650959Y411800D01*
X651126Y412050D01*
X651376Y412258D01*
X651667Y412425D01*
X652084Y412467D01*
X652501Y412425D01*
X652792Y412258D01*
X653042Y412050D01*
X653209Y411800D01*
X653334Y411467D01*
Y410633D01*
G01X652959Y413733D02*
X653167Y413983D01*
X653292Y414275D01*
X653334Y414650D01*
X653251Y415025D01*
X653084Y415317D01*
X652792Y415525D01*
X652459Y415567D01*
X652126Y415483D01*
X651917Y415275D01*
X651751Y414983D01*
X651709Y414692D01*
X651751Y414400D01*
X651917Y414025D01*
X650834Y414150D01*
Y415275D01*
G01X643777Y404137D02*
Y414937D01*
X648977D01*
Y404137D01*
X643777D01*
G01X657042Y505967D02*
X656917Y505717D01*
X656834Y505425D01*
Y505092D01*
X656959Y504717D01*
X657167Y504425D01*
X657417Y504217D01*
X657834Y504050D01*
X658209Y504008D01*
X658584Y504092D01*
X658834Y504217D01*
X659084Y504467D01*
X659251Y504758D01*
X659334Y505050D01*
Y505342D01*
X659251Y505633D01*
X659126Y505883D01*
X658959Y506092D01*
G01X657251Y507358D02*
X657001Y507608D01*
X656876Y507900D01*
X656834Y508233D01*
X656917Y508650D01*
X657126Y508942D01*
X657376Y509025D01*
X657626Y508983D01*
X657834Y508817D01*
X658251Y507983D01*
X658542Y507608D01*
X658959Y507358D01*
X659334Y507275D01*
Y509025D01*
G01X656834Y511250D02*
X656917Y510917D01*
X657126Y510667D01*
X657376Y510500D01*
X657709Y510375D01*
X658084Y510333D01*
X658459Y510375D01*
X658792Y510500D01*
X659042Y510667D01*
X659251Y510917D01*
X659334Y511250D01*
X659251Y511583D01*
X659042Y511833D01*
X658792Y512000D01*
X658459Y512125D01*
X658084Y512167D01*
X657709Y512125D01*
X657376Y512000D01*
X657126Y511833D01*
X656917Y511583D01*
X656834Y511250D01*
G01X658834Y513433D02*
X659126Y513683D01*
X659292Y514017D01*
X659334Y514392D01*
X659292Y514725D01*
X659084Y515058D01*
X658834Y515267D01*
X658584Y515308D01*
X658292Y515225D01*
X658084Y514933D01*
X658001Y514642D01*
Y514267D01*
G01Y514642D02*
X657876Y514892D01*
X657667Y515100D01*
X657417Y515183D01*
X657167Y515100D01*
X656959Y514892D01*
X656834Y514517D01*
X656876Y514142D01*
X657042Y513767D01*
G01X664842Y505967D02*
X664717Y505717D01*
X664634Y505425D01*
Y505092D01*
X664759Y504717D01*
X664967Y504425D01*
X665217Y504217D01*
X665634Y504050D01*
X666009Y504008D01*
X666384Y504092D01*
X666634Y504217D01*
X666884Y504467D01*
X667051Y504758D01*
X667134Y505050D01*
Y505342D01*
X667051Y505633D01*
X666926Y505883D01*
X666759Y506092D01*
G01X665051Y507358D02*
X664801Y507608D01*
X664676Y507900D01*
X664634Y508233D01*
X664717Y508650D01*
X664926Y508942D01*
X665176Y509025D01*
X665426Y508983D01*
X665634Y508817D01*
X666051Y507983D01*
X666342Y507608D01*
X666759Y507358D01*
X667134Y507275D01*
Y509025D01*
G01X664634Y511250D02*
X664717Y510917D01*
X664926Y510667D01*
X665176Y510500D01*
X665509Y510375D01*
X665884Y510333D01*
X666259Y510375D01*
X666592Y510500D01*
X666842Y510667D01*
X667051Y510917D01*
X667134Y511250D01*
X667051Y511583D01*
X666842Y511833D01*
X666592Y512000D01*
X666259Y512125D01*
X665884Y512167D01*
X665509Y512125D01*
X665176Y512000D01*
X664926Y511833D01*
X664717Y511583D01*
X664634Y511250D01*
G01X666759Y513433D02*
X666967Y513683D01*
X667092Y513975D01*
X667134Y514350D01*
X667051Y514725D01*
X666884Y515017D01*
X666592Y515225D01*
X666259Y515267D01*
X665926Y515183D01*
X665717Y514975D01*
X665551Y514683D01*
X665509Y514392D01*
X665551Y514100D01*
X665717Y513725D01*
X664634Y513850D01*
Y514975D01*
G01X660942Y506267D02*
X660817Y506017D01*
X660734Y505725D01*
Y505392D01*
X660859Y505017D01*
X661067Y504725D01*
X661317Y504517D01*
X661734Y504350D01*
X662109Y504308D01*
X662484Y504392D01*
X662734Y504517D01*
X662984Y504767D01*
X663151Y505058D01*
X663234Y505350D01*
Y505642D01*
X663151Y505933D01*
X663026Y506183D01*
X662859Y506392D01*
G01X661151Y507658D02*
X660901Y507908D01*
X660776Y508200D01*
X660734Y508533D01*
X660817Y508950D01*
X661026Y509242D01*
X661276Y509325D01*
X661526Y509283D01*
X661734Y509117D01*
X662151Y508283D01*
X662442Y507908D01*
X662859Y507658D01*
X663234Y507575D01*
Y509325D01*
G01X660734Y511550D02*
X660817Y511217D01*
X661026Y510967D01*
X661276Y510800D01*
X661609Y510675D01*
X661984Y510633D01*
X662359Y510675D01*
X662692Y510800D01*
X662942Y510967D01*
X663151Y511217D01*
X663234Y511550D01*
X663151Y511883D01*
X662942Y512133D01*
X662692Y512300D01*
X662359Y512425D01*
X661984Y512467D01*
X661609Y512425D01*
X661276Y512300D01*
X661026Y512133D01*
X660817Y511883D01*
X660734Y511550D01*
G01X663234Y515150D02*
X660734D01*
X662526Y513608D01*
Y515692D01*
G01X657917Y474667D02*
Y477167D01*
X658958D01*
X659292Y477042D01*
X659500Y476875D01*
X659583Y476542D01*
X659500Y476209D01*
X659250Y476000D01*
X658958Y475875D01*
X657917D01*
G01X658958D02*
X659583Y474667D01*
G01X660933Y475042D02*
X661183Y474834D01*
X661475Y474709D01*
X661850Y474667D01*
X662225Y474750D01*
X662517Y474917D01*
X662725Y475209D01*
X662767Y475542D01*
X662683Y475875D01*
X662475Y476084D01*
X662183Y476250D01*
X661892Y476292D01*
X661600Y476250D01*
X661225Y476084D01*
X661350Y477167D01*
X662475D01*
G01X664158Y476750D02*
X664408Y477000D01*
X664700Y477125D01*
X665033Y477167D01*
X665450Y477084D01*
X665742Y476875D01*
X665825Y476625D01*
X665783Y476375D01*
X665617Y476167D01*
X664783Y475750D01*
X664408Y475459D01*
X664158Y475042D01*
X664075Y474667D01*
X665825D01*
G01X667133Y475042D02*
X667383Y474834D01*
X667675Y474709D01*
X668050Y474667D01*
X668425Y474750D01*
X668717Y474917D01*
X668925Y475209D01*
X668967Y475542D01*
X668883Y475875D01*
X668675Y476084D01*
X668383Y476250D01*
X668092Y476292D01*
X667800Y476250D01*
X667425Y476084D01*
X667550Y477167D01*
X668675D01*
G01X660817Y497167D02*
Y499667D01*
X661858D01*
X662192Y499542D01*
X662400Y499375D01*
X662483Y499042D01*
X662400Y498709D01*
X662150Y498500D01*
X661858Y498375D01*
X660817D01*
G01X661858D02*
X662483Y497167D01*
G01X663833Y497542D02*
X664083Y497334D01*
X664375Y497209D01*
X664750Y497167D01*
X665125Y497250D01*
X665417Y497417D01*
X665625Y497709D01*
X665667Y498042D01*
X665583Y498375D01*
X665375Y498584D01*
X665083Y498750D01*
X664792Y498792D01*
X664500Y498750D01*
X664125Y498584D01*
X664250Y499667D01*
X665375D01*
G01X667058Y499250D02*
X667308Y499500D01*
X667600Y499625D01*
X667933Y499667D01*
X668350Y499584D01*
X668642Y499375D01*
X668725Y499125D01*
X668683Y498875D01*
X668517Y498667D01*
X667683Y498250D01*
X667308Y497959D01*
X667058Y497542D01*
X666975Y497167D01*
X668725D01*
G01X670867D02*
X670950Y497709D01*
X671075Y498167D01*
X671242Y498584D01*
X671450Y499042D01*
X671783Y499667D01*
X670117D01*
G01X655134Y504217D02*
X652634D01*
Y505258D01*
X652759Y505592D01*
X652926Y505800D01*
X653259Y505883D01*
X653592Y505800D01*
X653801Y505550D01*
X653926Y505258D01*
Y504217D01*
G01Y505258D02*
X655134Y505883D01*
G01X654759Y507233D02*
X654967Y507483D01*
X655092Y507775D01*
X655134Y508150D01*
X655051Y508525D01*
X654884Y508817D01*
X654592Y509025D01*
X654259Y509067D01*
X653926Y508983D01*
X653717Y508775D01*
X653551Y508483D01*
X653509Y508192D01*
X653551Y507900D01*
X653717Y507525D01*
X652634Y507650D01*
Y508775D01*
G01X655134Y511250D02*
X652634D01*
X653134Y510750D01*
G01X655134D02*
Y511750D01*
G01Y514267D02*
X654592Y514350D01*
X654134Y514475D01*
X653717Y514642D01*
X653259Y514850D01*
X652634Y515183D01*
Y513517D01*
G01X638160Y519843D02*
X642160D01*
Y527243D01*
G01X642517Y493667D02*
Y496167D01*
X643558D01*
X643892Y496042D01*
X644100Y495875D01*
X644183Y495542D01*
X644100Y495209D01*
X643850Y495000D01*
X643558Y494875D01*
X642517D01*
G01X643558D02*
X644183Y493667D01*
G01X645533Y494042D02*
X645783Y493834D01*
X646075Y493709D01*
X646450Y493667D01*
X646825Y493750D01*
X647117Y493917D01*
X647325Y494209D01*
X647367Y494542D01*
X647283Y494875D01*
X647075Y495084D01*
X646783Y495250D01*
X646492Y495292D01*
X646200Y495250D01*
X645825Y495084D01*
X645950Y496167D01*
X647075D01*
G01X649550Y493667D02*
Y496167D01*
X649050Y495667D01*
G01Y493667D02*
X650050D01*
G01X651942Y493959D02*
X652233Y493750D01*
X652567Y493667D01*
X652900Y493750D01*
X653192Y494000D01*
X653400Y494375D01*
X653483Y494750D01*
Y495209D01*
X653400Y495584D01*
X653192Y495917D01*
X652942Y496084D01*
X652650Y496167D01*
X652317Y496084D01*
X652067Y495917D01*
X651900Y495667D01*
X651817Y495334D01*
X651900Y495042D01*
X652108Y494750D01*
X652358Y494584D01*
X652650Y494542D01*
X652983Y494625D01*
X653233Y494834D01*
X653483Y495209D01*
G01X644400Y506100D02*
Y502100D01*
X651800D01*
G01X651467Y467366D02*
Y469866D01*
X652467D01*
X652800Y469741D01*
X653050Y469449D01*
X653133Y469116D01*
X653050Y468783D01*
X652842Y468533D01*
X652467Y468408D01*
X651467D01*
G01X655400Y467366D02*
X655067Y467408D01*
X654775Y467574D01*
X654525Y467824D01*
X654358Y468116D01*
X654275Y468449D01*
Y468783D01*
X654358Y469116D01*
X654525Y469408D01*
X654775Y469658D01*
X655067Y469824D01*
X655400Y469866D01*
X655733Y469824D01*
X656025Y469658D01*
X656275Y469408D01*
X656442Y469116D01*
X656525Y468783D01*
Y468449D01*
X656442Y468116D01*
X656275Y467824D01*
X656025Y467574D01*
X655733Y467408D01*
X655400Y467366D01*
G01X655733Y468033D02*
X656233Y467366D01*
G01X657583Y467741D02*
X657833Y467533D01*
X658125Y467408D01*
X658500Y467366D01*
X658875Y467449D01*
X659167Y467616D01*
X659375Y467908D01*
X659417Y468241D01*
X659333Y468574D01*
X659125Y468783D01*
X658833Y468949D01*
X658542Y468991D01*
X658250Y468949D01*
X657875Y468783D01*
X658000Y469866D01*
X659125D01*
G01X667134Y487550D02*
X667092Y487217D01*
X666926Y486925D01*
X666676Y486675D01*
X666384Y486508D01*
X666051Y486425D01*
X665717D01*
X665384Y486508D01*
X665092Y486675D01*
X664842Y486925D01*
X664676Y487217D01*
X664634Y487550D01*
X664676Y487883D01*
X664842Y488175D01*
X665092Y488425D01*
X665384Y488592D01*
X665717Y488675D01*
X666051D01*
X666384Y488592D01*
X666676Y488425D01*
X666926Y488175D01*
X667092Y487883D01*
X667134Y487550D01*
G01X666467Y487883D02*
X667134Y488383D01*
G01X666092Y489858D02*
X665801Y490150D01*
X665634Y490400D01*
X665551Y490733D01*
X665634Y491025D01*
X665801Y491233D01*
X666051Y491400D01*
X666342Y491442D01*
X666592Y491400D01*
X666842Y491233D01*
X667051Y490983D01*
X667134Y490692D01*
X667051Y490358D01*
X666801Y490067D01*
X666426Y489900D01*
X666009Y489858D01*
X665467Y489942D01*
X665176Y490067D01*
X664884Y490275D01*
X664676Y490567D01*
X664634Y490858D01*
X664717Y491150D01*
X664926Y491358D01*
G01X663034Y487650D02*
X662992Y487317D01*
X662826Y487025D01*
X662576Y486775D01*
X662284Y486608D01*
X661951Y486525D01*
X661617D01*
X661284Y486608D01*
X660992Y486775D01*
X660742Y487025D01*
X660576Y487317D01*
X660534Y487650D01*
X660576Y487983D01*
X660742Y488275D01*
X660992Y488525D01*
X661284Y488692D01*
X661617Y488775D01*
X661951D01*
X662284Y488692D01*
X662576Y488525D01*
X662826Y488275D01*
X662992Y487983D01*
X663034Y487650D01*
G01X662367Y487983D02*
X663034Y488483D01*
G01Y490667D02*
X662492Y490750D01*
X662034Y490875D01*
X661617Y491042D01*
X661159Y491250D01*
X660534Y491583D01*
Y489917D01*
G01X640292Y514719D02*
X640042Y514844D01*
X639750Y514927D01*
X639417D01*
X639042Y514802D01*
X638750Y514594D01*
X638542Y514344D01*
X638375Y513927D01*
X638333Y513552D01*
X638417Y513177D01*
X638542Y512927D01*
X638792Y512677D01*
X639083Y512510D01*
X639375Y512427D01*
X639667D01*
X639958Y512510D01*
X640208Y512635D01*
X640417Y512802D01*
G01X641683Y514510D02*
X641933Y514760D01*
X642225Y514885D01*
X642558Y514927D01*
X642975Y514844D01*
X643267Y514635D01*
X643350Y514385D01*
X643308Y514135D01*
X643142Y513927D01*
X642308Y513510D01*
X641933Y513219D01*
X641683Y512802D01*
X641600Y512427D01*
X643350D01*
G01X645575Y514927D02*
X645242Y514844D01*
X644992Y514635D01*
X644825Y514385D01*
X644700Y514052D01*
X644658Y513677D01*
X644700Y513302D01*
X644825Y512969D01*
X644992Y512719D01*
X645242Y512510D01*
X645575Y512427D01*
X645908Y512510D01*
X646158Y512719D01*
X646325Y512969D01*
X646450Y513302D01*
X646492Y513677D01*
X646450Y514052D01*
X646325Y514385D01*
X646158Y514635D01*
X645908Y514844D01*
X645575Y514927D01*
G01X648592Y512427D02*
X648675Y512969D01*
X648800Y513427D01*
X648967Y513844D01*
X649175Y514302D01*
X649508Y514927D01*
X647842D01*
G01X644267Y491459D02*
X644017Y491584D01*
X643725Y491667D01*
X643392D01*
X643017Y491542D01*
X642725Y491334D01*
X642517Y491084D01*
X642350Y490667D01*
X642308Y490292D01*
X642392Y489917D01*
X642517Y489667D01*
X642767Y489417D01*
X643058Y489250D01*
X643350Y489167D01*
X643642D01*
X643933Y489250D01*
X644183Y489375D01*
X644392Y489542D01*
G01X645658Y491250D02*
X645908Y491500D01*
X646200Y491625D01*
X646533Y491667D01*
X646950Y491584D01*
X647242Y491375D01*
X647325Y491125D01*
X647283Y490875D01*
X647117Y490667D01*
X646283Y490250D01*
X645908Y489959D01*
X645658Y489542D01*
X645575Y489167D01*
X647325D01*
G01X649550D02*
Y491667D01*
X649050Y491167D01*
G01Y489167D02*
X650050D01*
G01X652650D02*
Y491667D01*
X652150Y491167D01*
G01Y489167D02*
X653150D01*
G01X616167Y523566D02*
Y526066D01*
X617167D01*
X617500Y525941D01*
X617750Y525649D01*
X617833Y525316D01*
X617750Y524983D01*
X617542Y524733D01*
X617167Y524608D01*
X616167D01*
G01X619183Y526066D02*
Y524274D01*
X619350Y523899D01*
X619683Y523649D01*
X620100Y523566D01*
X620517Y523649D01*
X620850Y523899D01*
X621017Y524274D01*
Y526066D01*
G01X623700Y523566D02*
Y526066D01*
X622158Y524274D01*
X624242D01*
G01X626176Y529137D02*
Y526137D01*
G01X613360Y525043D02*
Y532043D01*
G01X606960Y525043D02*
X613360D01*
G01X614850Y488700D02*
Y515700D01*
X635350D01*
Y488700D01*
X614850D01*
G01X664242Y580667D02*
X664117Y580417D01*
X664034Y580125D01*
Y579792D01*
X664159Y579417D01*
X664367Y579125D01*
X664617Y578917D01*
X665034Y578750D01*
X665409Y578708D01*
X665784Y578792D01*
X666034Y578917D01*
X666284Y579167D01*
X666451Y579458D01*
X666534Y579750D01*
Y580042D01*
X666451Y580333D01*
X666326Y580583D01*
X666159Y580792D01*
G01X666534Y582850D02*
X664034D01*
X664534Y582350D01*
G01X666534D02*
Y583350D01*
G01X666159Y585033D02*
X666367Y585283D01*
X666492Y585575D01*
X666534Y585950D01*
X666451Y586325D01*
X666284Y586617D01*
X665992Y586825D01*
X665659Y586867D01*
X665326Y586783D01*
X665117Y586575D01*
X664951Y586283D01*
X664909Y585992D01*
X664951Y585700D01*
X665117Y585325D01*
X664034Y585450D01*
Y586575D01*
G01X666242Y588342D02*
X666451Y588633D01*
X666534Y588967D01*
X666451Y589300D01*
X666201Y589592D01*
X665826Y589800D01*
X665451Y589883D01*
X664992D01*
X664617Y589800D01*
X664284Y589592D01*
X664117Y589342D01*
X664034Y589050D01*
X664117Y588717D01*
X664284Y588467D01*
X664534Y588300D01*
X664867Y588217D01*
X665159Y588300D01*
X665451Y588508D01*
X665617Y588758D01*
X665659Y589050D01*
X665576Y589383D01*
X665367Y589633D01*
X664992Y589883D01*
G01X648467Y580192D02*
X648217Y580317D01*
X647925Y580400D01*
X647592D01*
X647217Y580275D01*
X646925Y580067D01*
X646717Y579817D01*
X646550Y579400D01*
X646508Y579025D01*
X646592Y578650D01*
X646717Y578400D01*
X646967Y578150D01*
X647258Y577983D01*
X647550Y577900D01*
X647842D01*
X648133Y577983D01*
X648383Y578108D01*
X648592Y578275D01*
G01X649858Y579983D02*
X650108Y580233D01*
X650400Y580358D01*
X650733Y580400D01*
X651150Y580317D01*
X651442Y580108D01*
X651525Y579858D01*
X651483Y579608D01*
X651317Y579400D01*
X650483Y578983D01*
X650108Y578692D01*
X649858Y578275D01*
X649775Y577900D01*
X651525D01*
G01X653750Y580400D02*
X653417Y580317D01*
X653167Y580108D01*
X653000Y579858D01*
X652875Y579525D01*
X652833Y579150D01*
X652875Y578775D01*
X653000Y578442D01*
X653167Y578192D01*
X653417Y577983D01*
X653750Y577900D01*
X654083Y577983D01*
X654333Y578192D01*
X654500Y578442D01*
X654625Y578775D01*
X654667Y579150D01*
X654625Y579525D01*
X654500Y579858D01*
X654333Y580108D01*
X654083Y580317D01*
X653750Y580400D01*
G01X656058Y578942D02*
X656350Y579233D01*
X656600Y579400D01*
X656933Y579483D01*
X657225Y579400D01*
X657433Y579233D01*
X657600Y578983D01*
X657642Y578692D01*
X657600Y578442D01*
X657433Y578192D01*
X657183Y577983D01*
X656892Y577900D01*
X656558Y577983D01*
X656267Y578233D01*
X656100Y578608D01*
X656058Y579025D01*
X656142Y579567D01*
X656267Y579858D01*
X656475Y580150D01*
X656767Y580358D01*
X657058Y580400D01*
X657350Y580317D01*
X657558Y580108D01*
G01X646777Y569943D02*
Y572443D01*
X647818D01*
X648152Y572318D01*
X648360Y572151D01*
X648443Y571818D01*
X648360Y571485D01*
X648110Y571276D01*
X647818Y571151D01*
X646777D01*
G01X647818D02*
X648443Y569943D01*
G01X649793Y570318D02*
X650043Y570110D01*
X650335Y569985D01*
X650710Y569943D01*
X651085Y570026D01*
X651377Y570193D01*
X651585Y570485D01*
X651627Y570818D01*
X651543Y571151D01*
X651335Y571360D01*
X651043Y571526D01*
X650752Y571568D01*
X650460Y571526D01*
X650085Y571360D01*
X650210Y572443D01*
X651335D01*
G01X653810Y569943D02*
Y572443D01*
X653310Y571943D01*
G01Y569943D02*
X654310D01*
G01X656118Y570985D02*
X656410Y571276D01*
X656660Y571443D01*
X656993Y571526D01*
X657285Y571443D01*
X657493Y571276D01*
X657660Y571026D01*
X657702Y570735D01*
X657660Y570485D01*
X657493Y570235D01*
X657243Y570026D01*
X656952Y569943D01*
X656618Y570026D01*
X656327Y570276D01*
X656160Y570651D01*
X656118Y571068D01*
X656202Y571610D01*
X656327Y571901D01*
X656535Y572193D01*
X656827Y572401D01*
X657118Y572443D01*
X657410Y572360D01*
X657618Y572151D01*
G01X637460Y551543D02*
Y547543D01*
X644860D01*
G01X634434Y563917D02*
X631934D01*
Y564958D01*
X632059Y565292D01*
X632226Y565500D01*
X632559Y565583D01*
X632892Y565500D01*
X633101Y565250D01*
X633226Y564958D01*
Y563917D01*
G01Y564958D02*
X634434Y565583D01*
G01X634059Y566933D02*
X634267Y567183D01*
X634392Y567475D01*
X634434Y567850D01*
X634351Y568225D01*
X634184Y568517D01*
X633892Y568725D01*
X633559Y568767D01*
X633226Y568683D01*
X633017Y568475D01*
X632851Y568183D01*
X632809Y567892D01*
X632851Y567600D01*
X633017Y567225D01*
X631934Y567350D01*
Y568475D01*
G01X634434Y570950D02*
X631934D01*
X632434Y570450D01*
G01X634434D02*
Y571450D01*
G01X633934Y573133D02*
X634226Y573383D01*
X634392Y573717D01*
X634434Y574092D01*
X634392Y574425D01*
X634184Y574758D01*
X633934Y574967D01*
X633684Y575008D01*
X633392Y574925D01*
X633184Y574633D01*
X633101Y574342D01*
Y573967D01*
G01Y574342D02*
X632976Y574592D01*
X632767Y574800D01*
X632517Y574883D01*
X632267Y574800D01*
X632059Y574592D01*
X631934Y574217D01*
X631976Y573842D01*
X632142Y573467D01*
G01X634628Y560027D02*
X630628D01*
Y552627D01*
G01X620900Y574717D02*
X618400D01*
Y575758D01*
X618525Y576092D01*
X618692Y576300D01*
X619025Y576383D01*
X619358Y576300D01*
X619567Y576050D01*
X619692Y575758D01*
Y574717D01*
G01Y575758D02*
X620900Y576383D01*
G01X620525Y577733D02*
X620733Y577983D01*
X620858Y578275D01*
X620900Y578650D01*
X620817Y579025D01*
X620650Y579317D01*
X620358Y579525D01*
X620025Y579567D01*
X619692Y579483D01*
X619483Y579275D01*
X619317Y578983D01*
X619275Y578692D01*
X619317Y578400D01*
X619483Y578025D01*
X618400Y578150D01*
Y579275D01*
G01X618817Y580958D02*
X618567Y581208D01*
X618442Y581500D01*
X618400Y581833D01*
X618483Y582250D01*
X618692Y582542D01*
X618942Y582625D01*
X619192Y582583D01*
X619400Y582417D01*
X619817Y581583D01*
X620108Y581208D01*
X620525Y580958D01*
X620900Y580875D01*
Y582625D01*
G01Y584850D02*
X618400D01*
X618900Y584350D01*
G01X620900D02*
Y585350D01*
G01X617400Y561800D02*
X621400D01*
Y569200D01*
G01X646817Y574100D02*
Y576600D01*
X647858D01*
X648192Y576475D01*
X648400Y576308D01*
X648483Y575975D01*
X648400Y575642D01*
X648150Y575433D01*
X647858Y575308D01*
X646817D01*
G01X647858D02*
X648483Y574100D01*
G01X649833Y574475D02*
X650083Y574267D01*
X650375Y574142D01*
X650750Y574100D01*
X651125Y574183D01*
X651417Y574350D01*
X651625Y574642D01*
X651667Y574975D01*
X651583Y575308D01*
X651375Y575517D01*
X651083Y575683D01*
X650792Y575725D01*
X650500Y575683D01*
X650125Y575517D01*
X650250Y576600D01*
X651375D01*
G01X653850Y574100D02*
Y576600D01*
X653350Y576100D01*
G01Y574100D02*
X654350D01*
G01X656033Y574475D02*
X656283Y574267D01*
X656575Y574142D01*
X656950Y574100D01*
X657325Y574183D01*
X657617Y574350D01*
X657825Y574642D01*
X657867Y574975D01*
X657783Y575308D01*
X657575Y575517D01*
X657283Y575683D01*
X656992Y575725D01*
X656700Y575683D01*
X656325Y575517D01*
X656450Y576600D01*
X657575D01*
G01X644900Y551700D02*
Y555700D01*
X637500D01*
G01X625042Y574669D02*
X622542D01*
Y575710D01*
X622667Y576044D01*
X622834Y576252D01*
X623167Y576335D01*
X623500Y576252D01*
X623709Y576002D01*
X623834Y575710D01*
Y574669D01*
G01Y575710D02*
X625042Y576335D01*
G01X624667Y577685D02*
X624875Y577935D01*
X625000Y578227D01*
X625042Y578602D01*
X624959Y578977D01*
X624792Y579269D01*
X624500Y579477D01*
X624167Y579519D01*
X623834Y579435D01*
X623625Y579227D01*
X623459Y578935D01*
X623417Y578644D01*
X623459Y578352D01*
X623625Y577977D01*
X622542Y578102D01*
Y579227D01*
G01X625042Y581702D02*
X622542D01*
X623042Y581202D01*
G01X625042D02*
Y582202D01*
G01Y584802D02*
X625000Y585094D01*
X624875Y585427D01*
X624667Y585635D01*
X624375Y585719D01*
X624084Y585635D01*
X623834Y585385D01*
X623709Y585010D01*
Y584594D01*
X623625Y584344D01*
X623417Y584135D01*
X623125Y584052D01*
X622834Y584177D01*
X622625Y584469D01*
X622542Y584802D01*
X622625Y585135D01*
X622834Y585427D01*
X623125Y585552D01*
X623417Y585469D01*
X623625Y585260D01*
X623709Y585010D01*
Y584594D01*
X623834Y584219D01*
X624084Y583969D01*
X624375Y583885D01*
X624667Y583969D01*
X624875Y584177D01*
X625000Y584510D01*
X625042Y584802D01*
G01X621542Y561752D02*
X625542D01*
Y569152D01*
G01X647017Y582000D02*
Y584500D01*
X648058D01*
X648392Y584375D01*
X648600Y584208D01*
X648683Y583875D01*
X648600Y583542D01*
X648350Y583333D01*
X648058Y583208D01*
X647017D01*
G01X648058D02*
X648683Y582000D01*
G01X650033Y582375D02*
X650283Y582167D01*
X650575Y582042D01*
X650950Y582000D01*
X651325Y582083D01*
X651617Y582250D01*
X651825Y582542D01*
X651867Y582875D01*
X651783Y583208D01*
X651575Y583417D01*
X651283Y583583D01*
X650992Y583625D01*
X650700Y583583D01*
X650325Y583417D01*
X650450Y584500D01*
X651575D01*
G01X654050Y582000D02*
Y584500D01*
X653550Y584000D01*
G01Y582000D02*
X654550D01*
G01X657650D02*
Y584500D01*
X656108Y582708D01*
X658192D01*
G01X650317Y566167D02*
Y568667D01*
X651358D01*
X651692Y568542D01*
X651900Y568375D01*
X651983Y568042D01*
X651900Y567709D01*
X651650Y567500D01*
X651358Y567375D01*
X650317D01*
G01X651358D02*
X651983Y566167D01*
G01X653333Y566542D02*
X653583Y566334D01*
X653875Y566209D01*
X654250Y566167D01*
X654625Y566250D01*
X654917Y566417D01*
X655125Y566709D01*
X655167Y567042D01*
X655083Y567375D01*
X654875Y567584D01*
X654583Y567750D01*
X654292Y567792D01*
X654000Y567750D01*
X653625Y567584D01*
X653750Y568667D01*
X654875D01*
G01X657350Y566167D02*
Y568667D01*
X656850Y568167D01*
G01Y566167D02*
X657850D01*
G01X660450D02*
Y568667D01*
X659950Y568167D01*
G01Y566167D02*
X660950D01*
G01X627368Y573510D02*
X627243Y573260D01*
X627160Y572968D01*
Y572635D01*
X627285Y572260D01*
X627493Y571968D01*
X627743Y571760D01*
X628160Y571593D01*
X628535Y571551D01*
X628910Y571635D01*
X629160Y571760D01*
X629410Y572010D01*
X629577Y572301D01*
X629660Y572593D01*
Y572885D01*
X629577Y573176D01*
X629452Y573426D01*
X629285Y573635D01*
G01X627577Y574901D02*
X627327Y575151D01*
X627202Y575443D01*
X627160Y575776D01*
X627243Y576193D01*
X627452Y576485D01*
X627702Y576568D01*
X627952Y576526D01*
X628160Y576360D01*
X628577Y575526D01*
X628868Y575151D01*
X629285Y574901D01*
X629660Y574818D01*
Y576568D01*
G01X627160Y578793D02*
X627243Y578460D01*
X627452Y578210D01*
X627702Y578043D01*
X628035Y577918D01*
X628410Y577876D01*
X628785Y577918D01*
X629118Y578043D01*
X629368Y578210D01*
X629577Y578460D01*
X629660Y578793D01*
X629577Y579126D01*
X629368Y579376D01*
X629118Y579543D01*
X628785Y579668D01*
X628410Y579710D01*
X628035Y579668D01*
X627702Y579543D01*
X627452Y579376D01*
X627243Y579126D01*
X627160Y578793D01*
G01X629368Y581185D02*
X629577Y581476D01*
X629660Y581810D01*
X629577Y582143D01*
X629327Y582435D01*
X628952Y582643D01*
X628577Y582726D01*
X628118D01*
X627743Y582643D01*
X627410Y582435D01*
X627243Y582185D01*
X627160Y581893D01*
X627243Y581560D01*
X627410Y581310D01*
X627660Y581143D01*
X627993Y581060D01*
X628285Y581143D01*
X628577Y581351D01*
X628743Y581601D01*
X628785Y581893D01*
X628702Y582226D01*
X628493Y582476D01*
X628118Y582726D01*
G01X652067Y564859D02*
X651817Y564984D01*
X651525Y565067D01*
X651192D01*
X650817Y564942D01*
X650525Y564734D01*
X650317Y564484D01*
X650150Y564067D01*
X650108Y563692D01*
X650192Y563317D01*
X650317Y563067D01*
X650567Y562817D01*
X650858Y562650D01*
X651150Y562567D01*
X651442D01*
X651733Y562650D01*
X651983Y562775D01*
X652192Y562942D01*
G01X653458Y564650D02*
X653708Y564900D01*
X654000Y565025D01*
X654333Y565067D01*
X654750Y564984D01*
X655042Y564775D01*
X655125Y564525D01*
X655083Y564275D01*
X654917Y564067D01*
X654083Y563650D01*
X653708Y563359D01*
X653458Y562942D01*
X653375Y562567D01*
X655125D01*
G01X657350Y565067D02*
X657017Y564984D01*
X656767Y564775D01*
X656600Y564525D01*
X656475Y564192D01*
X656433Y563817D01*
X656475Y563442D01*
X656600Y563109D01*
X656767Y562859D01*
X657017Y562650D01*
X657350Y562567D01*
X657683Y562650D01*
X657933Y562859D01*
X658100Y563109D01*
X658225Y563442D01*
X658267Y563817D01*
X658225Y564192D01*
X658100Y564525D01*
X657933Y564775D01*
X657683Y564984D01*
X657350Y565067D01*
G01X659658Y564650D02*
X659908Y564900D01*
X660200Y565025D01*
X660533Y565067D01*
X660950Y564984D01*
X661242Y564775D01*
X661325Y564525D01*
X661283Y564275D01*
X661117Y564067D01*
X660283Y563650D01*
X659908Y563359D01*
X659658Y562942D01*
X659575Y562567D01*
X661325D01*
G01X666834Y538717D02*
X664334D01*
Y539758D01*
X664459Y540092D01*
X664626Y540300D01*
X664959Y540383D01*
X665292Y540300D01*
X665501Y540050D01*
X665626Y539758D01*
Y538717D01*
G01Y539758D02*
X666834Y540383D01*
G01X666459Y541733D02*
X666667Y541983D01*
X666792Y542275D01*
X666834Y542650D01*
X666751Y543025D01*
X666584Y543317D01*
X666292Y543525D01*
X665959Y543567D01*
X665626Y543483D01*
X665417Y543275D01*
X665251Y542983D01*
X665209Y542692D01*
X665251Y542400D01*
X665417Y542025D01*
X664334Y542150D01*
Y543275D01*
G01X666834Y545750D02*
X664334D01*
X664834Y545250D01*
G01X666834D02*
Y546250D01*
G01X664751Y548058D02*
X664501Y548308D01*
X664376Y548600D01*
X664334Y548933D01*
X664417Y549350D01*
X664626Y549642D01*
X664876Y549725D01*
X665126Y549683D01*
X665334Y549517D01*
X665751Y548683D01*
X666042Y548308D01*
X666459Y548058D01*
X666834Y547975D01*
Y549725D01*
G01X663200Y534900D02*
X655200D01*
Y552500D01*
X663200D01*
Y534900D01*
G01X700500Y642300D02*
X659100D01*
Y592100D01*
X700500D01*
Y642300D01*
G01X632060Y528143D02*
X637060D01*
Y533143D01*
G01X617260D02*
Y528143D01*
X622260D01*
G01Y547943D02*
X617260D01*
Y542943D01*
G01X636066Y539027D02*
X638066D01*
G01X618254Y540996D02*
X616254D01*
G01X660017Y573667D02*
Y576167D01*
X661058D01*
X661392Y576042D01*
X661600Y575875D01*
X661683Y575542D01*
X661600Y575209D01*
X661350Y575000D01*
X661058Y574875D01*
X660017D01*
G01X661058D02*
X661683Y573667D01*
G01X664450D02*
Y576167D01*
X662908Y574375D01*
X664992D01*
G01X666258Y574709D02*
X666550Y575000D01*
X666800Y575167D01*
X667133Y575250D01*
X667425Y575167D01*
X667633Y575000D01*
X667800Y574750D01*
X667842Y574459D01*
X667800Y574209D01*
X667633Y573959D01*
X667383Y573750D01*
X667092Y573667D01*
X666758Y573750D01*
X666467Y574000D01*
X666300Y574375D01*
X666258Y574792D01*
X666342Y575334D01*
X666467Y575625D01*
X666675Y575917D01*
X666967Y576125D01*
X667258Y576167D01*
X667550Y576084D01*
X667758Y575875D01*
G01X669442Y573959D02*
X669733Y573750D01*
X670067Y573667D01*
X670400Y573750D01*
X670692Y574000D01*
X670900Y574375D01*
X670983Y574750D01*
Y575209D01*
X670900Y575584D01*
X670692Y575917D01*
X670442Y576084D01*
X670150Y576167D01*
X669817Y576084D01*
X669567Y575917D01*
X669400Y575667D01*
X669317Y575334D01*
X669400Y575042D01*
X669608Y574750D01*
X669858Y574584D01*
X670150Y574542D01*
X670483Y574625D01*
X670733Y574834D01*
X670983Y575209D01*
G01X613360Y532043D02*
X604660D01*
G01X653834Y614117D02*
X656334D01*
Y615783D01*
G01Y617967D02*
X655792Y618050D01*
X655334Y618175D01*
X654917Y618342D01*
X654459Y618550D01*
X653834Y618883D01*
Y617217D01*
G01X640483Y649844D02*
X640358Y649594D01*
X640275Y649302D01*
Y648969D01*
X640400Y648594D01*
X640608Y648302D01*
X640858Y648094D01*
X641275Y647927D01*
X641650Y647885D01*
X642025Y647969D01*
X642275Y648094D01*
X642525Y648344D01*
X642692Y648635D01*
X642775Y648927D01*
Y649219D01*
X642692Y649510D01*
X642567Y649760D01*
X642400Y649969D01*
G01X642775Y652027D02*
X640275D01*
X640775Y651527D01*
G01X642775D02*
Y652527D01*
G01X641733Y654335D02*
X641442Y654627D01*
X641275Y654877D01*
X641192Y655210D01*
X641275Y655502D01*
X641442Y655710D01*
X641692Y655877D01*
X641983Y655919D01*
X642233Y655877D01*
X642483Y655710D01*
X642692Y655460D01*
X642775Y655169D01*
X642692Y654835D01*
X642442Y654544D01*
X642067Y654377D01*
X641650Y654335D01*
X641108Y654419D01*
X640817Y654544D01*
X640525Y654752D01*
X640317Y655044D01*
X640275Y655335D01*
X640358Y655627D01*
X640567Y655835D01*
G01X642775Y658144D02*
X642233Y658227D01*
X641775Y658352D01*
X641358Y658519D01*
X640900Y658727D01*
X640275Y659060D01*
Y657394D01*
G01X646900Y644200D02*
Y662200D01*
G01X658100Y644200D02*
X646900D01*
G01Y662200D02*
X658100D01*
G01X640166Y671043D02*
X640041Y670793D01*
X639958Y670501D01*
Y670168D01*
X640083Y669793D01*
X640291Y669501D01*
X640541Y669293D01*
X640958Y669126D01*
X641333Y669084D01*
X641708Y669168D01*
X641958Y669293D01*
X642208Y669543D01*
X642375Y669834D01*
X642458Y670126D01*
Y670418D01*
X642375Y670709D01*
X642250Y670959D01*
X642083Y671168D01*
G01X642458Y673226D02*
X639958D01*
X640458Y672726D01*
G01X642458D02*
Y673726D01*
G01X641416Y675534D02*
X641125Y675826D01*
X640958Y676076D01*
X640875Y676409D01*
X640958Y676701D01*
X641125Y676909D01*
X641375Y677076D01*
X641666Y677118D01*
X641916Y677076D01*
X642166Y676909D01*
X642375Y676659D01*
X642458Y676368D01*
X642375Y676034D01*
X642125Y675743D01*
X641750Y675576D01*
X641333Y675534D01*
X640791Y675618D01*
X640500Y675743D01*
X640208Y675951D01*
X640000Y676243D01*
X639958Y676534D01*
X640041Y676826D01*
X640250Y677034D01*
G01X642458Y679426D02*
X642416Y679718D01*
X642291Y680051D01*
X642083Y680259D01*
X641791Y680343D01*
X641500Y680259D01*
X641250Y680009D01*
X641125Y679634D01*
Y679218D01*
X641041Y678968D01*
X640833Y678759D01*
X640541Y678676D01*
X640250Y678801D01*
X640041Y679093D01*
X639958Y679426D01*
X640041Y679759D01*
X640250Y680051D01*
X640541Y680176D01*
X640833Y680093D01*
X641041Y679884D01*
X641125Y679634D01*
Y679218D01*
X641250Y678843D01*
X641500Y678593D01*
X641791Y678509D01*
X642083Y678593D01*
X642291Y678801D01*
X642416Y679134D01*
X642458Y679426D01*
G01X646900Y682400D02*
X658100D01*
G01X646900Y664400D02*
Y682400D01*
G01X658100Y664400D02*
X646900D01*
G01X681861Y-23326D02*
Y20974D01*
X684211D01*
Y129874D01*
X733111D01*
Y20974D01*
X735461D01*
Y-23326D01*
X681861D01*
G01X689426Y7664D02*
Y11664D01*
X691026D01*
X691559Y11464D01*
X691959Y10997D01*
X692092Y10464D01*
X691959Y9931D01*
X691626Y9531D01*
X691026Y9331D01*
X689426D01*
G01X694426Y7664D02*
Y10331D01*
G01Y9797D02*
X694759Y10064D01*
X695092Y10264D01*
X695559Y10331D01*
X695892Y10264D01*
X696292Y10064D01*
G01X698959Y9464D02*
X701092D01*
X700892Y9931D01*
X700559Y10197D01*
X700092Y10331D01*
X699626Y10264D01*
X699226Y10064D01*
X698959Y9597D01*
X698826Y9197D01*
Y8797D01*
X698959Y8397D01*
X699292Y7997D01*
X699692Y7731D01*
X700159Y7664D01*
X700626Y7797D01*
X701092Y8197D01*
G01X703559Y8131D02*
X703892Y7864D01*
X704359Y7664D01*
X704759D01*
X705159Y7797D01*
X705426Y7997D01*
X705559Y8264D01*
X705492Y8664D01*
X705226Y8864D01*
X704026Y9264D01*
X703759Y9731D01*
X703892Y10064D01*
X704159Y10264D01*
X704559Y10331D01*
X704959Y10264D01*
X705359Y10064D01*
G01X708159Y8131D02*
X708492Y7864D01*
X708959Y7664D01*
X709359D01*
X709759Y7797D01*
X710026Y7997D01*
X710159Y8264D01*
X710092Y8664D01*
X709826Y8864D01*
X708626Y9264D01*
X708359Y9731D01*
X708492Y10064D01*
X708759Y10264D01*
X709159Y10331D01*
X709559Y10264D01*
X709959Y10064D01*
G01X717092Y7664D02*
Y11664D01*
X719626D01*
G01X718692Y9731D02*
X717092D01*
G01X722959Y10331D02*
Y7664D01*
G01Y11397D02*
X722826Y11464D01*
Y11597D01*
X722959Y11664D01*
X723092Y11597D01*
Y11464D01*
X722959Y11397D01*
G01X727559Y11664D02*
Y7664D01*
G01X726626Y10331D02*
X728492D01*
G01X703283Y134167D02*
X701617D01*
Y136667D01*
X703283D01*
G01X702617Y135459D02*
X701617D01*
G01X704675Y134167D02*
X706425Y136667D01*
G01X704675D02*
X706425Y134167D01*
G01X708650Y136667D02*
Y134167D01*
G01X707692Y136667D02*
X709608D01*
G01X711750Y134167D02*
Y136667D01*
X711250Y136167D01*
G01Y134167D02*
X712250D01*
G01X696590Y165927D02*
X694090D01*
Y166968D01*
X694215Y167302D01*
X694382Y167510D01*
X694715Y167593D01*
X695048Y167510D01*
X695257Y167260D01*
X695382Y166968D01*
Y165927D01*
G01Y166968D02*
X696590Y167593D01*
G01X695548Y169068D02*
X695257Y169360D01*
X695090Y169610D01*
X695007Y169943D01*
X695090Y170235D01*
X695257Y170443D01*
X695507Y170610D01*
X695798Y170652D01*
X696048Y170610D01*
X696298Y170443D01*
X696507Y170193D01*
X696590Y169902D01*
X696507Y169568D01*
X696257Y169277D01*
X695882Y169110D01*
X695465Y169068D01*
X694923Y169152D01*
X694632Y169277D01*
X694340Y169485D01*
X694132Y169777D01*
X694090Y170068D01*
X694173Y170360D01*
X694382Y170568D01*
G01X695548Y172168D02*
X695257Y172460D01*
X695090Y172710D01*
X695007Y173043D01*
X695090Y173335D01*
X695257Y173543D01*
X695507Y173710D01*
X695798Y173752D01*
X696048Y173710D01*
X696298Y173543D01*
X696507Y173293D01*
X696590Y173002D01*
X696507Y172668D01*
X696257Y172377D01*
X695882Y172210D01*
X695465Y172168D01*
X694923Y172252D01*
X694632Y172377D01*
X694340Y172585D01*
X694132Y172877D01*
X694090Y173168D01*
X694173Y173460D01*
X694382Y173668D01*
G01X696590Y175977D02*
X696048Y176060D01*
X695590Y176185D01*
X695173Y176352D01*
X694715Y176560D01*
X694090Y176893D01*
Y175227D01*
G01X729150Y193250D02*
X725150D01*
Y185850D01*
G01X701440Y167077D02*
X698940D01*
Y168118D01*
X699065Y168452D01*
X699232Y168660D01*
X699565Y168743D01*
X699898Y168660D01*
X700107Y168410D01*
X700232Y168118D01*
Y167077D01*
G01Y168118D02*
X701440Y168743D01*
G01X700398Y170218D02*
X700107Y170510D01*
X699940Y170760D01*
X699857Y171093D01*
X699940Y171385D01*
X700107Y171593D01*
X700357Y171760D01*
X700648Y171802D01*
X700898Y171760D01*
X701148Y171593D01*
X701357Y171343D01*
X701440Y171052D01*
X701357Y170718D01*
X701107Y170427D01*
X700732Y170260D01*
X700315Y170218D01*
X699773Y170302D01*
X699482Y170427D01*
X699190Y170635D01*
X698982Y170927D01*
X698940Y171218D01*
X699023Y171510D01*
X699232Y171718D01*
G01X701440Y174027D02*
X700898Y174110D01*
X700440Y174235D01*
X700023Y174402D01*
X699565Y174610D01*
X698940Y174943D01*
Y173277D01*
G01X701065Y176293D02*
X701273Y176543D01*
X701398Y176835D01*
X701440Y177210D01*
X701357Y177585D01*
X701190Y177877D01*
X700898Y178085D01*
X700565Y178127D01*
X700232Y178043D01*
X700023Y177835D01*
X699857Y177543D01*
X699815Y177252D01*
X699857Y176960D01*
X700023Y176585D01*
X698940Y176710D01*
Y177835D01*
G01X730000Y187000D02*
X734000D01*
Y194400D01*
G01X691590Y165927D02*
X689090D01*
Y166968D01*
X689215Y167302D01*
X689382Y167510D01*
X689715Y167593D01*
X690048Y167510D01*
X690257Y167260D01*
X690382Y166968D01*
Y165927D01*
G01Y166968D02*
X691590Y167593D01*
G01X690548Y169068D02*
X690257Y169360D01*
X690090Y169610D01*
X690007Y169943D01*
X690090Y170235D01*
X690257Y170443D01*
X690507Y170610D01*
X690798Y170652D01*
X691048Y170610D01*
X691298Y170443D01*
X691507Y170193D01*
X691590Y169902D01*
X691507Y169568D01*
X691257Y169277D01*
X690882Y169110D01*
X690465Y169068D01*
X689923Y169152D01*
X689632Y169277D01*
X689340Y169485D01*
X689132Y169777D01*
X689090Y170068D01*
X689173Y170360D01*
X689382Y170568D01*
G01X690548Y172168D02*
X690257Y172460D01*
X690090Y172710D01*
X690007Y173043D01*
X690090Y173335D01*
X690257Y173543D01*
X690507Y173710D01*
X690798Y173752D01*
X691048Y173710D01*
X691298Y173543D01*
X691507Y173293D01*
X691590Y173002D01*
X691507Y172668D01*
X691257Y172377D01*
X690882Y172210D01*
X690465Y172168D01*
X689923Y172252D01*
X689632Y172377D01*
X689340Y172585D01*
X689132Y172877D01*
X689090Y173168D01*
X689173Y173460D01*
X689382Y173668D01*
G01X691590Y176060D02*
X691548Y176352D01*
X691423Y176685D01*
X691215Y176893D01*
X690923Y176977D01*
X690632Y176893D01*
X690382Y176643D01*
X690257Y176268D01*
Y175852D01*
X690173Y175602D01*
X689965Y175393D01*
X689673Y175310D01*
X689382Y175435D01*
X689173Y175727D01*
X689090Y176060D01*
X689173Y176393D01*
X689382Y176685D01*
X689673Y176810D01*
X689965Y176727D01*
X690173Y176518D01*
X690257Y176268D01*
Y175852D01*
X690382Y175477D01*
X690632Y175227D01*
X690923Y175143D01*
X691215Y175227D01*
X691423Y175435D01*
X691548Y175768D01*
X691590Y176060D01*
G01X724150Y193250D02*
X720150D01*
Y185850D01*
G01X733984Y162567D02*
X731484D01*
Y163608D01*
X731609Y163942D01*
X731776Y164150D01*
X732109Y164233D01*
X732442Y164150D01*
X732651Y163900D01*
X732776Y163608D01*
Y162567D01*
G01Y163608D02*
X733984Y164233D01*
G01X732942Y165708D02*
X732651Y166000D01*
X732484Y166250D01*
X732401Y166583D01*
X732484Y166875D01*
X732651Y167083D01*
X732901Y167250D01*
X733192Y167292D01*
X733442Y167250D01*
X733692Y167083D01*
X733901Y166833D01*
X733984Y166542D01*
X733901Y166208D01*
X733651Y165917D01*
X733276Y165750D01*
X732859Y165708D01*
X732317Y165792D01*
X732026Y165917D01*
X731734Y166125D01*
X731526Y166417D01*
X731484Y166708D01*
X731567Y167000D01*
X731776Y167208D01*
G01X732942Y168808D02*
X732651Y169100D01*
X732484Y169350D01*
X732401Y169683D01*
X732484Y169975D01*
X732651Y170183D01*
X732901Y170350D01*
X733192Y170392D01*
X733442Y170350D01*
X733692Y170183D01*
X733901Y169933D01*
X733984Y169642D01*
X733901Y169308D01*
X733651Y169017D01*
X733276Y168850D01*
X732859Y168808D01*
X732317Y168892D01*
X732026Y169017D01*
X731734Y169225D01*
X731526Y169517D01*
X731484Y169808D01*
X731567Y170100D01*
X731776Y170308D01*
G01X731484Y172700D02*
X731567Y172367D01*
X731776Y172117D01*
X732026Y171950D01*
X732359Y171825D01*
X732734Y171783D01*
X733109Y171825D01*
X733442Y171950D01*
X733692Y172117D01*
X733901Y172367D01*
X733984Y172700D01*
X733901Y173033D01*
X733692Y173283D01*
X733442Y173450D01*
X733109Y173575D01*
X732734Y173617D01*
X732359Y173575D01*
X732026Y173450D01*
X731776Y173283D01*
X731567Y173033D01*
X731484Y172700D01*
G01X732028Y176946D02*
X736028D01*
Y184346D01*
G01X726434Y162167D02*
X723934D01*
Y163208D01*
X724059Y163542D01*
X724226Y163750D01*
X724559Y163833D01*
X724892Y163750D01*
X725101Y163500D01*
X725226Y163208D01*
Y162167D01*
G01Y163208D02*
X726434Y163833D01*
G01X725392Y165308D02*
X725101Y165600D01*
X724934Y165850D01*
X724851Y166183D01*
X724934Y166475D01*
X725101Y166683D01*
X725351Y166850D01*
X725642Y166892D01*
X725892Y166850D01*
X726142Y166683D01*
X726351Y166433D01*
X726434Y166142D01*
X726351Y165808D01*
X726101Y165517D01*
X725726Y165350D01*
X725309Y165308D01*
X724767Y165392D01*
X724476Y165517D01*
X724184Y165725D01*
X723976Y166017D01*
X723934Y166308D01*
X724017Y166600D01*
X724226Y166808D01*
G01X725392Y168408D02*
X725101Y168700D01*
X724934Y168950D01*
X724851Y169283D01*
X724934Y169575D01*
X725101Y169783D01*
X725351Y169950D01*
X725642Y169992D01*
X725892Y169950D01*
X726142Y169783D01*
X726351Y169533D01*
X726434Y169242D01*
X726351Y168908D01*
X726101Y168617D01*
X725726Y168450D01*
X725309Y168408D01*
X724767Y168492D01*
X724476Y168617D01*
X724184Y168825D01*
X723976Y169117D01*
X723934Y169408D01*
X724017Y169700D01*
X724226Y169908D01*
G01X726142Y171592D02*
X726351Y171883D01*
X726434Y172217D01*
X726351Y172550D01*
X726101Y172842D01*
X725726Y173050D01*
X725351Y173133D01*
X724892D01*
X724517Y173050D01*
X724184Y172842D01*
X724017Y172592D01*
X723934Y172300D01*
X724017Y171967D01*
X724184Y171717D01*
X724434Y171550D01*
X724767Y171467D01*
X725059Y171550D01*
X725351Y171758D01*
X725517Y172008D01*
X725559Y172300D01*
X725476Y172633D01*
X725267Y172883D01*
X724892Y173133D01*
G01X727678Y182392D02*
X723678D01*
Y174992D01*
G01X718034Y161367D02*
X715534D01*
Y162408D01*
X715659Y162742D01*
X715826Y162950D01*
X716159Y163033D01*
X716492Y162950D01*
X716701Y162700D01*
X716826Y162408D01*
Y161367D01*
G01Y162408D02*
X718034Y163033D01*
G01X716992Y164508D02*
X716701Y164800D01*
X716534Y165050D01*
X716451Y165383D01*
X716534Y165675D01*
X716701Y165883D01*
X716951Y166050D01*
X717242Y166092D01*
X717492Y166050D01*
X717742Y165883D01*
X717951Y165633D01*
X718034Y165342D01*
X717951Y165008D01*
X717701Y164717D01*
X717326Y164550D01*
X716909Y164508D01*
X716367Y164592D01*
X716076Y164717D01*
X715784Y164925D01*
X715576Y165217D01*
X715534Y165508D01*
X715617Y165800D01*
X715826Y166008D01*
G01X716992Y167608D02*
X716701Y167900D01*
X716534Y168150D01*
X716451Y168483D01*
X716534Y168775D01*
X716701Y168983D01*
X716951Y169150D01*
X717242Y169192D01*
X717492Y169150D01*
X717742Y168983D01*
X717951Y168733D01*
X718034Y168442D01*
X717951Y168108D01*
X717701Y167817D01*
X717326Y167650D01*
X716909Y167608D01*
X716367Y167692D01*
X716076Y167817D01*
X715784Y168025D01*
X715576Y168317D01*
X715534Y168608D01*
X715617Y168900D01*
X715826Y169108D01*
G01X718034Y171500D02*
X715534D01*
X716034Y171000D01*
G01X718034D02*
Y172000D01*
G01X714650Y175600D02*
X718650D01*
Y183000D01*
G01X712584Y160767D02*
X710084D01*
Y161808D01*
X710209Y162142D01*
X710376Y162350D01*
X710709Y162433D01*
X711042Y162350D01*
X711251Y162100D01*
X711376Y161808D01*
Y160767D01*
G01Y161808D02*
X712584Y162433D01*
G01X711542Y163908D02*
X711251Y164200D01*
X711084Y164450D01*
X711001Y164783D01*
X711084Y165075D01*
X711251Y165283D01*
X711501Y165450D01*
X711792Y165492D01*
X712042Y165450D01*
X712292Y165283D01*
X712501Y165033D01*
X712584Y164742D01*
X712501Y164408D01*
X712251Y164117D01*
X711876Y163950D01*
X711459Y163908D01*
X710917Y163992D01*
X710626Y164117D01*
X710334Y164325D01*
X710126Y164617D01*
X710084Y164908D01*
X710167Y165200D01*
X710376Y165408D01*
G01X712584Y167717D02*
X712042Y167800D01*
X711584Y167925D01*
X711167Y168092D01*
X710709Y168300D01*
X710084Y168633D01*
Y166967D01*
G01X712084Y169983D02*
X712376Y170233D01*
X712542Y170567D01*
X712584Y170942D01*
X712542Y171275D01*
X712334Y171608D01*
X712084Y171817D01*
X711834Y171858D01*
X711542Y171775D01*
X711334Y171483D01*
X711251Y171192D01*
Y170817D01*
G01Y171192D02*
X711126Y171442D01*
X710917Y171650D01*
X710667Y171733D01*
X710417Y171650D01*
X710209Y171442D01*
X710084Y171067D01*
X710126Y170692D01*
X710292Y170317D01*
G01X713150Y183000D02*
X709150D01*
Y175600D01*
G01X679097Y199777D02*
Y202277D01*
X680138D01*
X680472Y202152D01*
X680680Y201985D01*
X680763Y201652D01*
X680680Y201319D01*
X680430Y201110D01*
X680138Y200985D01*
X679097D01*
G01X680138D02*
X680763Y199777D01*
G01X682238Y200819D02*
X682530Y201110D01*
X682780Y201277D01*
X683113Y201360D01*
X683405Y201277D01*
X683613Y201110D01*
X683780Y200860D01*
X683822Y200569D01*
X683780Y200319D01*
X683613Y200069D01*
X683363Y199860D01*
X683072Y199777D01*
X682738Y199860D01*
X682447Y200110D01*
X682280Y200485D01*
X682238Y200902D01*
X682322Y201444D01*
X682447Y201735D01*
X682655Y202027D01*
X682947Y202235D01*
X683238Y202277D01*
X683530Y202194D01*
X683738Y201985D01*
G01X685338Y200819D02*
X685630Y201110D01*
X685880Y201277D01*
X686213Y201360D01*
X686505Y201277D01*
X686713Y201110D01*
X686880Y200860D01*
X686922Y200569D01*
X686880Y200319D01*
X686713Y200069D01*
X686463Y199860D01*
X686172Y199777D01*
X685838Y199860D01*
X685547Y200110D01*
X685380Y200485D01*
X685338Y200902D01*
X685422Y201444D01*
X685547Y201735D01*
X685755Y202027D01*
X686047Y202235D01*
X686338Y202277D01*
X686630Y202194D01*
X686838Y201985D01*
G01X688438Y201860D02*
X688688Y202110D01*
X688980Y202235D01*
X689313Y202277D01*
X689730Y202194D01*
X690022Y201985D01*
X690105Y201735D01*
X690063Y201485D01*
X689897Y201277D01*
X689063Y200860D01*
X688688Y200569D01*
X688438Y200152D01*
X688355Y199777D01*
X690105D01*
G01X694520Y199740D02*
Y195740D01*
X701920D01*
G01X686090Y165927D02*
X683590D01*
Y166968D01*
X683715Y167302D01*
X683882Y167510D01*
X684215Y167593D01*
X684548Y167510D01*
X684757Y167260D01*
X684882Y166968D01*
Y165927D01*
G01Y166968D02*
X686090Y167593D01*
G01X685048Y169068D02*
X684757Y169360D01*
X684590Y169610D01*
X684507Y169943D01*
X684590Y170235D01*
X684757Y170443D01*
X685007Y170610D01*
X685298Y170652D01*
X685548Y170610D01*
X685798Y170443D01*
X686007Y170193D01*
X686090Y169902D01*
X686007Y169568D01*
X685757Y169277D01*
X685382Y169110D01*
X684965Y169068D01*
X684423Y169152D01*
X684132Y169277D01*
X683840Y169485D01*
X683632Y169777D01*
X683590Y170068D01*
X683673Y170360D01*
X683882Y170568D01*
G01X686090Y172877D02*
X685548Y172960D01*
X685090Y173085D01*
X684673Y173252D01*
X684215Y173460D01*
X683590Y173793D01*
Y172127D01*
G01Y176060D02*
X683673Y175727D01*
X683882Y175477D01*
X684132Y175310D01*
X684465Y175185D01*
X684840Y175143D01*
X685215Y175185D01*
X685548Y175310D01*
X685798Y175477D01*
X686007Y175727D01*
X686090Y176060D01*
X686007Y176393D01*
X685798Y176643D01*
X685548Y176810D01*
X685215Y176935D01*
X684840Y176977D01*
X684465Y176935D01*
X684132Y176810D01*
X683882Y176643D01*
X683673Y176393D01*
X683590Y176060D01*
G01X718650Y193250D02*
X714650D01*
Y185850D01*
G01X675090Y165927D02*
X672590D01*
Y166968D01*
X672715Y167302D01*
X672882Y167510D01*
X673215Y167593D01*
X673548Y167510D01*
X673757Y167260D01*
X673882Y166968D01*
Y165927D01*
G01Y166968D02*
X675090Y167593D01*
G01X674048Y169068D02*
X673757Y169360D01*
X673590Y169610D01*
X673507Y169943D01*
X673590Y170235D01*
X673757Y170443D01*
X674007Y170610D01*
X674298Y170652D01*
X674548Y170610D01*
X674798Y170443D01*
X675007Y170193D01*
X675090Y169902D01*
X675007Y169568D01*
X674757Y169277D01*
X674382Y169110D01*
X673965Y169068D01*
X673423Y169152D01*
X673132Y169277D01*
X672840Y169485D01*
X672632Y169777D01*
X672590Y170068D01*
X672673Y170360D01*
X672882Y170568D01*
G01X675090Y172877D02*
X674548Y172960D01*
X674090Y173085D01*
X673673Y173252D01*
X673215Y173460D01*
X672590Y173793D01*
Y172127D01*
G01X675090Y176060D02*
X672590D01*
X673090Y175560D01*
G01X675090D02*
Y176560D01*
G01X707650Y193250D02*
X703650D01*
Y185850D01*
G01X680590Y165927D02*
X678090D01*
Y166968D01*
X678215Y167302D01*
X678382Y167510D01*
X678715Y167593D01*
X679048Y167510D01*
X679257Y167260D01*
X679382Y166968D01*
Y165927D01*
G01Y166968D02*
X680590Y167593D01*
G01X679548Y169068D02*
X679257Y169360D01*
X679090Y169610D01*
X679007Y169943D01*
X679090Y170235D01*
X679257Y170443D01*
X679507Y170610D01*
X679798Y170652D01*
X680048Y170610D01*
X680298Y170443D01*
X680507Y170193D01*
X680590Y169902D01*
X680507Y169568D01*
X680257Y169277D01*
X679882Y169110D01*
X679465Y169068D01*
X678923Y169152D01*
X678632Y169277D01*
X678340Y169485D01*
X678132Y169777D01*
X678090Y170068D01*
X678173Y170360D01*
X678382Y170568D01*
G01X680590Y172877D02*
X680048Y172960D01*
X679590Y173085D01*
X679173Y173252D01*
X678715Y173460D01*
X678090Y173793D01*
Y172127D01*
G01X678507Y175268D02*
X678257Y175518D01*
X678132Y175810D01*
X678090Y176143D01*
X678173Y176560D01*
X678382Y176852D01*
X678632Y176935D01*
X678882Y176893D01*
X679090Y176727D01*
X679507Y175893D01*
X679798Y175518D01*
X680215Y175268D01*
X680590Y175185D01*
Y176935D01*
G01X713150Y193250D02*
X709150D01*
Y185850D01*
G01X694240Y180960D02*
X696740D01*
G01X694240Y180002D02*
Y181918D01*
G01X696740Y183227D02*
X694240D01*
Y184227D01*
X694365Y184560D01*
X694657Y184810D01*
X694990Y184893D01*
X695323Y184810D01*
X695573Y184602D01*
X695698Y184227D01*
Y183227D01*
G01X696740Y187160D02*
X694240D01*
X694740Y186660D01*
G01X696740D02*
Y187660D01*
G01X695698Y189468D02*
X695407Y189760D01*
X695240Y190010D01*
X695157Y190343D01*
X695240Y190635D01*
X695407Y190843D01*
X695657Y191010D01*
X695948Y191052D01*
X696198Y191010D01*
X696448Y190843D01*
X696657Y190593D01*
X696740Y190302D01*
X696657Y189968D01*
X696407Y189677D01*
X696032Y189510D01*
X695615Y189468D01*
X695073Y189552D01*
X694782Y189677D01*
X694490Y189885D01*
X694282Y190177D01*
X694240Y190468D01*
X694323Y190760D01*
X694532Y190968D01*
G01X694657Y192568D02*
X694407Y192818D01*
X694282Y193110D01*
X694240Y193443D01*
X694323Y193860D01*
X694532Y194152D01*
X694782Y194235D01*
X695032Y194193D01*
X695240Y194027D01*
X695657Y193193D01*
X695948Y192818D01*
X696365Y192568D01*
X696740Y192485D01*
Y194235D01*
G01X699740Y180960D02*
X702240D01*
G01X699740Y180002D02*
Y181918D01*
G01X702240Y183227D02*
X699740D01*
Y184227D01*
X699865Y184560D01*
X700157Y184810D01*
X700490Y184893D01*
X700823Y184810D01*
X701073Y184602D01*
X701198Y184227D01*
Y183227D01*
G01X702240Y187160D02*
X699740D01*
X700240Y186660D01*
G01X702240D02*
Y187660D01*
G01X701198Y189468D02*
X700907Y189760D01*
X700740Y190010D01*
X700657Y190343D01*
X700740Y190635D01*
X700907Y190843D01*
X701157Y191010D01*
X701448Y191052D01*
X701698Y191010D01*
X701948Y190843D01*
X702157Y190593D01*
X702240Y190302D01*
X702157Y189968D01*
X701907Y189677D01*
X701532Y189510D01*
X701115Y189468D01*
X700573Y189552D01*
X700282Y189677D01*
X699990Y189885D01*
X699782Y190177D01*
X699740Y190468D01*
X699823Y190760D01*
X700032Y190968D01*
G01X702240Y193360D02*
X702198Y193652D01*
X702073Y193985D01*
X701865Y194193D01*
X701573Y194277D01*
X701282Y194193D01*
X701032Y193943D01*
X700907Y193568D01*
Y193152D01*
X700823Y192902D01*
X700615Y192693D01*
X700323Y192610D01*
X700032Y192735D01*
X699823Y193027D01*
X699740Y193360D01*
X699823Y193693D01*
X700032Y193985D01*
X700323Y194110D01*
X700615Y194027D01*
X700823Y193818D01*
X700907Y193568D01*
Y193152D01*
X701032Y192777D01*
X701282Y192527D01*
X701573Y192443D01*
X701865Y192527D01*
X702073Y192735D01*
X702198Y193068D01*
X702240Y193360D01*
G01X688940Y180960D02*
X691440D01*
G01X688940Y180002D02*
Y181918D01*
G01X691440Y183227D02*
X688940D01*
Y184227D01*
X689065Y184560D01*
X689357Y184810D01*
X689690Y184893D01*
X690023Y184810D01*
X690273Y184602D01*
X690398Y184227D01*
Y183227D01*
G01X691440Y187160D02*
X688940D01*
X689440Y186660D01*
G01X691440D02*
Y187660D01*
G01X690398Y189468D02*
X690107Y189760D01*
X689940Y190010D01*
X689857Y190343D01*
X689940Y190635D01*
X690107Y190843D01*
X690357Y191010D01*
X690648Y191052D01*
X690898Y191010D01*
X691148Y190843D01*
X691357Y190593D01*
X691440Y190302D01*
X691357Y189968D01*
X691107Y189677D01*
X690732Y189510D01*
X690315Y189468D01*
X689773Y189552D01*
X689482Y189677D01*
X689190Y189885D01*
X688982Y190177D01*
X688940Y190468D01*
X689023Y190760D01*
X689232Y190968D01*
G01X691065Y192443D02*
X691273Y192693D01*
X691398Y192985D01*
X691440Y193360D01*
X691357Y193735D01*
X691190Y194027D01*
X690898Y194235D01*
X690565Y194277D01*
X690232Y194193D01*
X690023Y193985D01*
X689857Y193693D01*
X689815Y193402D01*
X689857Y193110D01*
X690023Y192735D01*
X688940Y192860D01*
Y193985D01*
G01X671400Y145300D02*
X673900D01*
G01X671400Y144342D02*
Y146258D01*
G01X673900Y147567D02*
X671400D01*
Y148567D01*
X671525Y148900D01*
X671817Y149150D01*
X672150Y149233D01*
X672483Y149150D01*
X672733Y148942D01*
X672858Y148567D01*
Y147567D01*
G01X673900Y151500D02*
X671400D01*
X671900Y151000D01*
G01X673900D02*
Y152000D01*
G01Y154517D02*
X673358Y154600D01*
X672900Y154725D01*
X672483Y154892D01*
X672025Y155100D01*
X671400Y155433D01*
Y153767D01*
G01X673525Y156783D02*
X673733Y157033D01*
X673858Y157325D01*
X673900Y157700D01*
X673817Y158075D01*
X673650Y158367D01*
X673358Y158575D01*
X673025Y158617D01*
X672692Y158533D01*
X672483Y158325D01*
X672317Y158033D01*
X672275Y157742D01*
X672317Y157450D01*
X672483Y157075D01*
X671400Y157200D01*
Y158325D01*
G01X683100Y257400D02*
Y253400D01*
X690500D01*
G01X687042Y242547D02*
Y246547D01*
X679642D01*
G01X700300Y247400D02*
Y251400D01*
X692900D01*
G01X694600Y246800D02*
Y242800D01*
X702000D01*
G01X680000Y251100D02*
Y247100D01*
X687400D01*
G01X691900Y230400D02*
Y226400D01*
X699300D01*
G01X691900Y234400D02*
Y230400D01*
X699300D01*
G01X679117Y207600D02*
Y210100D01*
X680158D01*
X680492Y209975D01*
X680700Y209808D01*
X680783Y209475D01*
X680700Y209142D01*
X680450Y208933D01*
X680158Y208808D01*
X679117D01*
G01X680158D02*
X680783Y207600D01*
G01X682258Y208642D02*
X682550Y208933D01*
X682800Y209100D01*
X683133Y209183D01*
X683425Y209100D01*
X683633Y208933D01*
X683800Y208683D01*
X683842Y208392D01*
X683800Y208142D01*
X683633Y207892D01*
X683383Y207683D01*
X683092Y207600D01*
X682758Y207683D01*
X682467Y207933D01*
X682300Y208308D01*
X682258Y208725D01*
X682342Y209267D01*
X682467Y209558D01*
X682675Y209850D01*
X682967Y210058D01*
X683258Y210100D01*
X683550Y210017D01*
X683758Y209808D01*
G01X686067Y207600D02*
X686150Y208142D01*
X686275Y208600D01*
X686442Y209017D01*
X686650Y209475D01*
X686983Y210100D01*
X685317D01*
G01X689750Y207600D02*
Y210100D01*
X688208Y208308D01*
X690292D01*
G01X701500Y205600D02*
Y209600D01*
X694100D01*
G01X691900Y238850D02*
Y234850D01*
X699300D01*
G01X679447Y242430D02*
Y238430D01*
X686847D01*
G01X683600Y267100D02*
Y263100D01*
X691000D01*
G01X683200Y261500D02*
Y257500D01*
X690600D01*
G01X679020Y211743D02*
Y214243D01*
X680061D01*
X680395Y214118D01*
X680603Y213951D01*
X680686Y213618D01*
X680603Y213285D01*
X680353Y213076D01*
X680061Y212951D01*
X679020D01*
G01X680061D02*
X680686Y211743D01*
G01X682870D02*
X682953Y212285D01*
X683078Y212743D01*
X683245Y213160D01*
X683453Y213618D01*
X683786Y214243D01*
X682120D01*
G01X685261Y212785D02*
X685553Y213076D01*
X685803Y213243D01*
X686136Y213326D01*
X686428Y213243D01*
X686636Y213076D01*
X686803Y212826D01*
X686845Y212535D01*
X686803Y212285D01*
X686636Y212035D01*
X686386Y211826D01*
X686095Y211743D01*
X685761Y211826D01*
X685470Y212076D01*
X685303Y212451D01*
X685261Y212868D01*
X685345Y213410D01*
X685470Y213701D01*
X685678Y213993D01*
X685970Y214201D01*
X686261Y214243D01*
X686553Y214160D01*
X686761Y213951D01*
G01X688361Y212785D02*
X688653Y213076D01*
X688903Y213243D01*
X689236Y213326D01*
X689528Y213243D01*
X689736Y213076D01*
X689903Y212826D01*
X689945Y212535D01*
X689903Y212285D01*
X689736Y212035D01*
X689486Y211826D01*
X689195Y211743D01*
X688861Y211826D01*
X688570Y212076D01*
X688403Y212451D01*
X688361Y212868D01*
X688445Y213410D01*
X688570Y213701D01*
X688778Y213993D01*
X689070Y214201D01*
X689361Y214243D01*
X689653Y214160D01*
X689861Y213951D01*
G01X694003Y213743D02*
Y209743D01*
X701403D01*
G01X679229Y203684D02*
Y206184D01*
X680270D01*
X680604Y206059D01*
X680812Y205892D01*
X680895Y205559D01*
X680812Y205226D01*
X680562Y205017D01*
X680270Y204892D01*
X679229D01*
G01X680270D02*
X680895Y203684D01*
G01X683079D02*
X683162Y204226D01*
X683287Y204684D01*
X683454Y205101D01*
X683662Y205559D01*
X683995Y206184D01*
X682329D01*
G01X685470Y205767D02*
X685720Y206017D01*
X686012Y206142D01*
X686345Y206184D01*
X686762Y206101D01*
X687054Y205892D01*
X687137Y205642D01*
X687095Y205392D01*
X686929Y205184D01*
X686095Y204767D01*
X685720Y204476D01*
X685470Y204059D01*
X685387Y203684D01*
X687137D01*
G01X688654Y203976D02*
X688945Y203767D01*
X689279Y203684D01*
X689612Y203767D01*
X689904Y204017D01*
X690112Y204392D01*
X690195Y204767D01*
Y205226D01*
X690112Y205601D01*
X689904Y205934D01*
X689654Y206101D01*
X689362Y206184D01*
X689029Y206101D01*
X688779Y205934D01*
X688612Y205684D01*
X688529Y205351D01*
X688612Y205059D01*
X688820Y204767D01*
X689070Y204601D01*
X689362Y204559D01*
X689695Y204642D01*
X689945Y204851D01*
X690195Y205226D01*
G01X694150Y205560D02*
Y201560D01*
X701550D01*
G01X709842Y217204D02*
Y295394D01*
G01Y208936D02*
Y213504D01*
G01X719960Y207086D02*
X798150D01*
G01X711692D02*
X716260D01*
G01X711692D02*
G02I-1850J0D01*
G01Y215354D02*
G02I-1850J0D01*
G01X719960Y207086D02*
G02I-1850J0D01*
G01X683547Y279530D02*
Y275530D01*
X690947D01*
G01X683547Y271230D02*
Y267230D01*
X690947D01*
G01X683400Y287900D02*
Y283900D01*
X690800D01*
G01X716090Y330240D02*
X712090D01*
Y322840D01*
G01X708060Y322860D02*
X712060D01*
Y330260D01*
G01X708000Y330200D02*
X704000D01*
Y322800D01*
G01X683547Y283730D02*
Y279730D01*
X690947D01*
G01X680800Y309000D02*
Y305000D01*
X688200D01*
G01X683547Y275430D02*
Y271430D01*
X690947D01*
G01X732850Y324000D02*
Y321500D01*
G01X731892Y324000D02*
X733808D01*
G01X735117Y321500D02*
Y324000D01*
X736117D01*
X736450Y323875D01*
X736700Y323583D01*
X736783Y323250D01*
X736700Y322917D01*
X736492Y322667D01*
X736117Y322542D01*
X735117D01*
G01X738342Y321792D02*
X738633Y321583D01*
X738967Y321500D01*
X739300Y321583D01*
X739592Y321833D01*
X739800Y322208D01*
X739883Y322583D01*
Y323042D01*
X739800Y323417D01*
X739592Y323750D01*
X739342Y323917D01*
X739050Y324000D01*
X738717Y323917D01*
X738467Y323750D01*
X738300Y323500D01*
X738217Y323167D01*
X738300Y322875D01*
X738508Y322583D01*
X738758Y322417D01*
X739050Y322375D01*
X739383Y322458D01*
X739633Y322667D01*
X739883Y323042D01*
G01X742150Y321500D02*
X742442Y321542D01*
X742775Y321667D01*
X742983Y321875D01*
X743067Y322167D01*
X742983Y322458D01*
X742733Y322708D01*
X742358Y322833D01*
X741942D01*
X741692Y322917D01*
X741483Y323125D01*
X741400Y323417D01*
X741525Y323708D01*
X741817Y323917D01*
X742150Y324000D01*
X742483Y323917D01*
X742775Y323708D01*
X742900Y323417D01*
X742817Y323125D01*
X742608Y322917D01*
X742358Y322833D01*
X741942D01*
X741567Y322708D01*
X741317Y322458D01*
X741233Y322167D01*
X741317Y321875D01*
X741525Y321667D01*
X741858Y321542D01*
X742150Y321500D01*
G01X725800Y318500D02*
Y316000D01*
G01X724842Y318500D02*
X726758D01*
G01X728067Y316000D02*
Y318500D01*
X729067D01*
X729400Y318375D01*
X729650Y318083D01*
X729733Y317750D01*
X729650Y317417D01*
X729442Y317167D01*
X729067Y317042D01*
X728067D01*
G01X732000Y316000D02*
Y318500D01*
X731500Y318000D01*
G01Y316000D02*
X732500D01*
G01X734183Y316375D02*
X734433Y316167D01*
X734725Y316042D01*
X735100Y316000D01*
X735475Y316083D01*
X735767Y316250D01*
X735975Y316542D01*
X736017Y316875D01*
X735933Y317208D01*
X735725Y317417D01*
X735433Y317583D01*
X735142Y317625D01*
X734850Y317583D01*
X734475Y317417D01*
X734600Y318500D01*
X735725D01*
G01X738117Y316000D02*
X738200Y316542D01*
X738325Y317000D01*
X738492Y317417D01*
X738700Y317875D01*
X739033Y318500D01*
X737367D01*
G01X673800Y296167D02*
Y293667D01*
G01X672842Y296167D02*
X674758D01*
G01X676067Y293667D02*
Y296167D01*
X677067D01*
X677400Y296042D01*
X677650Y295750D01*
X677733Y295417D01*
X677650Y295084D01*
X677442Y294834D01*
X677067Y294709D01*
X676067D01*
G01X680000Y293667D02*
Y296167D01*
X679500Y295667D01*
G01Y293667D02*
X680500D01*
G01X682308Y295750D02*
X682558Y296000D01*
X682850Y296125D01*
X683183Y296167D01*
X683600Y296084D01*
X683892Y295875D01*
X683975Y295625D01*
X683933Y295375D01*
X683767Y295167D01*
X682933Y294750D01*
X682558Y294459D01*
X682308Y294042D01*
X682225Y293667D01*
X683975D01*
G01X686200D02*
Y296167D01*
X685700Y295667D01*
G01Y293667D02*
X686700D01*
G01X668034Y313600D02*
X670534D01*
G01X668034Y312642D02*
Y314558D01*
G01X670534Y315867D02*
X668034D01*
Y316867D01*
X668159Y317200D01*
X668451Y317450D01*
X668784Y317533D01*
X669117Y317450D01*
X669367Y317242D01*
X669492Y316867D01*
Y315867D01*
G01X670534Y319800D02*
X668034D01*
X668534Y319300D01*
G01X670534D02*
Y320300D01*
G01X670034Y321983D02*
X670326Y322233D01*
X670492Y322567D01*
X670534Y322942D01*
X670492Y323275D01*
X670284Y323608D01*
X670034Y323817D01*
X669784Y323858D01*
X669492Y323775D01*
X669284Y323483D01*
X669201Y323192D01*
Y322817D01*
G01Y323192D02*
X669076Y323442D01*
X668867Y323650D01*
X668617Y323733D01*
X668367Y323650D01*
X668159Y323442D01*
X668034Y323067D01*
X668076Y322692D01*
X668242Y322317D01*
G01X670034Y325083D02*
X670326Y325333D01*
X670492Y325667D01*
X670534Y326042D01*
X670492Y326375D01*
X670284Y326708D01*
X670034Y326917D01*
X669784Y326958D01*
X669492Y326875D01*
X669284Y326583D01*
X669201Y326292D01*
Y325917D01*
G01Y326292D02*
X669076Y326542D01*
X668867Y326750D01*
X668617Y326833D01*
X668367Y326750D01*
X668159Y326542D01*
X668034Y326167D01*
X668076Y325792D01*
X668242Y325417D01*
G01X677350Y318666D02*
Y316166D01*
G01X676392Y318666D02*
X678308D01*
G01X679617Y316166D02*
Y318666D01*
X680617D01*
X680950Y318541D01*
X681200Y318249D01*
X681283Y317916D01*
X681200Y317583D01*
X680992Y317333D01*
X680617Y317208D01*
X679617D01*
G01X682842Y316458D02*
X683133Y316249D01*
X683467Y316166D01*
X683800Y316249D01*
X684092Y316499D01*
X684300Y316874D01*
X684383Y317249D01*
Y317708D01*
X684300Y318083D01*
X684092Y318416D01*
X683842Y318583D01*
X683550Y318666D01*
X683217Y318583D01*
X682967Y318416D01*
X682800Y318166D01*
X682717Y317833D01*
X682800Y317541D01*
X683008Y317249D01*
X683258Y317083D01*
X683550Y317041D01*
X683883Y317124D01*
X684133Y317333D01*
X684383Y317708D01*
G01X686650Y318666D02*
X686317Y318583D01*
X686067Y318374D01*
X685900Y318124D01*
X685775Y317791D01*
X685733Y317416D01*
X685775Y317041D01*
X685900Y316708D01*
X686067Y316458D01*
X686317Y316249D01*
X686650Y316166D01*
X686983Y316249D01*
X687233Y316458D01*
X687400Y316708D01*
X687525Y317041D01*
X687567Y317416D01*
X687525Y317791D01*
X687400Y318124D01*
X687233Y318374D01*
X686983Y318583D01*
X686650Y318666D01*
G01X674850Y292167D02*
Y289667D01*
G01X673892Y292167D02*
X675808D01*
G01X677117Y289667D02*
Y292167D01*
X678117D01*
X678450Y292042D01*
X678700Y291750D01*
X678783Y291417D01*
X678700Y291084D01*
X678492Y290834D01*
X678117Y290709D01*
X677117D01*
G01X680342Y289959D02*
X680633Y289750D01*
X680967Y289667D01*
X681300Y289750D01*
X681592Y290000D01*
X681800Y290375D01*
X681883Y290750D01*
Y291209D01*
X681800Y291584D01*
X681592Y291917D01*
X681342Y292084D01*
X681050Y292167D01*
X680717Y292084D01*
X680467Y291917D01*
X680300Y291667D01*
X680217Y291334D01*
X680300Y291042D01*
X680508Y290750D01*
X680758Y290584D01*
X681050Y290542D01*
X681383Y290625D01*
X681633Y290834D01*
X681883Y291209D01*
G01X683233Y290167D02*
X683483Y289875D01*
X683817Y289709D01*
X684192Y289667D01*
X684525Y289709D01*
X684858Y289917D01*
X685067Y290167D01*
X685108Y290417D01*
X685025Y290709D01*
X684733Y290917D01*
X684442Y291000D01*
X684067D01*
G01X684442D02*
X684692Y291125D01*
X684900Y291334D01*
X684983Y291584D01*
X684900Y291834D01*
X684692Y292042D01*
X684317Y292167D01*
X683942Y292125D01*
X683567Y291959D01*
G01X675350Y300167D02*
Y297667D01*
G01X674392Y300167D02*
X676308D01*
G01X677617Y297667D02*
Y300167D01*
X678617D01*
X678950Y300042D01*
X679200Y299750D01*
X679283Y299417D01*
X679200Y299084D01*
X678992Y298834D01*
X678617Y298709D01*
X677617D01*
G01X680842Y297959D02*
X681133Y297750D01*
X681467Y297667D01*
X681800Y297750D01*
X682092Y298000D01*
X682300Y298375D01*
X682383Y298750D01*
Y299209D01*
X682300Y299584D01*
X682092Y299917D01*
X681842Y300084D01*
X681550Y300167D01*
X681217Y300084D01*
X680967Y299917D01*
X680800Y299667D01*
X680717Y299334D01*
X680800Y299042D01*
X681008Y298750D01*
X681258Y298584D01*
X681550Y298542D01*
X681883Y298625D01*
X682133Y298834D01*
X682383Y299209D01*
G01X683858Y298709D02*
X684150Y299000D01*
X684400Y299167D01*
X684733Y299250D01*
X685025Y299167D01*
X685233Y299000D01*
X685400Y298750D01*
X685442Y298459D01*
X685400Y298209D01*
X685233Y297959D01*
X684983Y297750D01*
X684692Y297667D01*
X684358Y297750D01*
X684067Y298000D01*
X683900Y298375D01*
X683858Y298792D01*
X683942Y299334D01*
X684067Y299625D01*
X684275Y299917D01*
X684567Y300125D01*
X684858Y300167D01*
X685150Y300084D01*
X685358Y299875D01*
G01X690400Y316166D02*
Y313666D01*
G01X689442Y316166D02*
X691358D01*
G01X692667Y313666D02*
Y316166D01*
X693667D01*
X694000Y316041D01*
X694250Y315749D01*
X694333Y315416D01*
X694250Y315083D01*
X694042Y314833D01*
X693667Y314708D01*
X692667D01*
G01X696600Y313666D02*
Y316166D01*
X696100Y315666D01*
G01Y313666D02*
X697100D01*
G01X699700Y316166D02*
X699367Y316083D01*
X699117Y315874D01*
X698950Y315624D01*
X698825Y315291D01*
X698783Y314916D01*
X698825Y314541D01*
X698950Y314208D01*
X699117Y313958D01*
X699367Y313749D01*
X699700Y313666D01*
X700033Y313749D01*
X700283Y313958D01*
X700450Y314208D01*
X700575Y314541D01*
X700617Y314916D01*
X700575Y315291D01*
X700450Y315624D01*
X700283Y315874D01*
X700033Y316083D01*
X699700Y316166D01*
G01X702717Y313666D02*
X702800Y314208D01*
X702925Y314666D01*
X703092Y315083D01*
X703300Y315541D01*
X703633Y316166D01*
X701967D01*
G01X709842Y303662D02*
Y299094D01*
G01X719960Y305512D02*
X798150D01*
G01X711692D02*
X716260D01*
G01X711692D02*
G02I-1850J0D01*
G01Y297244D02*
G02I-1850J0D01*
G01X719960Y305512D02*
G02I-1850J0D01*
G01X725067Y398659D02*
X724817Y398784D01*
X724525Y398867D01*
X724192D01*
X723817Y398742D01*
X723525Y398534D01*
X723317Y398284D01*
X723150Y397867D01*
X723108Y397492D01*
X723192Y397117D01*
X723317Y396867D01*
X723567Y396617D01*
X723858Y396450D01*
X724150Y396367D01*
X724442D01*
X724733Y396450D01*
X724983Y396575D01*
X725192Y396742D01*
G01X726458Y398450D02*
X726708Y398700D01*
X727000Y398825D01*
X727333Y398867D01*
X727750Y398784D01*
X728042Y398575D01*
X728125Y398325D01*
X728083Y398075D01*
X727917Y397867D01*
X727083Y397450D01*
X726708Y397159D01*
X726458Y396742D01*
X726375Y396367D01*
X728125D01*
G01X729558Y397409D02*
X729850Y397700D01*
X730100Y397867D01*
X730433Y397950D01*
X730725Y397867D01*
X730933Y397700D01*
X731100Y397450D01*
X731142Y397159D01*
X731100Y396909D01*
X730933Y396659D01*
X730683Y396450D01*
X730392Y396367D01*
X730058Y396450D01*
X729767Y396700D01*
X729600Y397075D01*
X729558Y397492D01*
X729642Y398034D01*
X729767Y398325D01*
X729975Y398617D01*
X730267Y398825D01*
X730558Y398867D01*
X730850Y398784D01*
X731058Y398575D01*
G01X732742Y396659D02*
X733033Y396450D01*
X733367Y396367D01*
X733700Y396450D01*
X733992Y396700D01*
X734200Y397075D01*
X734283Y397450D01*
Y397909D01*
X734200Y398284D01*
X733992Y398617D01*
X733742Y398784D01*
X733450Y398867D01*
X733117Y398784D01*
X732867Y398617D01*
X732700Y398367D01*
X732617Y398034D01*
X732700Y397742D01*
X732908Y397450D01*
X733158Y397284D01*
X733450Y397242D01*
X733783Y397325D01*
X734033Y397534D01*
X734283Y397909D01*
G01X724834Y379517D02*
X722334D01*
Y380558D01*
X722459Y380892D01*
X722626Y381100D01*
X722959Y381183D01*
X723292Y381100D01*
X723501Y380850D01*
X723626Y380558D01*
Y379517D01*
G01Y380558D02*
X724834Y381183D01*
G01X723792Y382658D02*
X723501Y382950D01*
X723334Y383200D01*
X723251Y383533D01*
X723334Y383825D01*
X723501Y384033D01*
X723751Y384200D01*
X724042Y384242D01*
X724292Y384200D01*
X724542Y384033D01*
X724751Y383783D01*
X724834Y383492D01*
X724751Y383158D01*
X724501Y382867D01*
X724126Y382700D01*
X723709Y382658D01*
X723167Y382742D01*
X722876Y382867D01*
X722584Y383075D01*
X722376Y383367D01*
X722334Y383658D01*
X722417Y383950D01*
X722626Y384158D01*
G01X724834Y387050D02*
X722334D01*
X724126Y385508D01*
Y387592D01*
G01X724834Y389650D02*
X722334D01*
X722834Y389150D01*
G01X724834D02*
Y390150D01*
G01X729200Y361500D02*
X725200D01*
Y354100D01*
G01X724834Y366017D02*
X722334D01*
Y367058D01*
X722459Y367392D01*
X722626Y367600D01*
X722959Y367683D01*
X723292Y367600D01*
X723501Y367350D01*
X723626Y367058D01*
Y366017D01*
G01Y367058D02*
X724834Y367683D01*
G01X723792Y369158D02*
X723501Y369450D01*
X723334Y369700D01*
X723251Y370033D01*
X723334Y370325D01*
X723501Y370533D01*
X723751Y370700D01*
X724042Y370742D01*
X724292Y370700D01*
X724542Y370533D01*
X724751Y370283D01*
X724834Y369992D01*
X724751Y369658D01*
X724501Y369367D01*
X724126Y369200D01*
X723709Y369158D01*
X723167Y369242D01*
X722876Y369367D01*
X722584Y369575D01*
X722376Y369867D01*
X722334Y370158D01*
X722417Y370450D01*
X722626Y370658D01*
G01X724459Y372133D02*
X724667Y372383D01*
X724792Y372675D01*
X724834Y373050D01*
X724751Y373425D01*
X724584Y373717D01*
X724292Y373925D01*
X723959Y373967D01*
X723626Y373883D01*
X723417Y373675D01*
X723251Y373383D01*
X723209Y373092D01*
X723251Y372800D01*
X723417Y372425D01*
X722334Y372550D01*
Y373675D01*
G01X724334Y375233D02*
X724626Y375483D01*
X724792Y375817D01*
X724834Y376192D01*
X724792Y376525D01*
X724584Y376858D01*
X724334Y377067D01*
X724084Y377108D01*
X723792Y377025D01*
X723584Y376733D01*
X723501Y376442D01*
Y376067D01*
G01Y376442D02*
X723376Y376692D01*
X723167Y376900D01*
X722917Y376983D01*
X722667Y376900D01*
X722459Y376692D01*
X722334Y376317D01*
X722376Y375942D01*
X722542Y375567D01*
G01X725000Y344300D02*
X729000D01*
Y351700D01*
G01X720834Y366017D02*
X718334D01*
Y367058D01*
X718459Y367392D01*
X718626Y367600D01*
X718959Y367683D01*
X719292Y367600D01*
X719501Y367350D01*
X719626Y367058D01*
Y366017D01*
G01Y367058D02*
X720834Y367683D01*
G01X719792Y369158D02*
X719501Y369450D01*
X719334Y369700D01*
X719251Y370033D01*
X719334Y370325D01*
X719501Y370533D01*
X719751Y370700D01*
X720042Y370742D01*
X720292Y370700D01*
X720542Y370533D01*
X720751Y370283D01*
X720834Y369992D01*
X720751Y369658D01*
X720501Y369367D01*
X720126Y369200D01*
X719709Y369158D01*
X719167Y369242D01*
X718876Y369367D01*
X718584Y369575D01*
X718376Y369867D01*
X718334Y370158D01*
X718417Y370450D01*
X718626Y370658D01*
G01X718751Y372258D02*
X718501Y372508D01*
X718376Y372800D01*
X718334Y373133D01*
X718417Y373550D01*
X718626Y373842D01*
X718876Y373925D01*
X719126Y373883D01*
X719334Y373717D01*
X719751Y372883D01*
X720042Y372508D01*
X720459Y372258D01*
X720834Y372175D01*
Y373925D01*
G01Y376067D02*
X720292Y376150D01*
X719834Y376275D01*
X719417Y376442D01*
X718959Y376650D01*
X718334Y376983D01*
Y375317D01*
G01X724500Y351700D02*
X720500D01*
Y344300D01*
G01X729334Y379517D02*
X726834D01*
Y380558D01*
X726959Y380892D01*
X727126Y381100D01*
X727459Y381183D01*
X727792Y381100D01*
X728001Y380850D01*
X728126Y380558D01*
Y379517D01*
G01Y380558D02*
X729334Y381183D01*
G01X728292Y382658D02*
X728001Y382950D01*
X727834Y383200D01*
X727751Y383533D01*
X727834Y383825D01*
X728001Y384033D01*
X728251Y384200D01*
X728542Y384242D01*
X728792Y384200D01*
X729042Y384033D01*
X729251Y383783D01*
X729334Y383492D01*
X729251Y383158D01*
X729001Y382867D01*
X728626Y382700D01*
X728209Y382658D01*
X727667Y382742D01*
X727376Y382867D01*
X727084Y383075D01*
X726876Y383367D01*
X726834Y383658D01*
X726917Y383950D01*
X727126Y384158D01*
G01X728959Y385633D02*
X729167Y385883D01*
X729292Y386175D01*
X729334Y386550D01*
X729251Y386925D01*
X729084Y387217D01*
X728792Y387425D01*
X728459Y387467D01*
X728126Y387383D01*
X727917Y387175D01*
X727751Y386883D01*
X727709Y386592D01*
X727751Y386300D01*
X727917Y385925D01*
X726834Y386050D01*
Y387175D01*
G01X729042Y388942D02*
X729251Y389233D01*
X729334Y389567D01*
X729251Y389900D01*
X729001Y390192D01*
X728626Y390400D01*
X728251Y390483D01*
X727792D01*
X727417Y390400D01*
X727084Y390192D01*
X726917Y389942D01*
X726834Y389650D01*
X726917Y389317D01*
X727084Y389067D01*
X727334Y388900D01*
X727667Y388817D01*
X727959Y388900D01*
X728251Y389108D01*
X728417Y389358D01*
X728459Y389650D01*
X728376Y389983D01*
X728167Y390233D01*
X727792Y390483D01*
G01X729400Y354000D02*
X733400D01*
Y361400D01*
G01X712334Y379517D02*
X709834D01*
Y380558D01*
X709959Y380892D01*
X710126Y381100D01*
X710459Y381183D01*
X710792Y381100D01*
X711001Y380850D01*
X711126Y380558D01*
Y379517D01*
G01Y380558D02*
X712334Y381183D01*
G01X711292Y382658D02*
X711001Y382950D01*
X710834Y383200D01*
X710751Y383533D01*
X710834Y383825D01*
X711001Y384033D01*
X711251Y384200D01*
X711542Y384242D01*
X711792Y384200D01*
X712042Y384033D01*
X712251Y383783D01*
X712334Y383492D01*
X712251Y383158D01*
X712001Y382867D01*
X711626Y382700D01*
X711209Y382658D01*
X710667Y382742D01*
X710376Y382867D01*
X710084Y383075D01*
X709876Y383367D01*
X709834Y383658D01*
X709917Y383950D01*
X710126Y384158D01*
G01X712334Y387050D02*
X709834D01*
X711626Y385508D01*
Y387592D01*
G01X710251Y388858D02*
X710001Y389108D01*
X709876Y389400D01*
X709834Y389733D01*
X709917Y390150D01*
X710126Y390442D01*
X710376Y390525D01*
X710626Y390483D01*
X710834Y390317D01*
X711251Y389483D01*
X711542Y389108D01*
X711959Y388858D01*
X712334Y388775D01*
Y390525D01*
G01X715500Y361600D02*
X711500D01*
Y354200D01*
G01X702424Y347857D02*
X699924D01*
Y348898D01*
X700049Y349232D01*
X700216Y349440D01*
X700549Y349523D01*
X700882Y349440D01*
X701091Y349190D01*
X701216Y348898D01*
Y347857D01*
G01Y348898D02*
X702424Y349523D01*
G01X701382Y350998D02*
X701091Y351290D01*
X700924Y351540D01*
X700841Y351873D01*
X700924Y352165D01*
X701091Y352373D01*
X701341Y352540D01*
X701632Y352582D01*
X701882Y352540D01*
X702132Y352373D01*
X702341Y352123D01*
X702424Y351832D01*
X702341Y351498D01*
X702091Y351207D01*
X701716Y351040D01*
X701299Y350998D01*
X700757Y351082D01*
X700466Y351207D01*
X700174Y351415D01*
X699966Y351707D01*
X699924Y351998D01*
X700007Y352290D01*
X700216Y352498D01*
G01X702424Y355390D02*
X699924D01*
X701716Y353848D01*
Y355932D01*
G01X702424Y358490D02*
X699924D01*
X701716Y356948D01*
Y359032D01*
G01X698394Y347877D02*
X695894D01*
Y348918D01*
X696019Y349252D01*
X696186Y349460D01*
X696519Y349543D01*
X696852Y349460D01*
X697061Y349210D01*
X697186Y348918D01*
Y347877D01*
G01Y348918D02*
X698394Y349543D01*
G01X697352Y351018D02*
X697061Y351310D01*
X696894Y351560D01*
X696811Y351893D01*
X696894Y352185D01*
X697061Y352393D01*
X697311Y352560D01*
X697602Y352602D01*
X697852Y352560D01*
X698102Y352393D01*
X698311Y352143D01*
X698394Y351852D01*
X698311Y351518D01*
X698061Y351227D01*
X697686Y351060D01*
X697269Y351018D01*
X696727Y351102D01*
X696436Y351227D01*
X696144Y351435D01*
X695936Y351727D01*
X695894Y352018D01*
X695977Y352310D01*
X696186Y352518D01*
G01X698019Y353993D02*
X698227Y354243D01*
X698352Y354535D01*
X698394Y354910D01*
X698311Y355285D01*
X698144Y355577D01*
X697852Y355785D01*
X697519Y355827D01*
X697186Y355743D01*
X696977Y355535D01*
X696811Y355243D01*
X696769Y354952D01*
X696811Y354660D01*
X696977Y354285D01*
X695894Y354410D01*
Y355535D01*
G01X697352Y357218D02*
X697061Y357510D01*
X696894Y357760D01*
X696811Y358093D01*
X696894Y358385D01*
X697061Y358593D01*
X697311Y358760D01*
X697602Y358802D01*
X697852Y358760D01*
X698102Y358593D01*
X698311Y358343D01*
X698394Y358052D01*
X698311Y357718D01*
X698061Y357427D01*
X697686Y357260D01*
X697269Y357218D01*
X696727Y357302D01*
X696436Y357427D01*
X696144Y357635D01*
X695936Y357927D01*
X695894Y358218D01*
X695977Y358510D01*
X696186Y358718D01*
G01X716834Y366017D02*
X714334D01*
Y367058D01*
X714459Y367392D01*
X714626Y367600D01*
X714959Y367683D01*
X715292Y367600D01*
X715501Y367350D01*
X715626Y367058D01*
Y366017D01*
G01Y367058D02*
X716834Y367683D01*
G01X715792Y369158D02*
X715501Y369450D01*
X715334Y369700D01*
X715251Y370033D01*
X715334Y370325D01*
X715501Y370533D01*
X715751Y370700D01*
X716042Y370742D01*
X716292Y370700D01*
X716542Y370533D01*
X716751Y370283D01*
X716834Y369992D01*
X716751Y369658D01*
X716501Y369367D01*
X716126Y369200D01*
X715709Y369158D01*
X715167Y369242D01*
X714876Y369367D01*
X714584Y369575D01*
X714376Y369867D01*
X714334Y370158D01*
X714417Y370450D01*
X714626Y370658D01*
G01X714751Y372258D02*
X714501Y372508D01*
X714376Y372800D01*
X714334Y373133D01*
X714417Y373550D01*
X714626Y373842D01*
X714876Y373925D01*
X715126Y373883D01*
X715334Y373717D01*
X715751Y372883D01*
X716042Y372508D01*
X716459Y372258D01*
X716834Y372175D01*
Y373925D01*
G01Y376150D02*
X714334D01*
X714834Y375650D01*
G01X716834D02*
Y376650D01*
G01X720000Y351700D02*
X716000D01*
Y344300D01*
G01X712334Y365517D02*
X709834D01*
Y366558D01*
X709959Y366892D01*
X710126Y367100D01*
X710459Y367183D01*
X710792Y367100D01*
X711001Y366850D01*
X711126Y366558D01*
Y365517D01*
G01Y366558D02*
X712334Y367183D01*
G01X711292Y368658D02*
X711001Y368950D01*
X710834Y369200D01*
X710751Y369533D01*
X710834Y369825D01*
X711001Y370033D01*
X711251Y370200D01*
X711542Y370242D01*
X711792Y370200D01*
X712042Y370033D01*
X712251Y369783D01*
X712334Y369492D01*
X712251Y369158D01*
X712001Y368867D01*
X711626Y368700D01*
X711209Y368658D01*
X710667Y368742D01*
X710376Y368867D01*
X710084Y369075D01*
X709876Y369367D01*
X709834Y369658D01*
X709917Y369950D01*
X710126Y370158D01*
G01X711959Y371633D02*
X712167Y371883D01*
X712292Y372175D01*
X712334Y372550D01*
X712251Y372925D01*
X712084Y373217D01*
X711792Y373425D01*
X711459Y373467D01*
X711126Y373383D01*
X710917Y373175D01*
X710751Y372883D01*
X710709Y372592D01*
X710751Y372300D01*
X710917Y371925D01*
X709834Y372050D01*
Y373175D01*
G01X712334Y376150D02*
X709834D01*
X711626Y374608D01*
Y376692D01*
G01X709700Y343300D02*
X713700D01*
Y350700D01*
G01X694834Y347817D02*
X692334D01*
Y348858D01*
X692459Y349192D01*
X692626Y349400D01*
X692959Y349483D01*
X693292Y349400D01*
X693501Y349150D01*
X693626Y348858D01*
Y347817D01*
G01Y348858D02*
X694834Y349483D01*
G01X693792Y350958D02*
X693501Y351250D01*
X693334Y351500D01*
X693251Y351833D01*
X693334Y352125D01*
X693501Y352333D01*
X693751Y352500D01*
X694042Y352542D01*
X694292Y352500D01*
X694542Y352333D01*
X694751Y352083D01*
X694834Y351792D01*
X694751Y351458D01*
X694501Y351167D01*
X694126Y351000D01*
X693709Y350958D01*
X693167Y351042D01*
X692876Y351167D01*
X692584Y351375D01*
X692376Y351667D01*
X692334Y351958D01*
X692417Y352250D01*
X692626Y352458D01*
G01X692751Y354058D02*
X692501Y354308D01*
X692376Y354600D01*
X692334Y354933D01*
X692417Y355350D01*
X692626Y355642D01*
X692876Y355725D01*
X693126Y355683D01*
X693334Y355517D01*
X693751Y354683D01*
X694042Y354308D01*
X694459Y354058D01*
X694834Y353975D01*
Y355725D01*
G01Y357950D02*
X694792Y358242D01*
X694667Y358575D01*
X694459Y358783D01*
X694167Y358867D01*
X693876Y358783D01*
X693626Y358533D01*
X693501Y358158D01*
Y357742D01*
X693417Y357492D01*
X693209Y357283D01*
X692917Y357200D01*
X692626Y357325D01*
X692417Y357617D01*
X692334Y357950D01*
X692417Y358283D01*
X692626Y358575D01*
X692917Y358700D01*
X693209Y358617D01*
X693417Y358408D01*
X693501Y358158D01*
Y357742D01*
X693626Y357367D01*
X693876Y357117D01*
X694167Y357033D01*
X694459Y357117D01*
X694667Y357325D01*
X694792Y357658D01*
X694834Y357950D01*
G01X727800Y368566D02*
Y366066D01*
G01X726842Y368566D02*
X728758D01*
G01X730067Y366066D02*
Y368566D01*
X731067D01*
X731400Y368441D01*
X731650Y368149D01*
X731733Y367816D01*
X731650Y367483D01*
X731442Y367233D01*
X731067Y367108D01*
X730067D01*
G01X734000Y366066D02*
Y368566D01*
X733500Y368066D01*
G01Y366066D02*
X734500D01*
G01X737600D02*
Y368566D01*
X736058Y366774D01*
X738142D01*
G01X739283Y366441D02*
X739533Y366233D01*
X739825Y366108D01*
X740200Y366066D01*
X740575Y366149D01*
X740867Y366316D01*
X741075Y366608D01*
X741117Y366941D01*
X741033Y367274D01*
X740825Y367483D01*
X740533Y367649D01*
X740242Y367691D01*
X739950Y367649D01*
X739575Y367483D01*
X739700Y368566D01*
X740825D01*
G01X727300Y373666D02*
Y371166D01*
G01X726342Y373666D02*
X728258D01*
G01X729567Y371166D02*
Y373666D01*
X730567D01*
X730900Y373541D01*
X731150Y373249D01*
X731233Y372916D01*
X731150Y372583D01*
X730942Y372333D01*
X730567Y372208D01*
X729567D01*
G01X733500Y371166D02*
Y373666D01*
X733000Y373166D01*
G01Y371166D02*
X734000D01*
G01X735683Y371541D02*
X735933Y371333D01*
X736225Y371208D01*
X736600Y371166D01*
X736975Y371249D01*
X737267Y371416D01*
X737475Y371708D01*
X737517Y372041D01*
X737433Y372374D01*
X737225Y372583D01*
X736933Y372749D01*
X736642Y372791D01*
X736350Y372749D01*
X735975Y372583D01*
X736100Y373666D01*
X737225D01*
G01X739700Y371166D02*
X739992Y371208D01*
X740325Y371333D01*
X740533Y371541D01*
X740617Y371833D01*
X740533Y372124D01*
X740283Y372374D01*
X739908Y372499D01*
X739492D01*
X739242Y372583D01*
X739033Y372791D01*
X738950Y373083D01*
X739075Y373374D01*
X739367Y373583D01*
X739700Y373666D01*
X740033Y373583D01*
X740325Y373374D01*
X740450Y373083D01*
X740367Y372791D01*
X740158Y372583D01*
X739908Y372499D01*
X739492D01*
X739117Y372374D01*
X738867Y372124D01*
X738783Y371833D01*
X738867Y371541D01*
X739075Y371333D01*
X739408Y371208D01*
X739700Y371166D01*
G01X712300Y336666D02*
Y334166D01*
G01X711342Y336666D02*
X713258D01*
G01X714567Y334166D02*
Y336666D01*
X715567D01*
X715900Y336541D01*
X716150Y336249D01*
X716233Y335916D01*
X716150Y335583D01*
X715942Y335333D01*
X715567Y335208D01*
X714567D01*
G01X718500Y334166D02*
Y336666D01*
X718000Y336166D01*
G01Y334166D02*
X719000D01*
G01X722100D02*
Y336666D01*
X720558Y334874D01*
X722642D01*
G01X723908Y335208D02*
X724200Y335499D01*
X724450Y335666D01*
X724783Y335749D01*
X725075Y335666D01*
X725283Y335499D01*
X725450Y335249D01*
X725492Y334958D01*
X725450Y334708D01*
X725283Y334458D01*
X725033Y334249D01*
X724742Y334166D01*
X724408Y334249D01*
X724117Y334499D01*
X723950Y334874D01*
X723908Y335291D01*
X723992Y335833D01*
X724117Y336124D01*
X724325Y336416D01*
X724617Y336624D01*
X724908Y336666D01*
X725200Y336583D01*
X725408Y336374D01*
G01X692234Y332800D02*
X694734D01*
G01X692234Y331842D02*
Y333758D01*
G01X694734Y335067D02*
X692234D01*
Y336067D01*
X692359Y336400D01*
X692651Y336650D01*
X692984Y336733D01*
X693317Y336650D01*
X693567Y336442D01*
X693692Y336067D01*
Y335067D01*
G01X694734Y339000D02*
X692234D01*
X692734Y338500D01*
G01X694734D02*
Y339500D01*
G01Y342600D02*
X692234D01*
X694026Y341058D01*
Y343142D01*
G01X694734Y345117D02*
X694192Y345200D01*
X693734Y345325D01*
X693317Y345492D01*
X692859Y345700D01*
X692234Y346033D01*
Y344367D01*
G01X700334Y332100D02*
X702834D01*
G01X700334Y331142D02*
Y333058D01*
G01X702834Y334367D02*
X700334D01*
Y335367D01*
X700459Y335700D01*
X700751Y335950D01*
X701084Y336033D01*
X701417Y335950D01*
X701667Y335742D01*
X701792Y335367D01*
Y334367D01*
G01X702834Y338300D02*
X700334D01*
X700834Y337800D01*
G01X702834D02*
Y338800D01*
G01X700334Y341400D02*
X700417Y341067D01*
X700626Y340817D01*
X700876Y340650D01*
X701209Y340525D01*
X701584Y340483D01*
X701959Y340525D01*
X702292Y340650D01*
X702542Y340817D01*
X702751Y341067D01*
X702834Y341400D01*
X702751Y341733D01*
X702542Y341983D01*
X702292Y342150D01*
X701959Y342275D01*
X701584Y342317D01*
X701209Y342275D01*
X700876Y342150D01*
X700626Y341983D01*
X700417Y341733D01*
X700334Y341400D01*
G01X702459Y343583D02*
X702667Y343833D01*
X702792Y344125D01*
X702834Y344500D01*
X702751Y344875D01*
X702584Y345167D01*
X702292Y345375D01*
X701959Y345417D01*
X701626Y345333D01*
X701417Y345125D01*
X701251Y344833D01*
X701209Y344542D01*
X701251Y344250D01*
X701417Y343875D01*
X700334Y344000D01*
Y345125D01*
G01X685508Y448667D02*
X685383Y448417D01*
X685300Y448125D01*
Y447792D01*
X685425Y447417D01*
X685633Y447125D01*
X685883Y446917D01*
X686300Y446750D01*
X686675Y446708D01*
X687050Y446792D01*
X687300Y446917D01*
X687550Y447167D01*
X687717Y447458D01*
X687800Y447750D01*
Y448042D01*
X687717Y448333D01*
X687592Y448583D01*
X687425Y448792D01*
G01X685717Y450058D02*
X685467Y450308D01*
X685342Y450600D01*
X685300Y450933D01*
X685383Y451350D01*
X685592Y451642D01*
X685842Y451725D01*
X686092Y451683D01*
X686300Y451517D01*
X686717Y450683D01*
X687008Y450308D01*
X687425Y450058D01*
X687800Y449975D01*
Y451725D01*
G01X685717Y453158D02*
X685467Y453408D01*
X685342Y453700D01*
X685300Y454033D01*
X685383Y454450D01*
X685592Y454742D01*
X685842Y454825D01*
X686092Y454783D01*
X686300Y454617D01*
X686717Y453783D01*
X687008Y453408D01*
X687425Y453158D01*
X687800Y453075D01*
Y454825D01*
G01Y457050D02*
X685300D01*
X685800Y456550D01*
G01X687800D02*
Y457550D01*
G01X734017Y423972D02*
X733767Y424097D01*
X733475Y424180D01*
X733142D01*
X732767Y424055D01*
X732475Y423847D01*
X732267Y423597D01*
X732100Y423180D01*
X732058Y422805D01*
X732142Y422430D01*
X732267Y422180D01*
X732517Y421930D01*
X732808Y421763D01*
X733100Y421680D01*
X733392D01*
X733683Y421763D01*
X733933Y421888D01*
X734142Y422055D01*
G01X736117Y421680D02*
X736200Y422222D01*
X736325Y422680D01*
X736492Y423097D01*
X736700Y423555D01*
X737033Y424180D01*
X735367D01*
G01X739800Y421680D02*
Y424180D01*
X738258Y422388D01*
X740342D01*
G01X742900Y421680D02*
Y424180D01*
X741358Y422388D01*
X743442D01*
G01X673767Y437959D02*
X673517Y438084D01*
X673225Y438167D01*
X672892D01*
X672517Y438042D01*
X672225Y437834D01*
X672017Y437584D01*
X671850Y437167D01*
X671808Y436792D01*
X671892Y436417D01*
X672017Y436167D01*
X672267Y435917D01*
X672558Y435750D01*
X672850Y435667D01*
X673142D01*
X673433Y435750D01*
X673683Y435875D01*
X673892Y436042D01*
G01X675158Y437750D02*
X675408Y438000D01*
X675700Y438125D01*
X676033Y438167D01*
X676450Y438084D01*
X676742Y437875D01*
X676825Y437625D01*
X676783Y437375D01*
X676617Y437167D01*
X675783Y436750D01*
X675408Y436459D01*
X675158Y436042D01*
X675075Y435667D01*
X676825D01*
G01X678258Y437750D02*
X678508Y438000D01*
X678800Y438125D01*
X679133Y438167D01*
X679550Y438084D01*
X679842Y437875D01*
X679925Y437625D01*
X679883Y437375D01*
X679717Y437167D01*
X678883Y436750D01*
X678508Y436459D01*
X678258Y436042D01*
X678175Y435667D01*
X679925D01*
G01X682150Y438167D02*
X681817Y438084D01*
X681567Y437875D01*
X681400Y437625D01*
X681275Y437292D01*
X681233Y436917D01*
X681275Y436542D01*
X681400Y436209D01*
X681567Y435959D01*
X681817Y435750D01*
X682150Y435667D01*
X682483Y435750D01*
X682733Y435959D01*
X682900Y436209D01*
X683025Y436542D01*
X683067Y436917D01*
X683025Y437292D01*
X682900Y437625D01*
X682733Y437875D01*
X682483Y438084D01*
X682150Y438167D01*
G01X725167Y414692D02*
X724917Y414817D01*
X724625Y414900D01*
X724292D01*
X723917Y414775D01*
X723625Y414567D01*
X723417Y414317D01*
X723250Y413900D01*
X723208Y413525D01*
X723292Y413150D01*
X723417Y412900D01*
X723667Y412650D01*
X723958Y412483D01*
X724250Y412400D01*
X724542D01*
X724833Y412483D01*
X725083Y412608D01*
X725292Y412775D01*
G01X726558Y414483D02*
X726808Y414733D01*
X727100Y414858D01*
X727433Y414900D01*
X727850Y414817D01*
X728142Y414608D01*
X728225Y414358D01*
X728183Y414108D01*
X728017Y413900D01*
X727183Y413483D01*
X726808Y413192D01*
X726558Y412775D01*
X726475Y412400D01*
X728225D01*
G01X730367D02*
X730450Y412942D01*
X730575Y413400D01*
X730742Y413817D01*
X730950Y414275D01*
X731283Y414900D01*
X729617D01*
G01X733550D02*
X733217Y414817D01*
X732967Y414608D01*
X732800Y414358D01*
X732675Y414025D01*
X732633Y413650D01*
X732675Y413275D01*
X732800Y412942D01*
X732967Y412692D01*
X733217Y412483D01*
X733550Y412400D01*
X733883Y412483D01*
X734133Y412692D01*
X734300Y412942D01*
X734425Y413275D01*
X734467Y413650D01*
X734425Y414025D01*
X734300Y414358D01*
X734133Y414608D01*
X733883Y414817D01*
X733550Y414900D01*
G01X725067Y402659D02*
X724817Y402784D01*
X724525Y402867D01*
X724192D01*
X723817Y402742D01*
X723525Y402534D01*
X723317Y402284D01*
X723150Y401867D01*
X723108Y401492D01*
X723192Y401117D01*
X723317Y400867D01*
X723567Y400617D01*
X723858Y400450D01*
X724150Y400367D01*
X724442D01*
X724733Y400450D01*
X724983Y400575D01*
X725192Y400742D01*
G01X726458Y402450D02*
X726708Y402700D01*
X727000Y402825D01*
X727333Y402867D01*
X727750Y402784D01*
X728042Y402575D01*
X728125Y402325D01*
X728083Y402075D01*
X727917Y401867D01*
X727083Y401450D01*
X726708Y401159D01*
X726458Y400742D01*
X726375Y400367D01*
X728125D01*
G01X730267D02*
X730350Y400909D01*
X730475Y401367D01*
X730642Y401784D01*
X730850Y402242D01*
X731183Y402867D01*
X729517D01*
G01X733450Y400367D02*
Y402867D01*
X732950Y402367D01*
G01Y400367D02*
X733950D01*
G01X725067Y406659D02*
X724817Y406784D01*
X724525Y406867D01*
X724192D01*
X723817Y406742D01*
X723525Y406534D01*
X723317Y406284D01*
X723150Y405867D01*
X723108Y405492D01*
X723192Y405117D01*
X723317Y404867D01*
X723567Y404617D01*
X723858Y404450D01*
X724150Y404367D01*
X724442D01*
X724733Y404450D01*
X724983Y404575D01*
X725192Y404742D01*
G01X726458Y406450D02*
X726708Y406700D01*
X727000Y406825D01*
X727333Y406867D01*
X727750Y406784D01*
X728042Y406575D01*
X728125Y406325D01*
X728083Y406075D01*
X727917Y405867D01*
X727083Y405450D01*
X726708Y405159D01*
X726458Y404742D01*
X726375Y404367D01*
X728125D01*
G01X730267D02*
X730350Y404909D01*
X730475Y405367D01*
X730642Y405784D01*
X730850Y406242D01*
X731183Y406867D01*
X729517D01*
G01X732658Y406450D02*
X732908Y406700D01*
X733200Y406825D01*
X733533Y406867D01*
X733950Y406784D01*
X734242Y406575D01*
X734325Y406325D01*
X734283Y406075D01*
X734117Y405867D01*
X733283Y405450D01*
X732908Y405159D01*
X732658Y404742D01*
X732575Y404367D01*
X734325D01*
G01X725067Y410659D02*
X724817Y410784D01*
X724525Y410867D01*
X724192D01*
X723817Y410742D01*
X723525Y410534D01*
X723317Y410284D01*
X723150Y409867D01*
X723108Y409492D01*
X723192Y409117D01*
X723317Y408867D01*
X723567Y408617D01*
X723858Y408450D01*
X724150Y408367D01*
X724442D01*
X724733Y408450D01*
X724983Y408575D01*
X725192Y408742D01*
G01X726458Y410450D02*
X726708Y410700D01*
X727000Y410825D01*
X727333Y410867D01*
X727750Y410784D01*
X728042Y410575D01*
X728125Y410325D01*
X728083Y410075D01*
X727917Y409867D01*
X727083Y409450D01*
X726708Y409159D01*
X726458Y408742D01*
X726375Y408367D01*
X728125D01*
G01X730267D02*
X730350Y408909D01*
X730475Y409367D01*
X730642Y409784D01*
X730850Y410242D01*
X731183Y410867D01*
X729517D01*
G01X733950Y408367D02*
Y410867D01*
X732408Y409075D01*
X734492D01*
G01X697161Y440623D02*
X694661D01*
Y441664D01*
X694786Y441998D01*
X694953Y442206D01*
X695286Y442289D01*
X695619Y442206D01*
X695828Y441956D01*
X695953Y441664D01*
Y440623D01*
G01Y441664D02*
X697161Y442289D01*
G01X696786Y443639D02*
X696994Y443889D01*
X697119Y444181D01*
X697161Y444556D01*
X697078Y444931D01*
X696911Y445223D01*
X696619Y445431D01*
X696286Y445473D01*
X695953Y445389D01*
X695744Y445181D01*
X695578Y444889D01*
X695536Y444598D01*
X695578Y444306D01*
X695744Y443931D01*
X694661Y444056D01*
Y445181D01*
G01X696119Y446864D02*
X695828Y447156D01*
X695661Y447406D01*
X695578Y447739D01*
X695661Y448031D01*
X695828Y448239D01*
X696078Y448406D01*
X696369Y448448D01*
X696619Y448406D01*
X696869Y448239D01*
X697078Y447989D01*
X697161Y447698D01*
X697078Y447364D01*
X696828Y447073D01*
X696453Y446906D01*
X696036Y446864D01*
X695494Y446948D01*
X695203Y447073D01*
X694911Y447281D01*
X694703Y447573D01*
X694661Y447864D01*
X694744Y448156D01*
X694953Y448364D01*
G01X697161Y450756D02*
X697119Y451048D01*
X696994Y451381D01*
X696786Y451589D01*
X696494Y451673D01*
X696203Y451589D01*
X695953Y451339D01*
X695828Y450964D01*
Y450548D01*
X695744Y450298D01*
X695536Y450089D01*
X695244Y450006D01*
X694953Y450131D01*
X694744Y450423D01*
X694661Y450756D01*
X694744Y451089D01*
X694953Y451381D01*
X695244Y451506D01*
X695536Y451423D01*
X695744Y451214D01*
X695828Y450964D01*
Y450548D01*
X695953Y450173D01*
X696203Y449923D01*
X696494Y449839D01*
X696786Y449923D01*
X696994Y450131D01*
X697119Y450464D01*
X697161Y450756D01*
G01X694527Y455306D02*
X698527D01*
Y462706D01*
G01X669017Y442167D02*
Y444667D01*
X670058D01*
X670392Y444542D01*
X670600Y444375D01*
X670683Y444042D01*
X670600Y443709D01*
X670350Y443500D01*
X670058Y443375D01*
X669017D01*
G01X670058D02*
X670683Y442167D01*
G01X672033Y442542D02*
X672283Y442334D01*
X672575Y442209D01*
X672950Y442167D01*
X673325Y442250D01*
X673617Y442417D01*
X673825Y442709D01*
X673867Y443042D01*
X673783Y443375D01*
X673575Y443584D01*
X673283Y443750D01*
X672992Y443792D01*
X672700Y443750D01*
X672325Y443584D01*
X672450Y444667D01*
X673575D01*
G01X675258Y444250D02*
X675508Y444500D01*
X675800Y444625D01*
X676133Y444667D01*
X676550Y444584D01*
X676842Y444375D01*
X676925Y444125D01*
X676883Y443875D01*
X676717Y443667D01*
X675883Y443250D01*
X675508Y442959D01*
X675258Y442542D01*
X675175Y442167D01*
X676925D01*
G01X679150D02*
X679442Y442209D01*
X679775Y442334D01*
X679983Y442542D01*
X680067Y442834D01*
X679983Y443125D01*
X679733Y443375D01*
X679358Y443500D01*
X678942D01*
X678692Y443584D01*
X678483Y443792D01*
X678400Y444084D01*
X678525Y444375D01*
X678817Y444584D01*
X679150Y444667D01*
X679483Y444584D01*
X679775Y444375D01*
X679900Y444084D01*
X679817Y443792D01*
X679608Y443584D01*
X679358Y443500D01*
X678942D01*
X678567Y443375D01*
X678317Y443125D01*
X678233Y442834D01*
X678317Y442542D01*
X678525Y442334D01*
X678858Y442209D01*
X679150Y442167D01*
G01X693534Y452317D02*
X691034D01*
Y453358D01*
X691159Y453692D01*
X691326Y453900D01*
X691659Y453983D01*
X691992Y453900D01*
X692201Y453650D01*
X692326Y453358D01*
Y452317D01*
G01Y453358D02*
X693534Y453983D01*
G01X693159Y455333D02*
X693367Y455583D01*
X693492Y455875D01*
X693534Y456250D01*
X693451Y456625D01*
X693284Y456917D01*
X692992Y457125D01*
X692659Y457167D01*
X692326Y457083D01*
X692117Y456875D01*
X691951Y456583D01*
X691909Y456292D01*
X691951Y456000D01*
X692117Y455625D01*
X691034Y455750D01*
Y456875D01*
G01X691451Y458558D02*
X691201Y458808D01*
X691076Y459100D01*
X691034Y459433D01*
X691117Y459850D01*
X691326Y460142D01*
X691576Y460225D01*
X691826Y460183D01*
X692034Y460017D01*
X692451Y459183D01*
X692742Y458808D01*
X693159Y458558D01*
X693534Y458475D01*
Y460225D01*
G01X693034Y461533D02*
X693326Y461783D01*
X693492Y462117D01*
X693534Y462492D01*
X693492Y462825D01*
X693284Y463158D01*
X693034Y463367D01*
X692784Y463408D01*
X692492Y463325D01*
X692284Y463033D01*
X692201Y462742D01*
Y462367D01*
G01Y462742D02*
X692076Y462992D01*
X691867Y463200D01*
X691617Y463283D01*
X691367Y463200D01*
X691159Y462992D01*
X691034Y462617D01*
X691076Y462242D01*
X691242Y461867D01*
G01X701934Y451683D02*
X703726D01*
X704101Y451850D01*
X704351Y452183D01*
X704434Y452600D01*
X704351Y453017D01*
X704101Y453350D01*
X703726Y453517D01*
X701934D01*
G01X704142Y454992D02*
X704351Y455283D01*
X704434Y455617D01*
X704351Y455950D01*
X704101Y456242D01*
X703726Y456450D01*
X703351Y456533D01*
X702892D01*
X702517Y456450D01*
X702184Y456242D01*
X702017Y455992D01*
X701934Y455700D01*
X702017Y455367D01*
X702184Y455117D01*
X702434Y454950D01*
X702767Y454867D01*
X703059Y454950D01*
X703351Y455158D01*
X703517Y455408D01*
X703559Y455700D01*
X703476Y456033D01*
X703267Y456283D01*
X702892Y456533D01*
G01X704059Y457883D02*
X704267Y458133D01*
X704392Y458425D01*
X704434Y458800D01*
X704351Y459175D01*
X704184Y459467D01*
X703892Y459675D01*
X703559Y459717D01*
X703226Y459633D01*
X703017Y459425D01*
X702851Y459133D01*
X702809Y458842D01*
X702851Y458550D01*
X703017Y458175D01*
X701934Y458300D01*
Y459425D01*
G01X700384Y460980D02*
Y474380D01*
G01X710384Y460980D02*
X700384D01*
G01X710384Y474380D02*
Y460980D01*
G01X704642Y439067D02*
X704517Y438817D01*
X704434Y438525D01*
Y438192D01*
X704559Y437817D01*
X704767Y437525D01*
X705017Y437317D01*
X705434Y437150D01*
X705809Y437108D01*
X706184Y437192D01*
X706434Y437317D01*
X706684Y437567D01*
X706851Y437858D01*
X706934Y438150D01*
Y438442D01*
X706851Y438733D01*
X706726Y438983D01*
X706559Y439192D01*
G01X704851Y440458D02*
X704601Y440708D01*
X704476Y441000D01*
X704434Y441333D01*
X704517Y441750D01*
X704726Y442042D01*
X704976Y442125D01*
X705226Y442083D01*
X705434Y441917D01*
X705851Y441083D01*
X706142Y440708D01*
X706559Y440458D01*
X706934Y440375D01*
Y442125D01*
G01Y444350D02*
X706892Y444642D01*
X706767Y444975D01*
X706559Y445183D01*
X706267Y445267D01*
X705976Y445183D01*
X705726Y444933D01*
X705601Y444558D01*
Y444142D01*
X705517Y443892D01*
X705309Y443683D01*
X705017Y443600D01*
X704726Y443725D01*
X704517Y444017D01*
X704434Y444350D01*
X704517Y444683D01*
X704726Y444975D01*
X705017Y445100D01*
X705309Y445017D01*
X705517Y444808D01*
X705601Y444558D01*
Y444142D01*
X705726Y443767D01*
X705976Y443517D01*
X706267Y443433D01*
X706559Y443517D01*
X706767Y443725D01*
X706892Y444058D01*
X706934Y444350D01*
G01Y447450D02*
X706892Y447742D01*
X706767Y448075D01*
X706559Y448283D01*
X706267Y448367D01*
X705976Y448283D01*
X705726Y448033D01*
X705601Y447658D01*
Y447242D01*
X705517Y446992D01*
X705309Y446783D01*
X705017Y446700D01*
X704726Y446825D01*
X704517Y447117D01*
X704434Y447450D01*
X704517Y447783D01*
X704726Y448075D01*
X705017Y448200D01*
X705309Y448117D01*
X705517Y447908D01*
X705601Y447658D01*
Y447242D01*
X705726Y446867D01*
X705976Y446617D01*
X706267Y446533D01*
X706559Y446617D01*
X706767Y446825D01*
X706892Y447158D01*
X706934Y447450D01*
G01X681482Y449746D02*
X681357Y449496D01*
X681274Y449204D01*
Y448871D01*
X681399Y448496D01*
X681607Y448204D01*
X681857Y447996D01*
X682274Y447829D01*
X682649Y447787D01*
X683024Y447871D01*
X683274Y447996D01*
X683524Y448246D01*
X683691Y448537D01*
X683774Y448829D01*
Y449121D01*
X683691Y449412D01*
X683566Y449662D01*
X683399Y449871D01*
G01X681691Y451137D02*
X681441Y451387D01*
X681316Y451679D01*
X681274Y452012D01*
X681357Y452429D01*
X681566Y452721D01*
X681816Y452804D01*
X682066Y452762D01*
X682274Y452596D01*
X682691Y451762D01*
X682982Y451387D01*
X683399Y451137D01*
X683774Y451054D01*
Y452804D01*
G01Y455029D02*
X681274D01*
X681774Y454529D01*
G01X683774D02*
Y455529D01*
G01X683482Y457421D02*
X683691Y457712D01*
X683774Y458046D01*
X683691Y458379D01*
X683441Y458671D01*
X683066Y458879D01*
X682691Y458962D01*
X682232D01*
X681857Y458879D01*
X681524Y458671D01*
X681357Y458421D01*
X681274Y458129D01*
X681357Y457796D01*
X681524Y457546D01*
X681774Y457379D01*
X682107Y457296D01*
X682399Y457379D01*
X682691Y457587D01*
X682857Y457837D01*
X682899Y458129D01*
X682816Y458462D01*
X682607Y458712D01*
X682232Y458962D01*
G01X680667Y431192D02*
X680417Y431317D01*
X680125Y431400D01*
X679792D01*
X679417Y431275D01*
X679125Y431067D01*
X678917Y430817D01*
X678750Y430400D01*
X678708Y430025D01*
X678792Y429650D01*
X678917Y429400D01*
X679167Y429150D01*
X679458Y428983D01*
X679750Y428900D01*
X680042D01*
X680333Y428983D01*
X680583Y429108D01*
X680792Y429275D01*
G01X683350Y428900D02*
Y431400D01*
X681808Y429608D01*
X683892D01*
G01X685158Y429942D02*
X685450Y430233D01*
X685700Y430400D01*
X686033Y430483D01*
X686325Y430400D01*
X686533Y430233D01*
X686700Y429983D01*
X686742Y429692D01*
X686700Y429442D01*
X686533Y429192D01*
X686283Y428983D01*
X685992Y428900D01*
X685658Y428983D01*
X685367Y429233D01*
X685200Y429608D01*
X685158Y430025D01*
X685242Y430567D01*
X685367Y430858D01*
X685575Y431150D01*
X685867Y431358D01*
X686158Y431400D01*
X686450Y431317D01*
X686658Y431108D01*
G01X688258Y429942D02*
X688550Y430233D01*
X688800Y430400D01*
X689133Y430483D01*
X689425Y430400D01*
X689633Y430233D01*
X689800Y429983D01*
X689842Y429692D01*
X689800Y429442D01*
X689633Y429192D01*
X689383Y428983D01*
X689092Y428900D01*
X688758Y428983D01*
X688467Y429233D01*
X688300Y429608D01*
X688258Y430025D01*
X688342Y430567D01*
X688467Y430858D01*
X688675Y431150D01*
X688967Y431358D01*
X689258Y431400D01*
X689550Y431317D01*
X689758Y431108D01*
G01X680667Y410692D02*
X680417Y410817D01*
X680125Y410900D01*
X679792D01*
X679417Y410775D01*
X679125Y410567D01*
X678917Y410317D01*
X678750Y409900D01*
X678708Y409525D01*
X678792Y409150D01*
X678917Y408900D01*
X679167Y408650D01*
X679458Y408483D01*
X679750Y408400D01*
X680042D01*
X680333Y408483D01*
X680583Y408608D01*
X680792Y408775D01*
G01X683350Y408400D02*
Y410900D01*
X681808Y409108D01*
X683892D01*
G01X685158Y409442D02*
X685450Y409733D01*
X685700Y409900D01*
X686033Y409983D01*
X686325Y409900D01*
X686533Y409733D01*
X686700Y409483D01*
X686742Y409192D01*
X686700Y408942D01*
X686533Y408692D01*
X686283Y408483D01*
X685992Y408400D01*
X685658Y408483D01*
X685367Y408733D01*
X685200Y409108D01*
X685158Y409525D01*
X685242Y410067D01*
X685367Y410358D01*
X685575Y410650D01*
X685867Y410858D01*
X686158Y410900D01*
X686450Y410817D01*
X686658Y410608D01*
G01X689050Y408400D02*
Y410900D01*
X688550Y410400D01*
G01Y408400D02*
X689550D01*
G01X680667Y414792D02*
X680417Y414917D01*
X680125Y415000D01*
X679792D01*
X679417Y414875D01*
X679125Y414667D01*
X678917Y414417D01*
X678750Y414000D01*
X678708Y413625D01*
X678792Y413250D01*
X678917Y413000D01*
X679167Y412750D01*
X679458Y412583D01*
X679750Y412500D01*
X680042D01*
X680333Y412583D01*
X680583Y412708D01*
X680792Y412875D01*
G01X683350Y412500D02*
Y415000D01*
X681808Y413208D01*
X683892D01*
G01X685158Y413542D02*
X685450Y413833D01*
X685700Y414000D01*
X686033Y414083D01*
X686325Y414000D01*
X686533Y413833D01*
X686700Y413583D01*
X686742Y413292D01*
X686700Y413042D01*
X686533Y412792D01*
X686283Y412583D01*
X685992Y412500D01*
X685658Y412583D01*
X685367Y412833D01*
X685200Y413208D01*
X685158Y413625D01*
X685242Y414167D01*
X685367Y414458D01*
X685575Y414750D01*
X685867Y414958D01*
X686158Y415000D01*
X686450Y414917D01*
X686658Y414708D01*
G01X688258Y414583D02*
X688508Y414833D01*
X688800Y414958D01*
X689133Y415000D01*
X689550Y414917D01*
X689842Y414708D01*
X689925Y414458D01*
X689883Y414208D01*
X689717Y414000D01*
X688883Y413583D01*
X688508Y413292D01*
X688258Y412875D01*
X688175Y412500D01*
X689925D01*
G01X680667Y418892D02*
X680417Y419017D01*
X680125Y419100D01*
X679792D01*
X679417Y418975D01*
X679125Y418767D01*
X678917Y418517D01*
X678750Y418100D01*
X678708Y417725D01*
X678792Y417350D01*
X678917Y417100D01*
X679167Y416850D01*
X679458Y416683D01*
X679750Y416600D01*
X680042D01*
X680333Y416683D01*
X680583Y416808D01*
X680792Y416975D01*
G01X683350Y416600D02*
Y419100D01*
X681808Y417308D01*
X683892D01*
G01X685158Y417642D02*
X685450Y417933D01*
X685700Y418100D01*
X686033Y418183D01*
X686325Y418100D01*
X686533Y417933D01*
X686700Y417683D01*
X686742Y417392D01*
X686700Y417142D01*
X686533Y416892D01*
X686283Y416683D01*
X685992Y416600D01*
X685658Y416683D01*
X685367Y416933D01*
X685200Y417308D01*
X685158Y417725D01*
X685242Y418267D01*
X685367Y418558D01*
X685575Y418850D01*
X685867Y419058D01*
X686158Y419100D01*
X686450Y419017D01*
X686658Y418808D01*
G01X688133Y417100D02*
X688383Y416808D01*
X688717Y416642D01*
X689092Y416600D01*
X689425Y416642D01*
X689758Y416850D01*
X689967Y417100D01*
X690008Y417350D01*
X689925Y417642D01*
X689633Y417850D01*
X689342Y417933D01*
X688967D01*
G01X689342D02*
X689592Y418058D01*
X689800Y418267D01*
X689883Y418517D01*
X689800Y418767D01*
X689592Y418975D01*
X689217Y419100D01*
X688842Y419058D01*
X688467Y418892D01*
G01X680667Y422992D02*
X680417Y423117D01*
X680125Y423200D01*
X679792D01*
X679417Y423075D01*
X679125Y422867D01*
X678917Y422617D01*
X678750Y422200D01*
X678708Y421825D01*
X678792Y421450D01*
X678917Y421200D01*
X679167Y420950D01*
X679458Y420783D01*
X679750Y420700D01*
X680042D01*
X680333Y420783D01*
X680583Y420908D01*
X680792Y421075D01*
G01X683350Y420700D02*
Y423200D01*
X681808Y421408D01*
X683892D01*
G01X685158Y421742D02*
X685450Y422033D01*
X685700Y422200D01*
X686033Y422283D01*
X686325Y422200D01*
X686533Y422033D01*
X686700Y421783D01*
X686742Y421492D01*
X686700Y421242D01*
X686533Y420992D01*
X686283Y420783D01*
X685992Y420700D01*
X685658Y420783D01*
X685367Y421033D01*
X685200Y421408D01*
X685158Y421825D01*
X685242Y422367D01*
X685367Y422658D01*
X685575Y422950D01*
X685867Y423158D01*
X686158Y423200D01*
X686450Y423117D01*
X686658Y422908D01*
G01X689550Y420700D02*
Y423200D01*
X688008Y421408D01*
X690092D01*
G01X680667Y427092D02*
X680417Y427217D01*
X680125Y427300D01*
X679792D01*
X679417Y427175D01*
X679125Y426967D01*
X678917Y426717D01*
X678750Y426300D01*
X678708Y425925D01*
X678792Y425550D01*
X678917Y425300D01*
X679167Y425050D01*
X679458Y424883D01*
X679750Y424800D01*
X680042D01*
X680333Y424883D01*
X680583Y425008D01*
X680792Y425175D01*
G01X683350Y424800D02*
Y427300D01*
X681808Y425508D01*
X683892D01*
G01X685158Y425842D02*
X685450Y426133D01*
X685700Y426300D01*
X686033Y426383D01*
X686325Y426300D01*
X686533Y426133D01*
X686700Y425883D01*
X686742Y425592D01*
X686700Y425342D01*
X686533Y425092D01*
X686283Y424883D01*
X685992Y424800D01*
X685658Y424883D01*
X685367Y425133D01*
X685200Y425508D01*
X685158Y425925D01*
X685242Y426467D01*
X685367Y426758D01*
X685575Y427050D01*
X685867Y427258D01*
X686158Y427300D01*
X686450Y427217D01*
X686658Y427008D01*
G01X688133Y425175D02*
X688383Y424967D01*
X688675Y424842D01*
X689050Y424800D01*
X689425Y424883D01*
X689717Y425050D01*
X689925Y425342D01*
X689967Y425675D01*
X689883Y426008D01*
X689675Y426217D01*
X689383Y426383D01*
X689092Y426425D01*
X688800Y426383D01*
X688425Y426217D01*
X688550Y427300D01*
X689675D01*
G01X710967Y414167D02*
Y411667D01*
X712633D01*
G01X714900D02*
Y414167D01*
X714400Y413667D01*
G01Y411667D02*
X715400D01*
G01X718000D02*
Y414167D01*
X717500Y413667D01*
G01Y411667D02*
X718500D01*
G01X700989Y417809D02*
X723589D01*
G01X700989Y428009D02*
Y417809D01*
G01X723589Y428009D02*
X700989D01*
G01X723589Y417809D02*
Y428009D01*
G01X700989Y417809D02*
X723589D01*
G01X700989Y428009D02*
Y417809D01*
G01X723589Y428009D02*
X700989D01*
G01X723589Y417809D02*
Y428009D01*
G01X726208Y517367D02*
X726083Y517117D01*
X726000Y516825D01*
Y516492D01*
X726125Y516117D01*
X726333Y515825D01*
X726583Y515617D01*
X727000Y515450D01*
X727375Y515408D01*
X727750Y515492D01*
X728000Y515617D01*
X728250Y515867D01*
X728417Y516158D01*
X728500Y516450D01*
Y516742D01*
X728417Y517033D01*
X728292Y517283D01*
X728125Y517492D01*
G01X726417Y518758D02*
X726167Y519008D01*
X726042Y519300D01*
X726000Y519633D01*
X726083Y520050D01*
X726292Y520342D01*
X726542Y520425D01*
X726792Y520383D01*
X727000Y520217D01*
X727417Y519383D01*
X727708Y519008D01*
X728125Y518758D01*
X728500Y518675D01*
Y520425D01*
G01Y522650D02*
X728458Y522942D01*
X728333Y523275D01*
X728125Y523483D01*
X727833Y523567D01*
X727542Y523483D01*
X727292Y523233D01*
X727167Y522858D01*
Y522442D01*
X727083Y522192D01*
X726875Y521983D01*
X726583Y521900D01*
X726292Y522025D01*
X726083Y522317D01*
X726000Y522650D01*
X726083Y522983D01*
X726292Y523275D01*
X726583Y523400D01*
X726875Y523317D01*
X727083Y523108D01*
X727167Y522858D01*
Y522442D01*
X727292Y522067D01*
X727542Y521817D01*
X727833Y521733D01*
X728125Y521817D01*
X728333Y522025D01*
X728458Y522358D01*
X728500Y522650D01*
G01Y525750D02*
X726000D01*
X726500Y525250D01*
G01X728500D02*
Y526250D01*
G01X718408Y517567D02*
X718283Y517317D01*
X718200Y517025D01*
Y516692D01*
X718325Y516317D01*
X718533Y516025D01*
X718783Y515817D01*
X719200Y515650D01*
X719575Y515608D01*
X719950Y515692D01*
X720200Y515817D01*
X720450Y516067D01*
X720617Y516358D01*
X720700Y516650D01*
Y516942D01*
X720617Y517233D01*
X720492Y517483D01*
X720325Y517692D01*
G01X718617Y518958D02*
X718367Y519208D01*
X718242Y519500D01*
X718200Y519833D01*
X718283Y520250D01*
X718492Y520542D01*
X718742Y520625D01*
X718992Y520583D01*
X719200Y520417D01*
X719617Y519583D01*
X719908Y519208D01*
X720325Y518958D01*
X720700Y518875D01*
Y520625D01*
G01Y522850D02*
X720658Y523142D01*
X720533Y523475D01*
X720325Y523683D01*
X720033Y523767D01*
X719742Y523683D01*
X719492Y523433D01*
X719367Y523058D01*
Y522642D01*
X719283Y522392D01*
X719075Y522183D01*
X718783Y522100D01*
X718492Y522225D01*
X718283Y522517D01*
X718200Y522850D01*
X718283Y523183D01*
X718492Y523475D01*
X718783Y523600D01*
X719075Y523517D01*
X719283Y523308D01*
X719367Y523058D01*
Y522642D01*
X719492Y522267D01*
X719742Y522017D01*
X720033Y521933D01*
X720325Y522017D01*
X720533Y522225D01*
X720658Y522558D01*
X720700Y522850D01*
G01Y525867D02*
X720158Y525950D01*
X719700Y526075D01*
X719283Y526242D01*
X718825Y526450D01*
X718200Y526783D01*
Y525117D01*
G01X701842Y498167D02*
X701717Y497917D01*
X701634Y497625D01*
Y497292D01*
X701759Y496917D01*
X701967Y496625D01*
X702217Y496417D01*
X702634Y496250D01*
X703009Y496208D01*
X703384Y496292D01*
X703634Y496417D01*
X703884Y496667D01*
X704051Y496958D01*
X704134Y497250D01*
Y497542D01*
X704051Y497833D01*
X703926Y498083D01*
X703759Y498292D01*
G01Y499433D02*
X703967Y499683D01*
X704092Y499975D01*
X704134Y500350D01*
X704051Y500725D01*
X703884Y501017D01*
X703592Y501225D01*
X703259Y501267D01*
X702926Y501183D01*
X702717Y500975D01*
X702551Y500683D01*
X702509Y500392D01*
X702551Y500100D01*
X702717Y499725D01*
X701634Y499850D01*
Y500975D01*
G01X704134Y503450D02*
X701634D01*
X702134Y502950D01*
G01X704134D02*
Y503950D01*
G01X701634Y506550D02*
X701717Y506217D01*
X701926Y505967D01*
X702176Y505800D01*
X702509Y505675D01*
X702884Y505633D01*
X703259Y505675D01*
X703592Y505800D01*
X703842Y505967D01*
X704051Y506217D01*
X704134Y506550D01*
X704051Y506883D01*
X703842Y507133D01*
X703592Y507300D01*
X703259Y507425D01*
X702884Y507467D01*
X702509Y507425D01*
X702176Y507300D01*
X701926Y507133D01*
X701717Y506883D01*
X701634Y506550D01*
G01X676867Y515959D02*
X676617Y516084D01*
X676325Y516167D01*
X675992D01*
X675617Y516042D01*
X675325Y515834D01*
X675117Y515584D01*
X674950Y515167D01*
X674908Y514792D01*
X674992Y514417D01*
X675117Y514167D01*
X675367Y513917D01*
X675658Y513750D01*
X675950Y513667D01*
X676242D01*
X676533Y513750D01*
X676783Y513875D01*
X676992Y514042D01*
G01X679050Y513667D02*
Y516167D01*
X678550Y515667D01*
G01Y513667D02*
X679550D01*
G01X681233Y514042D02*
X681483Y513834D01*
X681775Y513709D01*
X682150Y513667D01*
X682525Y513750D01*
X682817Y513917D01*
X683025Y514209D01*
X683067Y514542D01*
X682983Y514875D01*
X682775Y515084D01*
X682483Y515250D01*
X682192Y515292D01*
X681900Y515250D01*
X681525Y515084D01*
X681650Y516167D01*
X682775D01*
G01X685250Y513667D02*
Y516167D01*
X684750Y515667D01*
G01Y513667D02*
X685750D01*
G01X676767Y527559D02*
X676517Y527684D01*
X676225Y527767D01*
X675892D01*
X675517Y527642D01*
X675225Y527434D01*
X675017Y527184D01*
X674850Y526767D01*
X674808Y526392D01*
X674892Y526017D01*
X675017Y525767D01*
X675267Y525517D01*
X675558Y525350D01*
X675850Y525267D01*
X676142D01*
X676433Y525350D01*
X676683Y525475D01*
X676892Y525642D01*
G01X678950Y525267D02*
Y527767D01*
X678450Y527267D01*
G01Y525267D02*
X679450D01*
G01X681133Y525642D02*
X681383Y525434D01*
X681675Y525309D01*
X682050Y525267D01*
X682425Y525350D01*
X682717Y525517D01*
X682925Y525809D01*
X682967Y526142D01*
X682883Y526475D01*
X682675Y526684D01*
X682383Y526850D01*
X682092Y526892D01*
X681800Y526850D01*
X681425Y526684D01*
X681550Y527767D01*
X682675D01*
G01X684233Y525642D02*
X684483Y525434D01*
X684775Y525309D01*
X685150Y525267D01*
X685525Y525350D01*
X685817Y525517D01*
X686025Y525809D01*
X686067Y526142D01*
X685983Y526475D01*
X685775Y526684D01*
X685483Y526850D01*
X685192Y526892D01*
X684900Y526850D01*
X684525Y526684D01*
X684650Y527767D01*
X685775D01*
G01X676767Y519759D02*
X676517Y519884D01*
X676225Y519967D01*
X675892D01*
X675517Y519842D01*
X675225Y519634D01*
X675017Y519384D01*
X674850Y518967D01*
X674808Y518592D01*
X674892Y518217D01*
X675017Y517967D01*
X675267Y517717D01*
X675558Y517550D01*
X675850Y517467D01*
X676142D01*
X676433Y517550D01*
X676683Y517675D01*
X676892Y517842D01*
G01X678950Y517467D02*
Y519967D01*
X678450Y519467D01*
G01Y517467D02*
X679450D01*
G01X681133Y517842D02*
X681383Y517634D01*
X681675Y517509D01*
X682050Y517467D01*
X682425Y517550D01*
X682717Y517717D01*
X682925Y518009D01*
X682967Y518342D01*
X682883Y518675D01*
X682675Y518884D01*
X682383Y519050D01*
X682092Y519092D01*
X681800Y519050D01*
X681425Y518884D01*
X681550Y519967D01*
X682675D01*
G01X684358Y519550D02*
X684608Y519800D01*
X684900Y519925D01*
X685233Y519967D01*
X685650Y519884D01*
X685942Y519675D01*
X686025Y519425D01*
X685983Y519175D01*
X685817Y518967D01*
X684983Y518550D01*
X684608Y518259D01*
X684358Y517842D01*
X684275Y517467D01*
X686025D01*
G01X676767Y523559D02*
X676517Y523684D01*
X676225Y523767D01*
X675892D01*
X675517Y523642D01*
X675225Y523434D01*
X675017Y523184D01*
X674850Y522767D01*
X674808Y522392D01*
X674892Y522017D01*
X675017Y521767D01*
X675267Y521517D01*
X675558Y521350D01*
X675850Y521267D01*
X676142D01*
X676433Y521350D01*
X676683Y521475D01*
X676892Y521642D01*
G01X678950Y521267D02*
Y523767D01*
X678450Y523267D01*
G01Y521267D02*
X679450D01*
G01X681133Y521642D02*
X681383Y521434D01*
X681675Y521309D01*
X682050Y521267D01*
X682425Y521350D01*
X682717Y521517D01*
X682925Y521809D01*
X682967Y522142D01*
X682883Y522475D01*
X682675Y522684D01*
X682383Y522850D01*
X682092Y522892D01*
X681800Y522850D01*
X681425Y522684D01*
X681550Y523767D01*
X682675D01*
G01X684233Y521767D02*
X684483Y521475D01*
X684817Y521309D01*
X685192Y521267D01*
X685525Y521309D01*
X685858Y521517D01*
X686067Y521767D01*
X686108Y522017D01*
X686025Y522309D01*
X685733Y522517D01*
X685442Y522600D01*
X685067D01*
G01X685442D02*
X685692Y522725D01*
X685900Y522934D01*
X685983Y523184D01*
X685900Y523434D01*
X685692Y523642D01*
X685317Y523767D01*
X684942Y523725D01*
X684567Y523559D01*
G01X732400Y515617D02*
X729900D01*
Y516658D01*
X730025Y516992D01*
X730192Y517200D01*
X730525Y517283D01*
X730858Y517200D01*
X731067Y516950D01*
X731192Y516658D01*
Y515617D01*
G01Y516658D02*
X732400Y517283D01*
G01X732025Y518633D02*
X732233Y518883D01*
X732358Y519175D01*
X732400Y519550D01*
X732317Y519925D01*
X732150Y520217D01*
X731858Y520425D01*
X731525Y520467D01*
X731192Y520383D01*
X730983Y520175D01*
X730817Y519883D01*
X730775Y519592D01*
X730817Y519300D01*
X730983Y518925D01*
X729900Y519050D01*
Y520175D01*
G01X732025Y521733D02*
X732233Y521983D01*
X732358Y522275D01*
X732400Y522650D01*
X732317Y523025D01*
X732150Y523317D01*
X731858Y523525D01*
X731525Y523567D01*
X731192Y523483D01*
X730983Y523275D01*
X730817Y522983D01*
X730775Y522692D01*
X730817Y522400D01*
X730983Y522025D01*
X729900Y522150D01*
Y523275D01*
G01X732400Y526250D02*
X729900D01*
X731692Y524708D01*
Y526792D01*
G01X724600Y515617D02*
X722100D01*
Y516658D01*
X722225Y516992D01*
X722392Y517200D01*
X722725Y517283D01*
X723058Y517200D01*
X723267Y516950D01*
X723392Y516658D01*
Y515617D01*
G01Y516658D02*
X724600Y517283D01*
G01X724225Y518633D02*
X724433Y518883D01*
X724558Y519175D01*
X724600Y519550D01*
X724517Y519925D01*
X724350Y520217D01*
X724058Y520425D01*
X723725Y520467D01*
X723392Y520383D01*
X723183Y520175D01*
X723017Y519883D01*
X722975Y519592D01*
X723017Y519300D01*
X723183Y518925D01*
X722100Y519050D01*
Y520175D01*
G01X723558Y521858D02*
X723267Y522150D01*
X723100Y522400D01*
X723017Y522733D01*
X723100Y523025D01*
X723267Y523233D01*
X723517Y523400D01*
X723808Y523442D01*
X724058Y523400D01*
X724308Y523233D01*
X724517Y522983D01*
X724600Y522692D01*
X724517Y522358D01*
X724267Y522067D01*
X723892Y521900D01*
X723475Y521858D01*
X722933Y521942D01*
X722642Y522067D01*
X722350Y522275D01*
X722142Y522567D01*
X722100Y522858D01*
X722183Y523150D01*
X722392Y523358D01*
G01X724100Y524833D02*
X724392Y525083D01*
X724558Y525417D01*
X724600Y525792D01*
X724558Y526125D01*
X724350Y526458D01*
X724100Y526667D01*
X723850Y526708D01*
X723558Y526625D01*
X723350Y526333D01*
X723267Y526042D01*
Y525667D01*
G01Y526042D02*
X723142Y526292D01*
X722933Y526500D01*
X722683Y526583D01*
X722433Y526500D01*
X722225Y526292D01*
X722100Y525917D01*
X722142Y525542D01*
X722308Y525167D01*
G01X705517Y521700D02*
Y524200D01*
X706558D01*
X706892Y524075D01*
X707100Y523908D01*
X707183Y523575D01*
X707100Y523242D01*
X706850Y523033D01*
X706558Y522908D01*
X705517D01*
G01X706558D02*
X707183Y521700D01*
G01X708533Y522075D02*
X708783Y521867D01*
X709075Y521742D01*
X709450Y521700D01*
X709825Y521783D01*
X710117Y521950D01*
X710325Y522242D01*
X710367Y522575D01*
X710283Y522908D01*
X710075Y523117D01*
X709783Y523283D01*
X709492Y523325D01*
X709200Y523283D01*
X708825Y523117D01*
X708950Y524200D01*
X710075D01*
G01X711758Y522742D02*
X712050Y523033D01*
X712300Y523200D01*
X712633Y523283D01*
X712925Y523200D01*
X713133Y523033D01*
X713300Y522783D01*
X713342Y522492D01*
X713300Y522242D01*
X713133Y521992D01*
X712883Y521783D01*
X712592Y521700D01*
X712258Y521783D01*
X711967Y522033D01*
X711800Y522408D01*
X711758Y522825D01*
X711842Y523367D01*
X711967Y523658D01*
X712175Y523950D01*
X712467Y524158D01*
X712758Y524200D01*
X713050Y524117D01*
X713258Y523908D01*
G01X716150Y521700D02*
Y524200D01*
X714608Y522408D01*
X716692D01*
G01X705917Y526567D02*
Y529067D01*
X706958D01*
X707292Y528942D01*
X707500Y528775D01*
X707583Y528442D01*
X707500Y528109D01*
X707250Y527900D01*
X706958Y527775D01*
X705917D01*
G01X706958D02*
X707583Y526567D01*
G01X708933Y526942D02*
X709183Y526734D01*
X709475Y526609D01*
X709850Y526567D01*
X710225Y526650D01*
X710517Y526817D01*
X710725Y527109D01*
X710767Y527442D01*
X710683Y527775D01*
X710475Y527984D01*
X710183Y528150D01*
X709892Y528192D01*
X709600Y528150D01*
X709225Y527984D01*
X709350Y529067D01*
X710475D01*
G01X712158Y527609D02*
X712450Y527900D01*
X712700Y528067D01*
X713033Y528150D01*
X713325Y528067D01*
X713533Y527900D01*
X713700Y527650D01*
X713742Y527359D01*
X713700Y527109D01*
X713533Y526859D01*
X713283Y526650D01*
X712992Y526567D01*
X712658Y526650D01*
X712367Y526900D01*
X712200Y527275D01*
X712158Y527692D01*
X712242Y528234D01*
X712367Y528525D01*
X712575Y528817D01*
X712867Y529025D01*
X713158Y529067D01*
X713450Y528984D01*
X713658Y528775D01*
G01X715258Y527609D02*
X715550Y527900D01*
X715800Y528067D01*
X716133Y528150D01*
X716425Y528067D01*
X716633Y527900D01*
X716800Y527650D01*
X716842Y527359D01*
X716800Y527109D01*
X716633Y526859D01*
X716383Y526650D01*
X716092Y526567D01*
X715758Y526650D01*
X715467Y526900D01*
X715300Y527275D01*
X715258Y527692D01*
X715342Y528234D01*
X715467Y528525D01*
X715675Y528817D01*
X715967Y529025D01*
X716258Y529067D01*
X716550Y528984D01*
X716758Y528775D01*
G01X669150Y472684D02*
Y468684D01*
X676550D01*
G01X685734Y501217D02*
X683234D01*
Y502258D01*
X683359Y502592D01*
X683526Y502800D01*
X683859Y502883D01*
X684192Y502800D01*
X684401Y502550D01*
X684526Y502258D01*
Y501217D01*
G01Y502258D02*
X685734Y502883D01*
G01X685359Y504233D02*
X685567Y504483D01*
X685692Y504775D01*
X685734Y505150D01*
X685651Y505525D01*
X685484Y505817D01*
X685192Y506025D01*
X684859Y506067D01*
X684526Y505983D01*
X684317Y505775D01*
X684151Y505483D01*
X684109Y505192D01*
X684151Y504900D01*
X684317Y504525D01*
X683234Y504650D01*
Y505775D01*
G01X683651Y507458D02*
X683401Y507708D01*
X683276Y508000D01*
X683234Y508333D01*
X683317Y508750D01*
X683526Y509042D01*
X683776Y509125D01*
X684026Y509083D01*
X684234Y508917D01*
X684651Y508083D01*
X684942Y507708D01*
X685359Y507458D01*
X685734Y507375D01*
Y509125D01*
G01X684692Y510558D02*
X684401Y510850D01*
X684234Y511100D01*
X684151Y511433D01*
X684234Y511725D01*
X684401Y511933D01*
X684651Y512100D01*
X684942Y512142D01*
X685192Y512100D01*
X685442Y511933D01*
X685651Y511683D01*
X685734Y511392D01*
X685651Y511058D01*
X685401Y510767D01*
X685026Y510600D01*
X684609Y510558D01*
X684067Y510642D01*
X683776Y510767D01*
X683484Y510975D01*
X683276Y511267D01*
X683234Y511558D01*
X683317Y511850D01*
X683526Y512058D01*
G01X691000Y505200D02*
X687000D01*
Y497800D01*
G01X670500Y505900D02*
Y501900D01*
X677900D01*
G01X694700Y467900D02*
X698700D01*
Y475300D01*
G01X690317Y510167D02*
Y512667D01*
X691358D01*
X691692Y512542D01*
X691900Y512375D01*
X691983Y512042D01*
X691900Y511709D01*
X691650Y511500D01*
X691358Y511375D01*
X690317D01*
G01X691358D02*
X691983Y510167D01*
G01X693333Y510542D02*
X693583Y510334D01*
X693875Y510209D01*
X694250Y510167D01*
X694625Y510250D01*
X694917Y510417D01*
X695125Y510709D01*
X695167Y511042D01*
X695083Y511375D01*
X694875Y511584D01*
X694583Y511750D01*
X694292Y511792D01*
X694000Y511750D01*
X693625Y511584D01*
X693750Y512667D01*
X694875D01*
G01X696558Y512250D02*
X696808Y512500D01*
X697100Y512625D01*
X697433Y512667D01*
X697850Y512584D01*
X698142Y512375D01*
X698225Y512125D01*
X698183Y511875D01*
X698017Y511667D01*
X697183Y511250D01*
X696808Y510959D01*
X696558Y510542D01*
X696475Y510167D01*
X698225D01*
G01X700950D02*
Y512667D01*
X699408Y510875D01*
X701492D01*
G01X694000Y506000D02*
Y502000D01*
X701400D01*
G01X707934Y505317D02*
X705434D01*
Y506358D01*
X705559Y506692D01*
X705726Y506900D01*
X706059Y506983D01*
X706392Y506900D01*
X706601Y506650D01*
X706726Y506358D01*
Y505317D01*
G01Y506358D02*
X707934Y506983D01*
G01Y509167D02*
X707392Y509250D01*
X706934Y509375D01*
X706517Y509542D01*
X706059Y509750D01*
X705434Y510083D01*
Y508417D01*
G01X705851Y511558D02*
X705601Y511808D01*
X705476Y512100D01*
X705434Y512433D01*
X705517Y512850D01*
X705726Y513142D01*
X705976Y513225D01*
X706226Y513183D01*
X706434Y513017D01*
X706851Y512183D01*
X707142Y511808D01*
X707559Y511558D01*
X707934Y511475D01*
Y513225D01*
G01Y515367D02*
X707392Y515450D01*
X706934Y515575D01*
X706517Y515742D01*
X706059Y515950D01*
X705434Y516283D01*
Y514617D01*
G01X700390Y486860D02*
X704390D01*
Y494260D01*
G01X700384Y474380D02*
X710384D01*
G01X670567Y477666D02*
Y480166D01*
X671567D01*
X671900Y480041D01*
X672150Y479749D01*
X672233Y479416D01*
X672150Y479083D01*
X671942Y478833D01*
X671567Y478708D01*
X670567D01*
G01X674500Y477666D02*
X674167Y477708D01*
X673875Y477874D01*
X673625Y478124D01*
X673458Y478416D01*
X673375Y478749D01*
Y479083D01*
X673458Y479416D01*
X673625Y479708D01*
X673875Y479958D01*
X674167Y480124D01*
X674500Y480166D01*
X674833Y480124D01*
X675125Y479958D01*
X675375Y479708D01*
X675542Y479416D01*
X675625Y479083D01*
Y478749D01*
X675542Y478416D01*
X675375Y478124D01*
X675125Y477874D01*
X674833Y477708D01*
X674500Y477666D01*
G01X674833Y478333D02*
X675333Y477666D01*
G01X678100D02*
Y480166D01*
X676558Y478374D01*
X678642D01*
G01X679750Y466884D02*
X693750D01*
G01X679750Y479884D02*
Y466884D01*
G01X693750Y479884D02*
X679750D01*
G01X693750Y466884D02*
Y479884D01*
G01X699350Y496216D02*
X685350D01*
G01X699350Y483216D02*
Y496216D01*
G01X685350Y483216D02*
X699350D01*
G01X685350Y496216D02*
Y483216D01*
G01X683500Y496000D02*
X669500D01*
G01X683500Y483000D02*
Y496000D01*
G01X669500Y483000D02*
X683500D01*
G01X669500Y496000D02*
Y483000D01*
G01X723942Y498467D02*
X723817Y498217D01*
X723734Y497925D01*
Y497592D01*
X723859Y497217D01*
X724067Y496925D01*
X724317Y496717D01*
X724734Y496550D01*
X725109Y496508D01*
X725484Y496592D01*
X725734Y496717D01*
X725984Y496967D01*
X726151Y497258D01*
X726234Y497550D01*
Y497842D01*
X726151Y498133D01*
X726026Y498383D01*
X725859Y498592D01*
G01X724151Y499858D02*
X723901Y500108D01*
X723776Y500400D01*
X723734Y500733D01*
X723817Y501150D01*
X724026Y501442D01*
X724276Y501525D01*
X724526Y501483D01*
X724734Y501317D01*
X725151Y500483D01*
X725442Y500108D01*
X725859Y499858D01*
X726234Y499775D01*
Y501525D01*
G01Y503667D02*
X725692Y503750D01*
X725234Y503875D01*
X724817Y504042D01*
X724359Y504250D01*
X723734Y504583D01*
Y502917D01*
G01X726234Y506767D02*
X725692Y506850D01*
X725234Y506975D01*
X724817Y507142D01*
X724359Y507350D01*
X723734Y507683D01*
Y506017D01*
G01X717540Y499279D02*
X717415Y499029D01*
X717332Y498737D01*
Y498404D01*
X717457Y498029D01*
X717665Y497737D01*
X717915Y497529D01*
X718332Y497362D01*
X718707Y497320D01*
X719082Y497404D01*
X719332Y497529D01*
X719582Y497779D01*
X719749Y498070D01*
X719832Y498362D01*
Y498654D01*
X719749Y498945D01*
X719624Y499195D01*
X719457Y499404D01*
G01X717749Y500670D02*
X717499Y500920D01*
X717374Y501212D01*
X717332Y501545D01*
X717415Y501962D01*
X717624Y502254D01*
X717874Y502337D01*
X718124Y502295D01*
X718332Y502129D01*
X718749Y501295D01*
X719040Y500920D01*
X719457Y500670D01*
X719832Y500587D01*
Y502337D01*
G01Y504479D02*
X719290Y504562D01*
X718832Y504687D01*
X718415Y504854D01*
X717957Y505062D01*
X717332Y505395D01*
Y503729D01*
G01X719832Y507662D02*
X719790Y507954D01*
X719665Y508287D01*
X719457Y508495D01*
X719165Y508579D01*
X718874Y508495D01*
X718624Y508245D01*
X718499Y507870D01*
Y507454D01*
X718415Y507204D01*
X718207Y506995D01*
X717915Y506912D01*
X717624Y507037D01*
X717415Y507329D01*
X717332Y507662D01*
X717415Y507995D01*
X717624Y508287D01*
X717915Y508412D01*
X718207Y508329D01*
X718415Y508120D01*
X718499Y507870D01*
Y507454D01*
X718624Y507079D01*
X718874Y506829D01*
X719165Y506745D01*
X719457Y506829D01*
X719665Y507037D01*
X719790Y507370D01*
X719832Y507662D01*
G01X688400Y540000D02*
Y526600D01*
G01X695600D02*
Y540000D01*
G01X688400Y526600D02*
X695600D01*
G01X732567Y493666D02*
Y496166D01*
X733567D01*
X733900Y496041D01*
X734150Y495749D01*
X734233Y495416D01*
X734150Y495083D01*
X733942Y494833D01*
X733567Y494708D01*
X732567D01*
G01X735583Y496166D02*
Y494374D01*
X735750Y493999D01*
X736083Y493749D01*
X736500Y493666D01*
X736917Y493749D01*
X737250Y493999D01*
X737417Y494374D01*
Y496166D01*
G01X739600Y493666D02*
X739892Y493708D01*
X740225Y493833D01*
X740433Y494041D01*
X740517Y494333D01*
X740433Y494624D01*
X740183Y494874D01*
X739808Y494999D01*
X739392D01*
X739142Y495083D01*
X738933Y495291D01*
X738850Y495583D01*
X738975Y495874D01*
X739267Y496083D01*
X739600Y496166D01*
X739933Y496083D01*
X740225Y495874D01*
X740350Y495583D01*
X740267Y495291D01*
X740058Y495083D01*
X739808Y494999D01*
X739392D01*
X739017Y494874D01*
X738767Y494624D01*
X738683Y494333D01*
X738767Y494041D01*
X738975Y493833D01*
X739308Y493708D01*
X739600Y493666D01*
G01X731722Y474508D02*
Y469508D01*
X736722D01*
G01X732714Y475424D02*
X730714D01*
G01X719960Y473076D02*
X719835Y472826D01*
X719752Y472534D01*
Y472201D01*
X719877Y471826D01*
X720085Y471534D01*
X720335Y471326D01*
X720752Y471159D01*
X721127Y471117D01*
X721502Y471201D01*
X721752Y471326D01*
X722002Y471576D01*
X722169Y471867D01*
X722252Y472159D01*
Y472451D01*
X722169Y472742D01*
X722044Y472992D01*
X721877Y473201D01*
G01X720169Y474467D02*
X719919Y474717D01*
X719794Y475009D01*
X719752Y475342D01*
X719835Y475759D01*
X720044Y476051D01*
X720294Y476134D01*
X720544Y476092D01*
X720752Y475926D01*
X721169Y475092D01*
X721460Y474717D01*
X721877Y474467D01*
X722252Y474384D01*
Y476134D01*
G01Y478276D02*
X721710Y478359D01*
X721252Y478484D01*
X720835Y478651D01*
X720377Y478859D01*
X719752Y479192D01*
Y477526D01*
G01X721210Y480667D02*
X720919Y480959D01*
X720752Y481209D01*
X720669Y481542D01*
X720752Y481834D01*
X720919Y482042D01*
X721169Y482209D01*
X721460Y482251D01*
X721710Y482209D01*
X721960Y482042D01*
X722169Y481792D01*
X722252Y481501D01*
X722169Y481167D01*
X721919Y480876D01*
X721544Y480709D01*
X721127Y480667D01*
X720585Y480751D01*
X720294Y480876D01*
X720002Y481084D01*
X719794Y481376D01*
X719752Y481667D01*
X719835Y481959D01*
X720044Y482167D01*
G01X712000Y505533D02*
X709500D01*
Y506367D01*
X709625Y506700D01*
X709792Y506950D01*
X710042Y507158D01*
X710333Y507325D01*
X710750Y507367D01*
X711167Y507325D01*
X711458Y507158D01*
X711708Y506950D01*
X711875Y506700D01*
X712000Y506367D01*
Y505533D01*
G01X711625Y508633D02*
X711833Y508883D01*
X711958Y509175D01*
X712000Y509550D01*
X711917Y509925D01*
X711750Y510217D01*
X711458Y510425D01*
X711125Y510467D01*
X710792Y510383D01*
X710583Y510175D01*
X710417Y509883D01*
X710375Y509592D01*
X710417Y509300D01*
X710583Y508925D01*
X709500Y509050D01*
Y510175D01*
G01X714880Y501470D02*
X705780D01*
Y479670D01*
X714880D01*
Y501470D01*
G01X676767Y531459D02*
X676517Y531584D01*
X676225Y531667D01*
X675892D01*
X675517Y531542D01*
X675225Y531334D01*
X675017Y531084D01*
X674850Y530667D01*
X674808Y530292D01*
X674892Y529917D01*
X675017Y529667D01*
X675267Y529417D01*
X675558Y529250D01*
X675850Y529167D01*
X676142D01*
X676433Y529250D01*
X676683Y529375D01*
X676892Y529542D01*
G01X678950Y529167D02*
Y531667D01*
X678450Y531167D01*
G01Y529167D02*
X679450D01*
G01X681133Y529542D02*
X681383Y529334D01*
X681675Y529209D01*
X682050Y529167D01*
X682425Y529250D01*
X682717Y529417D01*
X682925Y529709D01*
X682967Y530042D01*
X682883Y530375D01*
X682675Y530584D01*
X682383Y530750D01*
X682092Y530792D01*
X681800Y530750D01*
X681425Y530584D01*
X681550Y531667D01*
X682675D01*
G01X685650Y529167D02*
Y531667D01*
X684108Y529875D01*
X686192D01*
G01X689167Y547197D02*
Y549697D01*
X690208D01*
X690542Y549572D01*
X690750Y549405D01*
X690833Y549072D01*
X690750Y548739D01*
X690500Y548530D01*
X690208Y548405D01*
X689167D01*
G01X690208D02*
X690833Y547197D01*
G01X693600D02*
Y549697D01*
X692058Y547905D01*
X694142D01*
G01X696117Y547197D02*
X696200Y547739D01*
X696325Y548197D01*
X696492Y548614D01*
X696700Y549072D01*
X697033Y549697D01*
X695367D01*
G01X698508Y548239D02*
X698800Y548530D01*
X699050Y548697D01*
X699383Y548780D01*
X699675Y548697D01*
X699883Y548530D01*
X700050Y548280D01*
X700092Y547989D01*
X700050Y547739D01*
X699883Y547489D01*
X699633Y547280D01*
X699342Y547197D01*
X699008Y547280D01*
X698717Y547530D01*
X698550Y547905D01*
X698508Y548322D01*
X698592Y548864D01*
X698717Y549155D01*
X698925Y549447D01*
X699217Y549655D01*
X699508Y549697D01*
X699800Y549614D01*
X700008Y549405D01*
G01X701138Y555602D02*
Y551602D01*
X708538D01*
G01X728017Y568167D02*
Y570667D01*
X729058D01*
X729392Y570542D01*
X729600Y570375D01*
X729683Y570042D01*
X729600Y569709D01*
X729350Y569500D01*
X729058Y569375D01*
X728017D01*
G01X729058D02*
X729683Y568167D01*
G01X732450D02*
Y570667D01*
X730908Y568875D01*
X732992D01*
G01X734967Y568167D02*
X735050Y568709D01*
X735175Y569167D01*
X735342Y569584D01*
X735550Y570042D01*
X735883Y570667D01*
X734217D01*
G01X738067Y568167D02*
X738150Y568709D01*
X738275Y569167D01*
X738442Y569584D01*
X738650Y570042D01*
X738983Y570667D01*
X737317D01*
G01X716600Y571100D02*
Y567100D01*
X724000D01*
G01X728017Y564167D02*
Y566667D01*
X729058D01*
X729392Y566542D01*
X729600Y566375D01*
X729683Y566042D01*
X729600Y565709D01*
X729350Y565500D01*
X729058Y565375D01*
X728017D01*
G01X729058D02*
X729683Y564167D01*
G01X732450D02*
Y566667D01*
X730908Y564875D01*
X732992D01*
G01X734967Y564167D02*
X735050Y564709D01*
X735175Y565167D01*
X735342Y565584D01*
X735550Y566042D01*
X735883Y566667D01*
X734217D01*
G01X737233Y564542D02*
X737483Y564334D01*
X737775Y564209D01*
X738150Y564167D01*
X738525Y564250D01*
X738817Y564417D01*
X739025Y564709D01*
X739067Y565042D01*
X738983Y565375D01*
X738775Y565584D01*
X738483Y565750D01*
X738192Y565792D01*
X737900Y565750D01*
X737525Y565584D01*
X737650Y566667D01*
X738775D01*
G01X725600Y562600D02*
Y566600D01*
X718200D01*
G01X728017Y559667D02*
Y562167D01*
X729058D01*
X729392Y562042D01*
X729600Y561875D01*
X729683Y561542D01*
X729600Y561209D01*
X729350Y561000D01*
X729058Y560875D01*
X728017D01*
G01X729058D02*
X729683Y559667D01*
G01X732450D02*
Y562167D01*
X730908Y560375D01*
X732992D01*
G01X734967Y559667D02*
X735050Y560209D01*
X735175Y560667D01*
X735342Y561084D01*
X735550Y561542D01*
X735883Y562167D01*
X734217D01*
G01X737358Y561750D02*
X737608Y562000D01*
X737900Y562125D01*
X738233Y562167D01*
X738650Y562084D01*
X738942Y561875D01*
X739025Y561625D01*
X738983Y561375D01*
X738817Y561167D01*
X737983Y560750D01*
X737608Y560459D01*
X737358Y560042D01*
X737275Y559667D01*
X739025D01*
G01X725600Y558600D02*
Y562600D01*
X718200D01*
G01X722209Y540894D02*
X719709D01*
Y541935D01*
X719834Y542269D01*
X720001Y542477D01*
X720334Y542560D01*
X720667Y542477D01*
X720876Y542227D01*
X721001Y541935D01*
Y540894D01*
G01Y541935D02*
X722209Y542560D01*
G01Y545327D02*
X719709D01*
X721501Y543785D01*
Y545869D01*
G01X722209Y547844D02*
X721667Y547927D01*
X721209Y548052D01*
X720792Y548219D01*
X720334Y548427D01*
X719709Y548760D01*
Y547094D01*
G01Y551027D02*
X719792Y550694D01*
X720001Y550444D01*
X720251Y550277D01*
X720584Y550152D01*
X720959Y550110D01*
X721334Y550152D01*
X721667Y550277D01*
X721917Y550444D01*
X722126Y550694D01*
X722209Y551027D01*
X722126Y551360D01*
X721917Y551610D01*
X721667Y551777D01*
X721334Y551902D01*
X720959Y551944D01*
X720584Y551902D01*
X720251Y551777D01*
X720001Y551610D01*
X719792Y551360D01*
X719709Y551027D01*
G01X715575Y558177D02*
X711575D01*
Y550777D01*
G01X714176Y596029D02*
Y592029D01*
X721576D01*
G01X729676Y585729D02*
X733676D01*
Y593129D01*
G01X730000Y585650D02*
X726000D01*
Y578250D01*
G01X690467Y559759D02*
X690217Y559884D01*
X689925Y559967D01*
X689592D01*
X689217Y559842D01*
X688925Y559634D01*
X688717Y559384D01*
X688550Y558967D01*
X688508Y558592D01*
X688592Y558217D01*
X688717Y557967D01*
X688967Y557717D01*
X689258Y557550D01*
X689550Y557467D01*
X689842D01*
X690133Y557550D01*
X690383Y557675D01*
X690592Y557842D01*
G01X692650Y557467D02*
Y559967D01*
X692150Y559467D01*
G01Y557467D02*
X693150D01*
G01X694958Y558509D02*
X695250Y558800D01*
X695500Y558967D01*
X695833Y559050D01*
X696125Y558967D01*
X696333Y558800D01*
X696500Y558550D01*
X696542Y558259D01*
X696500Y558009D01*
X696333Y557759D01*
X696083Y557550D01*
X695792Y557467D01*
X695458Y557550D01*
X695167Y557800D01*
X695000Y558175D01*
X694958Y558592D01*
X695042Y559134D01*
X695167Y559425D01*
X695375Y559717D01*
X695667Y559925D01*
X695958Y559967D01*
X696250Y559884D01*
X696458Y559675D01*
G01X698850Y557467D02*
Y559967D01*
X698350Y559467D01*
G01Y557467D02*
X699350D01*
G01X696834Y533117D02*
X699334D01*
Y534783D01*
G01X698292Y536258D02*
X698001Y536550D01*
X697834Y536800D01*
X697751Y537133D01*
X697834Y537425D01*
X698001Y537633D01*
X698251Y537800D01*
X698542Y537842D01*
X698792Y537800D01*
X699042Y537633D01*
X699251Y537383D01*
X699334Y537092D01*
X699251Y536758D01*
X699001Y536467D01*
X698626Y536300D01*
X698209Y536258D01*
X697667Y536342D01*
X697376Y536467D01*
X697084Y536675D01*
X696876Y536967D01*
X696834Y537258D01*
X696917Y537550D01*
X697126Y537758D01*
G01X695600Y540000D02*
X688400D01*
G01X734834Y573567D02*
X732334D01*
Y574567D01*
X732459Y574900D01*
X732751Y575150D01*
X733084Y575233D01*
X733417Y575150D01*
X733667Y574942D01*
X733792Y574567D01*
Y573567D01*
G01X732334Y576583D02*
X734126D01*
X734501Y576750D01*
X734751Y577083D01*
X734834Y577500D01*
X734751Y577917D01*
X734501Y578250D01*
X734126Y578417D01*
X732334D01*
G01X734834Y580600D02*
X732334D01*
X732834Y580100D01*
G01X734834D02*
Y581100D01*
G01X709346Y563749D02*
X714346D01*
Y568749D01*
G01X686746D02*
Y563749D01*
X691746D01*
G01Y591449D02*
X686746D01*
Y586449D01*
G01X706452Y564756D02*
Y561756D01*
G01X696609Y564756D02*
Y562756D01*
G01X692672Y590442D02*
Y593442D01*
G01X702515Y590442D02*
Y592442D01*
G01X672776Y583071D02*
X677976D01*
G01X672776Y576071D02*
X680576D01*
G01X672776Y583071D02*
Y576071D01*
G01X686176Y583071D02*
X677476D01*
G01X686176Y576071D02*
Y583071D01*
G01X679776Y576071D02*
X686176D01*
G01X728737Y657722D02*
X729404Y658222D01*
X729904Y659055D01*
X730237Y660222D01*
X729904Y661222D01*
X729237Y661889D01*
X728071Y662389D01*
X723571D01*
Y652389D01*
X729071D01*
X730237Y653056D01*
X730904Y654056D01*
X731237Y655222D01*
X730904Y656389D01*
X729904Y657389D01*
X728737Y657722D01*
X723571D01*
G01X740004Y652389D02*
Y662389D01*
X733837Y655222D01*
X742171D01*
G01X748604Y652389D02*
X749771Y652556D01*
X751104Y653056D01*
X751937Y653889D01*
X752271Y655056D01*
X751937Y656222D01*
X750937Y657222D01*
X749437Y657722D01*
X747771D01*
X746771Y658056D01*
X745937Y658889D01*
X745604Y660056D01*
X746104Y661222D01*
X747270Y662056D01*
X748604Y662389D01*
X749937Y662056D01*
X751104Y661222D01*
X751604Y660056D01*
X751271Y658889D01*
X750437Y658056D01*
X749437Y657722D01*
X747771D01*
X746271Y657222D01*
X745271Y656222D01*
X744937Y655056D01*
X745271Y653889D01*
X746104Y653056D01*
X747437Y652556D01*
X748604Y652389D01*
G01X759204Y652056D02*
X758871Y652222D01*
Y652556D01*
X759204Y652722D01*
X759537Y652556D01*
Y652222D01*
X759204Y652056D01*
G01X769804Y662389D02*
X768470Y662056D01*
X767471Y661222D01*
X766804Y660222D01*
X766304Y658889D01*
X766137Y657389D01*
X766304Y655889D01*
X766804Y654556D01*
X767471Y653555D01*
X768470Y652722D01*
X769804Y652389D01*
X771137Y652722D01*
X772137Y653555D01*
X772804Y654556D01*
X773304Y655889D01*
X773471Y657389D01*
X773304Y658889D01*
X772804Y660222D01*
X772137Y661222D01*
X771137Y662056D01*
X769804Y662389D01*
G01X780404Y652389D02*
Y662389D01*
X778404Y660389D01*
G01Y652389D02*
X782404D01*
G01X791004D02*
Y662389D01*
X789004Y660389D01*
G01Y652389D02*
X793004D01*
G01X801604D02*
Y662389D01*
X799604Y660389D01*
G01Y652389D02*
X803604D01*
G01X808537Y653889D02*
X809537Y653056D01*
X810704Y652556D01*
X812204Y652389D01*
X813704Y652722D01*
X814871Y653389D01*
X815704Y654556D01*
X815871Y655889D01*
X815537Y657222D01*
X814704Y658056D01*
X813537Y658722D01*
X812371Y658889D01*
X811204Y658722D01*
X809704Y658056D01*
X810204Y662389D01*
X814704D01*
G01X822804Y652056D02*
X822471Y652222D01*
Y652556D01*
X822804Y652722D01*
X823137Y652556D01*
Y652222D01*
X822804Y652056D01*
G01X833404Y662389D02*
X832070Y662056D01*
X831071Y661222D01*
X830404Y660222D01*
X829904Y658889D01*
X829737Y657389D01*
X829904Y655889D01*
X830404Y654556D01*
X831071Y653555D01*
X832070Y652722D01*
X833404Y652389D01*
X834737Y652722D01*
X835737Y653555D01*
X836404Y654556D01*
X836904Y655889D01*
X837071Y657389D01*
X836904Y658889D01*
X836404Y660222D01*
X835737Y661222D01*
X834737Y662056D01*
X833404Y662389D01*
G01X844004D02*
X842670Y662056D01*
X841671Y661222D01*
X841004Y660222D01*
X840504Y658889D01*
X840337Y657389D01*
X840504Y655889D01*
X841004Y654556D01*
X841671Y653555D01*
X842670Y652722D01*
X844004Y652389D01*
X845337Y652722D01*
X846337Y653555D01*
X847004Y654556D01*
X847504Y655889D01*
X847671Y657389D01*
X847504Y658889D01*
X847004Y660222D01*
X846337Y661222D01*
X845337Y662056D01*
X844004Y662389D01*
G01X851437Y660722D02*
X852437Y661722D01*
X853604Y662222D01*
X854937Y662389D01*
X856604Y662056D01*
X857771Y661222D01*
X858104Y660222D01*
X857937Y659222D01*
X857271Y658389D01*
X853937Y656722D01*
X852437Y655556D01*
X851437Y653889D01*
X851104Y652389D01*
X858104D01*
G01X865204D02*
Y662389D01*
X863204Y660389D01*
G01Y652389D02*
X867204D01*
G01X722371Y636889D02*
Y646889D01*
X726704Y638556D01*
X731037Y646889D01*
Y636889D01*
G01X733137D02*
X737304Y646889D01*
X741471Y636889D01*
G01X739971Y640389D02*
X734637D01*
G01X744237Y636889D02*
Y646889D01*
X747571D01*
X748904Y646389D01*
X749904Y645722D01*
X750737Y644722D01*
X751404Y643555D01*
X751571Y641889D01*
X751404Y640222D01*
X750737Y639056D01*
X749904Y638055D01*
X748904Y637389D01*
X747571Y636889D01*
X744237D01*
G01X761837D02*
X755171D01*
Y646889D01*
X761837D01*
G01X759171Y642056D02*
X755171D01*
G01X777704Y646889D02*
X781704D01*
G01X779704D02*
Y636889D01*
G01X777704D02*
X781704D01*
G01X786471D02*
Y646889D01*
X794137Y636889D01*
Y646889D01*
G01X811504D02*
Y636889D01*
G01X807671Y646889D02*
X815337D01*
G01X817937Y636889D02*
X822104Y646889D01*
X826271Y636889D01*
G01X824771Y640389D02*
X819437D01*
G01X830704Y646889D02*
X834704D01*
G01X832704D02*
Y636889D01*
G01X830704D02*
X834704D01*
G01X838304Y646889D02*
X840637Y636889D01*
X843304Y646889D01*
X845971Y636889D01*
X848304Y646889D01*
G01X849737Y636889D02*
X853904Y646889D01*
X858071Y636889D01*
G01X856571Y640389D02*
X851237D01*
G01X860671Y636889D02*
Y646889D01*
X868337Y636889D01*
Y646889D01*
G01X725317Y614467D02*
Y616967D01*
X726358D01*
X726692Y616842D01*
X726900Y616675D01*
X726983Y616342D01*
X726900Y616009D01*
X726650Y615800D01*
X726358Y615675D01*
X725317D01*
G01X726358D02*
X726983Y614467D01*
G01X729750D02*
Y616967D01*
X728208Y615175D01*
X730292D01*
G01X731558Y615509D02*
X731850Y615800D01*
X732100Y615967D01*
X732433Y616050D01*
X732725Y615967D01*
X732933Y615800D01*
X733100Y615550D01*
X733142Y615259D01*
X733100Y615009D01*
X732933Y614759D01*
X732683Y614550D01*
X732392Y614467D01*
X732058Y614550D01*
X731767Y614800D01*
X731600Y615175D01*
X731558Y615592D01*
X731642Y616134D01*
X731767Y616425D01*
X731975Y616717D01*
X732267Y616925D01*
X732558Y616967D01*
X732850Y616884D01*
X733058Y616675D01*
G01X735450Y614467D02*
X735742Y614509D01*
X736075Y614634D01*
X736283Y614842D01*
X736367Y615134D01*
X736283Y615425D01*
X736033Y615675D01*
X735658Y615800D01*
X735242D01*
X734992Y615884D01*
X734783Y616092D01*
X734700Y616384D01*
X734825Y616675D01*
X735117Y616884D01*
X735450Y616967D01*
X735783Y616884D01*
X736075Y616675D01*
X736200Y616384D01*
X736117Y616092D01*
X735908Y615884D01*
X735658Y615800D01*
X735242D01*
X734867Y615675D01*
X734617Y615425D01*
X734533Y615134D01*
X734617Y614842D01*
X734825Y614634D01*
X735158Y614509D01*
X735450Y614467D01*
G01X705800Y616500D02*
Y612500D01*
X713200D01*
G01X705800Y606900D02*
X701800D01*
Y599500D01*
G01X705826Y599479D02*
X709826D01*
Y606879D01*
G01X721576Y596329D02*
Y600329D01*
X714176D01*
G01X714345Y606390D02*
X718345D01*
Y613790D01*
G01X727067Y620359D02*
X726817Y620484D01*
X726525Y620567D01*
X726192D01*
X725817Y620442D01*
X725525Y620234D01*
X725317Y619984D01*
X725150Y619567D01*
X725108Y619192D01*
X725192Y618817D01*
X725317Y618567D01*
X725567Y618317D01*
X725858Y618150D01*
X726150Y618067D01*
X726442D01*
X726733Y618150D01*
X726983Y618275D01*
X727192Y618442D01*
G01X729250Y618067D02*
Y620567D01*
X728750Y620067D01*
G01Y618067D02*
X729750D01*
G01X731558Y619109D02*
X731850Y619400D01*
X732100Y619567D01*
X732433Y619650D01*
X732725Y619567D01*
X732933Y619400D01*
X733100Y619150D01*
X733142Y618859D01*
X733100Y618609D01*
X732933Y618359D01*
X732683Y618150D01*
X732392Y618067D01*
X732058Y618150D01*
X731767Y618400D01*
X731600Y618775D01*
X731558Y619192D01*
X731642Y619734D01*
X731767Y620025D01*
X731975Y620317D01*
X732267Y620525D01*
X732558Y620567D01*
X732850Y620484D01*
X733058Y620275D01*
G01X735450Y620567D02*
X735117Y620484D01*
X734867Y620275D01*
X734700Y620025D01*
X734575Y619692D01*
X734533Y619317D01*
X734575Y618942D01*
X734700Y618609D01*
X734867Y618359D01*
X735117Y618150D01*
X735450Y618067D01*
X735783Y618150D01*
X736033Y618359D01*
X736200Y618609D01*
X736325Y618942D01*
X736367Y619317D01*
X736325Y619692D01*
X736200Y620025D01*
X736033Y620275D01*
X735783Y620484D01*
X735450Y620567D01*
G01X685300Y644200D02*
Y662200D01*
G01X674100Y644200D02*
X685300D01*
G01X711733Y707333D02*
X712400Y707833D01*
X712900Y708666D01*
X713233Y709833D01*
X712900Y710833D01*
X712233Y711500D01*
X711067Y712000D01*
X706567D01*
Y702000D01*
X712067D01*
X713233Y702667D01*
X713900Y703667D01*
X714233Y704833D01*
X713900Y706000D01*
X712900Y707000D01*
X711733Y707333D01*
X706567D01*
G01X718667Y702000D02*
Y708666D01*
G01Y707333D02*
X719500Y708000D01*
X720333Y708500D01*
X721500Y708666D01*
X722333Y708500D01*
X723333Y708000D01*
G01X728100Y699000D02*
X729100Y698667D01*
X730433Y699000D01*
X731267Y699667D01*
X731933Y700500D01*
X732933Y703166D01*
X735100Y708666D01*
G01X729767D02*
X732933Y703166D01*
G01X744867Y707833D02*
X743700Y708500D01*
X742700Y708666D01*
X741367Y708333D01*
X740367Y707667D01*
X739700Y706500D01*
X739533Y705333D01*
X739700Y704167D01*
X740367Y703166D01*
X741367Y702333D01*
X742700Y702000D01*
X743867Y702333D01*
X744867Y703000D01*
G01X750300Y706500D02*
X755633D01*
X755133Y707667D01*
X754300Y708333D01*
X753133Y708666D01*
X751967Y708500D01*
X750967Y708000D01*
X750300Y706833D01*
X749967Y705833D01*
Y704833D01*
X750300Y703833D01*
X751133Y702833D01*
X752133Y702167D01*
X753300Y702000D01*
X754467Y702333D01*
X755633Y703333D01*
G01X777667Y711167D02*
X776667Y711667D01*
X775500Y712000D01*
X774167D01*
X772666Y711500D01*
X771500Y710667D01*
X770667Y709667D01*
X770000Y708000D01*
X769833Y706500D01*
X770167Y705000D01*
X770667Y704000D01*
X771667Y703000D01*
X772833Y702333D01*
X774000Y702000D01*
X775167D01*
X776333Y702333D01*
X777333Y702833D01*
X778167Y703500D01*
G01X787600Y702000D02*
Y708666D01*
G01Y707500D02*
X786933Y708167D01*
X785933Y708500D01*
X784767Y708666D01*
X783600Y708333D01*
X782600Y707667D01*
X781933Y706667D01*
X781600Y705333D01*
X781933Y704000D01*
X782600Y703000D01*
X783600Y702333D01*
X784767Y702000D01*
X785933Y702167D01*
X786933Y702667D01*
X787600Y703333D01*
G01X792367Y702000D02*
Y708666D01*
G01Y707000D02*
X793033Y707833D01*
X794033Y708500D01*
X795367Y708666D01*
X796533Y708500D01*
X797533Y707833D01*
X798033Y706667D01*
Y702000D01*
G01X802300Y699000D02*
X803300Y698667D01*
X804633Y699000D01*
X805467Y699667D01*
X806133Y700500D01*
X807133Y703166D01*
X809300Y708666D01*
G01X803967D02*
X807133Y703166D01*
G01X816400Y702000D02*
X815400Y702167D01*
X814400Y702833D01*
X813733Y704000D01*
X813400Y705333D01*
X813733Y706667D01*
X814400Y707833D01*
X815400Y708500D01*
X816400Y708666D01*
X817400Y708500D01*
X818400Y707833D01*
X819067Y706667D01*
X819233Y705333D01*
X819067Y704000D01*
X818400Y702833D01*
X817400Y702167D01*
X816400Y702000D01*
G01X824167D02*
Y708666D01*
G01Y707000D02*
X824833Y707833D01*
X825833Y708500D01*
X827167Y708666D01*
X828333Y708500D01*
X829333Y707833D01*
X829833Y706667D01*
Y702000D01*
G01X846200Y712000D02*
X850200D01*
G01X848200D02*
Y702000D01*
G01X846200D02*
X850200D01*
G01X858800D02*
X857466Y702167D01*
X856300Y702833D01*
X855300Y703833D01*
X854633Y705000D01*
X854300Y706333D01*
Y707667D01*
X854633Y709000D01*
X855300Y710167D01*
X856300Y711167D01*
X857466Y711833D01*
X858800Y712000D01*
X860133Y711833D01*
X861300Y711167D01*
X862300Y710167D01*
X862967Y709000D01*
X863300Y707667D01*
Y706333D01*
X862967Y705000D01*
X862300Y703833D01*
X861300Y702833D01*
X860133Y702167D01*
X858800Y702000D01*
G01X865067D02*
Y712000D01*
X869400Y703667D01*
X873733Y712000D01*
Y702000D01*
G01X681767Y698459D02*
X681517Y698584D01*
X681225Y698667D01*
X680892D01*
X680517Y698542D01*
X680225Y698334D01*
X680017Y698084D01*
X679850Y697667D01*
X679808Y697292D01*
X679892Y696917D01*
X680017Y696667D01*
X680267Y696417D01*
X680558Y696250D01*
X680850Y696167D01*
X681142D01*
X681433Y696250D01*
X681683Y696375D01*
X681892Y696542D01*
G01X683950Y696167D02*
Y698667D01*
X683450Y698167D01*
G01Y696167D02*
X684450D01*
G01X686258Y697209D02*
X686550Y697500D01*
X686800Y697667D01*
X687133Y697750D01*
X687425Y697667D01*
X687633Y697500D01*
X687800Y697250D01*
X687842Y696959D01*
X687800Y696709D01*
X687633Y696459D01*
X687383Y696250D01*
X687092Y696167D01*
X686758Y696250D01*
X686467Y696500D01*
X686300Y696875D01*
X686258Y697292D01*
X686342Y697834D01*
X686467Y698125D01*
X686675Y698417D01*
X686967Y698625D01*
X687258Y698667D01*
X687550Y698584D01*
X687758Y698375D01*
G01X690650Y696167D02*
Y698667D01*
X689108Y696875D01*
X691192D01*
G01X681767Y694459D02*
X681517Y694584D01*
X681225Y694667D01*
X680892D01*
X680517Y694542D01*
X680225Y694334D01*
X680017Y694084D01*
X679850Y693667D01*
X679808Y693292D01*
X679892Y692917D01*
X680017Y692667D01*
X680267Y692417D01*
X680558Y692250D01*
X680850Y692167D01*
X681142D01*
X681433Y692250D01*
X681683Y692375D01*
X681892Y692542D01*
G01X683950Y692167D02*
Y694667D01*
X683450Y694167D01*
G01Y692167D02*
X684450D01*
G01X686258Y693209D02*
X686550Y693500D01*
X686800Y693667D01*
X687133Y693750D01*
X687425Y693667D01*
X687633Y693500D01*
X687800Y693250D01*
X687842Y692959D01*
X687800Y692709D01*
X687633Y692459D01*
X687383Y692250D01*
X687092Y692167D01*
X686758Y692250D01*
X686467Y692500D01*
X686300Y692875D01*
X686258Y693292D01*
X686342Y693834D01*
X686467Y694125D01*
X686675Y694417D01*
X686967Y694625D01*
X687258Y694667D01*
X687550Y694584D01*
X687758Y694375D01*
G01X689233Y692542D02*
X689483Y692334D01*
X689775Y692209D01*
X690150Y692167D01*
X690525Y692250D01*
X690817Y692417D01*
X691025Y692709D01*
X691067Y693042D01*
X690983Y693375D01*
X690775Y693584D01*
X690483Y693750D01*
X690192Y693792D01*
X689900Y693750D01*
X689525Y693584D01*
X689650Y694667D01*
X690775D01*
G01X681767Y690459D02*
X681517Y690584D01*
X681225Y690667D01*
X680892D01*
X680517Y690542D01*
X680225Y690334D01*
X680017Y690084D01*
X679850Y689667D01*
X679808Y689292D01*
X679892Y688917D01*
X680017Y688667D01*
X680267Y688417D01*
X680558Y688250D01*
X680850Y688167D01*
X681142D01*
X681433Y688250D01*
X681683Y688375D01*
X681892Y688542D01*
G01X683950Y688167D02*
Y690667D01*
X683450Y690167D01*
G01Y688167D02*
X684450D01*
G01X686258Y689209D02*
X686550Y689500D01*
X686800Y689667D01*
X687133Y689750D01*
X687425Y689667D01*
X687633Y689500D01*
X687800Y689250D01*
X687842Y688959D01*
X687800Y688709D01*
X687633Y688459D01*
X687383Y688250D01*
X687092Y688167D01*
X686758Y688250D01*
X686467Y688500D01*
X686300Y688875D01*
X686258Y689292D01*
X686342Y689834D01*
X686467Y690125D01*
X686675Y690417D01*
X686967Y690625D01*
X687258Y690667D01*
X687550Y690584D01*
X687758Y690375D01*
G01X689358Y689209D02*
X689650Y689500D01*
X689900Y689667D01*
X690233Y689750D01*
X690525Y689667D01*
X690733Y689500D01*
X690900Y689250D01*
X690942Y688959D01*
X690900Y688709D01*
X690733Y688459D01*
X690483Y688250D01*
X690192Y688167D01*
X689858Y688250D01*
X689567Y688500D01*
X689400Y688875D01*
X689358Y689292D01*
X689442Y689834D01*
X689567Y690125D01*
X689775Y690417D01*
X690067Y690625D01*
X690358Y690667D01*
X690650Y690584D01*
X690858Y690375D01*
G01X685300Y662200D02*
X674100D01*
G01X681270Y701329D02*
X682103D01*
Y700579D01*
X681853Y700329D01*
X681562Y700162D01*
X681145Y700079D01*
X680728Y700162D01*
X680437Y700329D01*
X680187Y700579D01*
X680020Y700871D01*
X679937Y701204D01*
Y701496D01*
X680020Y701746D01*
X680187Y702037D01*
X680437Y702287D01*
X680687Y702454D01*
X681020Y702579D01*
X681312D01*
X681645Y702496D01*
X681895Y702329D01*
G01X684120Y700079D02*
Y702579D01*
X683620Y702079D01*
G01Y700079D02*
X684620D01*
G01X685300Y682400D02*
X674100D01*
G01X685300Y664400D02*
Y682400D01*
G01X674100Y664400D02*
X685300D01*
G01X748980Y30409D02*
X778580D01*
Y-7191D01*
X748980D01*
Y30409D01*
G01X796224D02*
X825824D01*
Y-7191D01*
X796224D01*
Y30409D01*
G01X762367Y65792D02*
X762117Y65917D01*
X761825Y66000D01*
X761492D01*
X761117Y65875D01*
X760825Y65667D01*
X760617Y65417D01*
X760450Y65000D01*
X760408Y64625D01*
X760492Y64250D01*
X760617Y64000D01*
X760867Y63750D01*
X761158Y63583D01*
X761450Y63500D01*
X761742D01*
X762033Y63583D01*
X762283Y63708D01*
X762492Y63875D01*
G01X763633D02*
X763883Y63667D01*
X764175Y63542D01*
X764550Y63500D01*
X764925Y63583D01*
X765217Y63750D01*
X765425Y64042D01*
X765467Y64375D01*
X765383Y64708D01*
X765175Y64917D01*
X764883Y65083D01*
X764592Y65125D01*
X764300Y65083D01*
X763925Y64917D01*
X764050Y66000D01*
X765175D01*
G01X767650Y63500D02*
Y66000D01*
X767150Y65500D01*
G01Y63500D02*
X768150D01*
G01X769958Y64542D02*
X770250Y64833D01*
X770500Y65000D01*
X770833Y65083D01*
X771125Y65000D01*
X771333Y64833D01*
X771500Y64583D01*
X771542Y64292D01*
X771500Y64042D01*
X771333Y63792D01*
X771083Y63583D01*
X770792Y63500D01*
X770458Y63583D01*
X770167Y63833D01*
X770000Y64208D01*
X769958Y64625D01*
X770042Y65167D01*
X770167Y65458D01*
X770375Y65750D01*
X770667Y65958D01*
X770958Y66000D01*
X771250Y65917D01*
X771458Y65708D01*
G01X771308Y48467D02*
X771183Y48217D01*
X771100Y47925D01*
Y47592D01*
X771225Y47217D01*
X771433Y46925D01*
X771683Y46717D01*
X772100Y46550D01*
X772475Y46508D01*
X772850Y46592D01*
X773100Y46717D01*
X773350Y46967D01*
X773517Y47258D01*
X773600Y47550D01*
Y47842D01*
X773517Y48133D01*
X773392Y48383D01*
X773225Y48592D01*
G01Y49733D02*
X773433Y49983D01*
X773558Y50275D01*
X773600Y50650D01*
X773517Y51025D01*
X773350Y51317D01*
X773058Y51525D01*
X772725Y51567D01*
X772392Y51483D01*
X772183Y51275D01*
X772017Y50983D01*
X771975Y50692D01*
X772017Y50400D01*
X772183Y50025D01*
X771100Y50150D01*
Y51275D01*
G01X773600Y53750D02*
X771100D01*
X771600Y53250D01*
G01X773600D02*
Y54250D01*
G01Y57350D02*
X771100D01*
X772892Y55808D01*
Y57892D01*
G01X780500Y77500D02*
Y63500D01*
G01X793500D02*
Y77500D01*
G01X780500Y63500D02*
X793500D01*
G01X782053Y41462D02*
Y39670D01*
X782220Y39295D01*
X782553Y39045D01*
X782970Y38962D01*
X783387Y39045D01*
X783720Y39295D01*
X783887Y39670D01*
Y41462D01*
G01X786570Y38962D02*
Y41462D01*
X785028Y39670D01*
X787112D01*
G01X789087Y38962D02*
X789170Y39504D01*
X789295Y39962D01*
X789462Y40379D01*
X789670Y40837D01*
X790003Y41462D01*
X788337D01*
G01X791420Y57012D02*
Y43612D01*
G01X781420Y57012D02*
X791420D01*
G01X781420Y43612D02*
Y57012D01*
G01X791420Y43612D02*
X781420D01*
G01X745700Y46417D02*
X743200D01*
Y47458D01*
X743325Y47792D01*
X743492Y48000D01*
X743825Y48083D01*
X744158Y48000D01*
X744367Y47750D01*
X744492Y47458D01*
Y46417D01*
G01Y47458D02*
X745700Y48083D01*
G01Y50350D02*
X745658Y50642D01*
X745533Y50975D01*
X745325Y51183D01*
X745033Y51267D01*
X744742Y51183D01*
X744492Y50933D01*
X744367Y50558D01*
Y50142D01*
X744283Y49892D01*
X744075Y49683D01*
X743783Y49600D01*
X743492Y49725D01*
X743283Y50017D01*
X743200Y50350D01*
X743283Y50683D01*
X743492Y50975D01*
X743783Y51100D01*
X744075Y51017D01*
X744283Y50808D01*
X744367Y50558D01*
Y50142D01*
X744492Y49767D01*
X744742Y49517D01*
X745033Y49433D01*
X745325Y49517D01*
X745533Y49725D01*
X745658Y50058D01*
X745700Y50350D01*
G01X743200Y53450D02*
X743283Y53117D01*
X743492Y52867D01*
X743742Y52700D01*
X744075Y52575D01*
X744450Y52533D01*
X744825Y52575D01*
X745158Y52700D01*
X745408Y52867D01*
X745617Y53117D01*
X745700Y53450D01*
X745617Y53783D01*
X745408Y54033D01*
X745158Y54200D01*
X744825Y54325D01*
X744450Y54367D01*
X744075Y54325D01*
X743742Y54200D01*
X743492Y54033D01*
X743283Y53783D01*
X743200Y53450D01*
G01Y56550D02*
X743283Y56217D01*
X743492Y55967D01*
X743742Y55800D01*
X744075Y55675D01*
X744450Y55633D01*
X744825Y55675D01*
X745158Y55800D01*
X745408Y55967D01*
X745617Y56217D01*
X745700Y56550D01*
X745617Y56883D01*
X745408Y57133D01*
X745158Y57300D01*
X744825Y57425D01*
X744450Y57467D01*
X744075Y57425D01*
X743742Y57300D01*
X743492Y57133D01*
X743283Y56883D01*
X743200Y56550D01*
G01X751217Y38400D02*
Y40900D01*
X752258D01*
X752592Y40775D01*
X752800Y40608D01*
X752883Y40275D01*
X752800Y39942D01*
X752550Y39733D01*
X752258Y39608D01*
X751217D01*
G01X752258D02*
X752883Y38400D01*
G01X755067D02*
X755150Y38942D01*
X755275Y39400D01*
X755442Y39817D01*
X755650Y40275D01*
X755983Y40900D01*
X754317D01*
G01X757333Y38900D02*
X757583Y38608D01*
X757917Y38442D01*
X758292Y38400D01*
X758625Y38442D01*
X758958Y38650D01*
X759167Y38900D01*
X759208Y39150D01*
X759125Y39442D01*
X758833Y39650D01*
X758542Y39733D01*
X758167D01*
G01X758542D02*
X758792Y39858D01*
X759000Y40067D01*
X759083Y40317D01*
X759000Y40567D01*
X758792Y40775D01*
X758417Y40900D01*
X758042Y40858D01*
X757667Y40692D01*
G01X760433Y38900D02*
X760683Y38608D01*
X761017Y38442D01*
X761392Y38400D01*
X761725Y38442D01*
X762058Y38650D01*
X762267Y38900D01*
X762308Y39150D01*
X762225Y39442D01*
X761933Y39650D01*
X761642Y39733D01*
X761267D01*
G01X761642D02*
X761892Y39858D01*
X762100Y40067D01*
X762183Y40317D01*
X762100Y40567D01*
X761892Y40775D01*
X761517Y40900D01*
X761142Y40858D01*
X760767Y40692D01*
G01X759017Y34817D02*
Y32317D01*
X760683D01*
G01X763783D02*
X762117D01*
Y34817D01*
X763783D01*
G01X763117Y33609D02*
X762117D01*
G01X765133Y32317D02*
Y34817D01*
X765967D01*
X766300Y34692D01*
X766550Y34525D01*
X766758Y34275D01*
X766925Y33984D01*
X766967Y33567D01*
X766925Y33150D01*
X766758Y32859D01*
X766550Y32609D01*
X766300Y32442D01*
X765967Y32317D01*
X765133D01*
G01X768358Y34400D02*
X768608Y34650D01*
X768900Y34775D01*
X769233Y34817D01*
X769650Y34734D01*
X769942Y34525D01*
X770025Y34275D01*
X769983Y34025D01*
X769817Y33817D01*
X768983Y33400D01*
X768608Y33109D01*
X768358Y32692D01*
X768275Y32317D01*
X770025D01*
G01X756875Y15199D02*
X750175D01*
G01X761975D02*
X766075D01*
G01X756875Y10099D02*
X761975Y15199D01*
G01X756875Y20299D02*
Y10099D01*
G01X761975Y15199D02*
X756875Y20299D01*
G01X771175Y10099D02*
X766075Y15199D01*
G01X771175Y20299D02*
Y10099D01*
G01X766075Y15199D02*
X771175Y20299D01*
G01Y15199D02*
X774875D01*
G01X761975Y12399D02*
Y18799D01*
G01X766075Y12399D02*
Y18799D01*
G01X796517Y36000D02*
Y33500D01*
X798183D01*
G01X801283D02*
X799617D01*
Y36000D01*
X801283D01*
G01X800617Y34792D02*
X799617D01*
G01X802633Y33500D02*
Y36000D01*
X803467D01*
X803800Y35875D01*
X804050Y35708D01*
X804258Y35458D01*
X804425Y35167D01*
X804467Y34750D01*
X804425Y34333D01*
X804258Y34042D01*
X804050Y33792D01*
X803800Y33625D01*
X803467Y33500D01*
X802633D01*
G01X806567D02*
X806650Y34042D01*
X806775Y34500D01*
X806942Y34917D01*
X807150Y35375D01*
X807483Y36000D01*
X805817D01*
G01X804119Y15199D02*
X797419D01*
G01X798600Y52300D02*
X798558Y51967D01*
X798392Y51675D01*
X798142Y51425D01*
X797850Y51258D01*
X797517Y51175D01*
X797183D01*
X796850Y51258D01*
X796558Y51425D01*
X796308Y51675D01*
X796142Y51967D01*
X796100Y52300D01*
X796142Y52633D01*
X796308Y52925D01*
X796558Y53175D01*
X796850Y53342D01*
X797183Y53425D01*
X797517D01*
X797850Y53342D01*
X798142Y53175D01*
X798392Y52925D01*
X798558Y52633D01*
X798600Y52300D01*
G01X797933Y52633D02*
X798600Y53133D01*
G01X796517Y54608D02*
X796267Y54858D01*
X796142Y55150D01*
X796100Y55483D01*
X796183Y55900D01*
X796392Y56192D01*
X796642Y56275D01*
X796892Y56233D01*
X797100Y56067D01*
X797517Y55233D01*
X797808Y54858D01*
X798225Y54608D01*
X798600Y54525D01*
Y56275D01*
G01Y58500D02*
X798558Y58792D01*
X798433Y59125D01*
X798225Y59333D01*
X797933Y59417D01*
X797642Y59333D01*
X797392Y59083D01*
X797267Y58708D01*
Y58292D01*
X797183Y58042D01*
X796975Y57833D01*
X796683Y57750D01*
X796392Y57875D01*
X796183Y58167D01*
X796100Y58500D01*
X796183Y58833D01*
X796392Y59125D01*
X796683Y59250D01*
X796975Y59167D01*
X797183Y58958D01*
X797267Y58708D01*
Y58292D01*
X797392Y57917D01*
X797642Y57667D01*
X797933Y57583D01*
X798225Y57667D01*
X798433Y57875D01*
X798558Y58208D01*
X798600Y58500D01*
G01X747050Y63900D02*
X746717Y63942D01*
X746425Y64108D01*
X746175Y64358D01*
X746008Y64650D01*
X745925Y64983D01*
Y65317D01*
X746008Y65650D01*
X746175Y65942D01*
X746425Y66192D01*
X746717Y66358D01*
X747050Y66400D01*
X747383Y66358D01*
X747675Y66192D01*
X747925Y65942D01*
X748092Y65650D01*
X748175Y65317D01*
Y64983D01*
X748092Y64650D01*
X747925Y64358D01*
X747675Y64108D01*
X747383Y63942D01*
X747050Y63900D01*
G01X747383Y64567D02*
X747883Y63900D01*
G01X749358Y65983D02*
X749608Y66233D01*
X749900Y66358D01*
X750233Y66400D01*
X750650Y66317D01*
X750942Y66108D01*
X751025Y65858D01*
X750983Y65608D01*
X750817Y65400D01*
X749983Y64983D01*
X749608Y64692D01*
X749358Y64275D01*
X749275Y63900D01*
X751025D01*
G01X753250Y66400D02*
X752917Y66317D01*
X752667Y66108D01*
X752500Y65858D01*
X752375Y65525D01*
X752333Y65150D01*
X752375Y64775D01*
X752500Y64442D01*
X752667Y64192D01*
X752917Y63983D01*
X753250Y63900D01*
X753583Y63983D01*
X753833Y64192D01*
X754000Y64442D01*
X754125Y64775D01*
X754167Y65150D01*
X754125Y65525D01*
X754000Y65858D01*
X753833Y66108D01*
X753583Y66317D01*
X753250Y66400D01*
G01X755558Y64942D02*
X755850Y65233D01*
X756100Y65400D01*
X756433Y65483D01*
X756725Y65400D01*
X756933Y65233D01*
X757100Y64983D01*
X757142Y64692D01*
X757100Y64442D01*
X756933Y64192D01*
X756683Y63983D01*
X756392Y63900D01*
X756058Y63983D01*
X755767Y64233D01*
X755600Y64608D01*
X755558Y65025D01*
X755642Y65567D01*
X755767Y65858D01*
X755975Y66150D01*
X756267Y66358D01*
X756558Y66400D01*
X756850Y66317D01*
X757058Y66108D01*
G01X768700Y55480D02*
X768440D01*
X767005Y54045D01*
X768440Y52610D01*
G01X768700Y55480D02*
Y52610D01*
X757700D01*
G01Y55480D02*
X768700D01*
G01X757700D02*
Y52610D01*
G01X764267Y129792D02*
X764017Y129917D01*
X763725Y130000D01*
X763392D01*
X763017Y129875D01*
X762725Y129667D01*
X762517Y129417D01*
X762350Y129000D01*
X762308Y128625D01*
X762392Y128250D01*
X762517Y128000D01*
X762767Y127750D01*
X763058Y127583D01*
X763350Y127500D01*
X763642D01*
X763933Y127583D01*
X764183Y127708D01*
X764392Y127875D01*
G01X765533D02*
X765783Y127667D01*
X766075Y127542D01*
X766450Y127500D01*
X766825Y127583D01*
X767117Y127750D01*
X767325Y128042D01*
X767367Y128375D01*
X767283Y128708D01*
X767075Y128917D01*
X766783Y129083D01*
X766492Y129125D01*
X766200Y129083D01*
X765825Y128917D01*
X765950Y130000D01*
X767075D01*
G01X769550Y127500D02*
Y130000D01*
X769050Y129500D01*
G01Y127500D02*
X770050D01*
G01X771733Y127875D02*
X771983Y127667D01*
X772275Y127542D01*
X772650Y127500D01*
X773025Y127583D01*
X773317Y127750D01*
X773525Y128042D01*
X773567Y128375D01*
X773483Y128708D01*
X773275Y128917D01*
X772983Y129083D01*
X772692Y129125D01*
X772400Y129083D01*
X772025Y128917D01*
X772150Y130000D01*
X773275D01*
G01X790834Y123717D02*
X788334D01*
Y124758D01*
X788459Y125092D01*
X788626Y125300D01*
X788959Y125383D01*
X789292Y125300D01*
X789501Y125050D01*
X789626Y124758D01*
Y123717D01*
G01Y124758D02*
X790834Y125383D01*
G01Y127567D02*
X790292Y127650D01*
X789834Y127775D01*
X789417Y127942D01*
X788959Y128150D01*
X788334Y128483D01*
Y126817D01*
G01X790334Y129833D02*
X790626Y130083D01*
X790792Y130417D01*
X790834Y130792D01*
X790792Y131125D01*
X790584Y131458D01*
X790334Y131667D01*
X790084Y131708D01*
X789792Y131625D01*
X789584Y131333D01*
X789501Y131042D01*
Y130667D01*
G01Y131042D02*
X789376Y131292D01*
X789167Y131500D01*
X788917Y131583D01*
X788667Y131500D01*
X788459Y131292D01*
X788334Y130917D01*
X788376Y130542D01*
X788542Y130167D01*
G01X788334Y133850D02*
X788417Y133517D01*
X788626Y133267D01*
X788876Y133100D01*
X789209Y132975D01*
X789584Y132933D01*
X789959Y132975D01*
X790292Y133100D01*
X790542Y133267D01*
X790751Y133517D01*
X790834Y133850D01*
X790751Y134183D01*
X790542Y134433D01*
X790292Y134600D01*
X789959Y134725D01*
X789584Y134767D01*
X789209Y134725D01*
X788876Y134600D01*
X788626Y134433D01*
X788417Y134183D01*
X788334Y133850D01*
G01X786161Y128815D02*
X782161D01*
Y121415D01*
G01X752320Y128510D02*
Y124510D01*
X759720D01*
G01X777784Y96367D02*
X775284D01*
Y97408D01*
X775409Y97742D01*
X775576Y97950D01*
X775909Y98033D01*
X776242Y97950D01*
X776451Y97700D01*
X776576Y97408D01*
Y96367D01*
G01Y97408D02*
X777784Y98033D01*
G01X776742Y99508D02*
X776451Y99800D01*
X776284Y100050D01*
X776201Y100383D01*
X776284Y100675D01*
X776451Y100883D01*
X776701Y101050D01*
X776992Y101092D01*
X777242Y101050D01*
X777492Y100883D01*
X777701Y100633D01*
X777784Y100342D01*
X777701Y100008D01*
X777451Y99717D01*
X777076Y99550D01*
X776659Y99508D01*
X776117Y99592D01*
X775826Y99717D01*
X775534Y99925D01*
X775326Y100217D01*
X775284Y100508D01*
X775367Y100800D01*
X775576Y101008D01*
G01X777492Y102692D02*
X777701Y102983D01*
X777784Y103317D01*
X777701Y103650D01*
X777451Y103942D01*
X777076Y104150D01*
X776701Y104233D01*
X776242D01*
X775867Y104150D01*
X775534Y103942D01*
X775367Y103692D01*
X775284Y103400D01*
X775367Y103067D01*
X775534Y102817D01*
X775784Y102650D01*
X776117Y102567D01*
X776409Y102650D01*
X776701Y102858D01*
X776867Y103108D01*
X776909Y103400D01*
X776826Y103733D01*
X776617Y103983D01*
X776242Y104233D01*
G01X777409Y105583D02*
X777617Y105833D01*
X777742Y106125D01*
X777784Y106500D01*
X777701Y106875D01*
X777534Y107167D01*
X777242Y107375D01*
X776909Y107417D01*
X776576Y107333D01*
X776367Y107125D01*
X776201Y106833D01*
X776159Y106542D01*
X776201Y106250D01*
X776367Y105875D01*
X775284Y106000D01*
Y107125D01*
G01X786400Y104700D02*
X782400D01*
Y97300D01*
G01X761384Y74167D02*
X758884D01*
Y75208D01*
X759009Y75542D01*
X759176Y75750D01*
X759509Y75833D01*
X759842Y75750D01*
X760051Y75500D01*
X760176Y75208D01*
Y74167D01*
G01Y75208D02*
X761384Y75833D01*
G01X760342Y77308D02*
X760051Y77600D01*
X759884Y77850D01*
X759801Y78183D01*
X759884Y78475D01*
X760051Y78683D01*
X760301Y78850D01*
X760592Y78892D01*
X760842Y78850D01*
X761092Y78683D01*
X761301Y78433D01*
X761384Y78142D01*
X761301Y77808D01*
X761051Y77517D01*
X760676Y77350D01*
X760259Y77308D01*
X759717Y77392D01*
X759426Y77517D01*
X759134Y77725D01*
X758926Y78017D01*
X758884Y78308D01*
X758967Y78600D01*
X759176Y78808D01*
G01X761092Y80492D02*
X761301Y80783D01*
X761384Y81117D01*
X761301Y81450D01*
X761051Y81742D01*
X760676Y81950D01*
X760301Y82033D01*
X759842D01*
X759467Y81950D01*
X759134Y81742D01*
X758967Y81492D01*
X758884Y81200D01*
X758967Y80867D01*
X759134Y80617D01*
X759384Y80450D01*
X759717Y80367D01*
X760009Y80450D01*
X760301Y80658D01*
X760467Y80908D01*
X760509Y81200D01*
X760426Y81533D01*
X760217Y81783D01*
X759842Y82033D01*
G01X760342Y83508D02*
X760051Y83800D01*
X759884Y84050D01*
X759801Y84383D01*
X759884Y84675D01*
X760051Y84883D01*
X760301Y85050D01*
X760592Y85092D01*
X760842Y85050D01*
X761092Y84883D01*
X761301Y84633D01*
X761384Y84342D01*
X761301Y84008D01*
X761051Y83717D01*
X760676Y83550D01*
X760259Y83508D01*
X759717Y83592D01*
X759426Y83717D01*
X759134Y83925D01*
X758926Y84217D01*
X758884Y84508D01*
X758967Y84800D01*
X759176Y85008D01*
G01X775700Y72200D02*
X779700D01*
Y79600D01*
G01X797134Y88850D02*
X797092Y88517D01*
X796926Y88225D01*
X796676Y87975D01*
X796384Y87808D01*
X796051Y87725D01*
X795717D01*
X795384Y87808D01*
X795092Y87975D01*
X794842Y88225D01*
X794676Y88517D01*
X794634Y88850D01*
X794676Y89183D01*
X794842Y89475D01*
X795092Y89725D01*
X795384Y89892D01*
X795717Y89975D01*
X796051D01*
X796384Y89892D01*
X796676Y89725D01*
X796926Y89475D01*
X797092Y89183D01*
X797134Y88850D01*
G01X796467Y89183D02*
X797134Y89683D01*
G01X795051Y91158D02*
X794801Y91408D01*
X794676Y91700D01*
X794634Y92033D01*
X794717Y92450D01*
X794926Y92742D01*
X795176Y92825D01*
X795426Y92783D01*
X795634Y92617D01*
X796051Y91783D01*
X796342Y91408D01*
X796759Y91158D01*
X797134Y91075D01*
Y92825D01*
G01Y95550D02*
X794634D01*
X796426Y94008D01*
Y96092D01*
G01X780250Y96800D02*
Y82800D01*
G01X793250Y96800D02*
X780250D01*
G01X793250Y82800D02*
Y96800D01*
G01X780250Y82800D02*
X793250D01*
G01X799034Y71400D02*
X798992Y71067D01*
X798826Y70775D01*
X798576Y70525D01*
X798284Y70358D01*
X797951Y70275D01*
X797617D01*
X797284Y70358D01*
X796992Y70525D01*
X796742Y70775D01*
X796576Y71067D01*
X796534Y71400D01*
X796576Y71733D01*
X796742Y72025D01*
X796992Y72275D01*
X797284Y72442D01*
X797617Y72525D01*
X797951D01*
X798284Y72442D01*
X798576Y72275D01*
X798826Y72025D01*
X798992Y71733D01*
X799034Y71400D01*
G01X798367Y71733D02*
X799034Y72233D01*
G01X796951Y73708D02*
X796701Y73958D01*
X796576Y74250D01*
X796534Y74583D01*
X796617Y75000D01*
X796826Y75292D01*
X797076Y75375D01*
X797326Y75333D01*
X797534Y75167D01*
X797951Y74333D01*
X798242Y73958D01*
X798659Y73708D01*
X799034Y73625D01*
Y75375D01*
G01Y77600D02*
X796534D01*
X797034Y77100D01*
G01X799034D02*
Y78100D01*
G01X793500Y77500D02*
X780500D01*
G01X798084Y111200D02*
X798042Y110867D01*
X797876Y110575D01*
X797626Y110325D01*
X797334Y110158D01*
X797001Y110075D01*
X796667D01*
X796334Y110158D01*
X796042Y110325D01*
X795792Y110575D01*
X795626Y110867D01*
X795584Y111200D01*
X795626Y111533D01*
X795792Y111825D01*
X796042Y112075D01*
X796334Y112242D01*
X796667Y112325D01*
X797001D01*
X797334Y112242D01*
X797626Y112075D01*
X797876Y111825D01*
X798042Y111533D01*
X798084Y111200D01*
G01X797417Y111533D02*
X798084Y112033D01*
G01X796001Y113508D02*
X795751Y113758D01*
X795626Y114050D01*
X795584Y114383D01*
X795667Y114800D01*
X795876Y115092D01*
X796126Y115175D01*
X796376Y115133D01*
X796584Y114967D01*
X797001Y114133D01*
X797292Y113758D01*
X797709Y113508D01*
X798084Y113425D01*
Y115175D01*
G01Y117317D02*
X797542Y117400D01*
X797084Y117525D01*
X796667Y117692D01*
X796209Y117900D01*
X795584Y118233D01*
Y116567D01*
G01X779100Y120850D02*
Y106850D01*
G01X792100Y120850D02*
X779100D01*
G01X792100Y106850D02*
Y120850D01*
G01X779100Y106850D02*
X792100D01*
G01X754534Y97183D02*
X756326D01*
X756701Y97350D01*
X756951Y97683D01*
X757034Y98100D01*
X756951Y98517D01*
X756701Y98850D01*
X756326Y99017D01*
X754534D01*
G01X757034Y101700D02*
X754534D01*
X756326Y100158D01*
Y102242D01*
G01X757034Y104300D02*
X756992Y104592D01*
X756867Y104925D01*
X756659Y105133D01*
X756367Y105217D01*
X756076Y105133D01*
X755826Y104883D01*
X755701Y104508D01*
Y104092D01*
X755617Y103842D01*
X755409Y103633D01*
X755117Y103550D01*
X754826Y103675D01*
X754617Y103967D01*
X754534Y104300D01*
X754617Y104633D01*
X754826Y104925D01*
X755117Y105050D01*
X755409Y104967D01*
X755617Y104758D01*
X755701Y104508D01*
Y104092D01*
X755826Y103717D01*
X756076Y103467D01*
X756367Y103383D01*
X756659Y103467D01*
X756867Y103675D01*
X756992Y104008D01*
X757034Y104300D01*
G01X770300Y109700D02*
Y96300D01*
G01X760300Y109700D02*
X770300D01*
G01X760300Y96300D02*
Y109700D01*
G01X770300Y96300D02*
X760300D01*
G01X754534Y73933D02*
X756326D01*
X756701Y74100D01*
X756951Y74433D01*
X757034Y74850D01*
X756951Y75267D01*
X756701Y75600D01*
X756326Y75767D01*
X754534D01*
G01X757034Y78450D02*
X754534D01*
X756326Y76908D01*
Y78992D01*
G01X756742Y80342D02*
X756951Y80633D01*
X757034Y80967D01*
X756951Y81300D01*
X756701Y81592D01*
X756326Y81800D01*
X755951Y81883D01*
X755492D01*
X755117Y81800D01*
X754784Y81592D01*
X754617Y81342D01*
X754534Y81050D01*
X754617Y80717D01*
X754784Y80467D01*
X755034Y80300D01*
X755367Y80217D01*
X755659Y80300D01*
X755951Y80508D01*
X756117Y80758D01*
X756159Y81050D01*
X756076Y81383D01*
X755867Y81633D01*
X755492Y81883D01*
G01X764500Y68800D02*
Y82200D01*
G01X774500Y68800D02*
X764500D01*
G01X774500Y82200D02*
Y68800D01*
G01X764500Y82200D02*
X774500D01*
G01X754267Y134292D02*
X754017Y134417D01*
X753725Y134500D01*
X753392D01*
X753017Y134375D01*
X752725Y134167D01*
X752517Y133917D01*
X752350Y133500D01*
X752308Y133125D01*
X752392Y132750D01*
X752517Y132500D01*
X752767Y132250D01*
X753058Y132083D01*
X753350Y132000D01*
X753642D01*
X753933Y132083D01*
X754183Y132208D01*
X754392Y132375D01*
G01X755533D02*
X755783Y132167D01*
X756075Y132042D01*
X756450Y132000D01*
X756825Y132083D01*
X757117Y132250D01*
X757325Y132542D01*
X757367Y132875D01*
X757283Y133208D01*
X757075Y133417D01*
X756783Y133583D01*
X756492Y133625D01*
X756200Y133583D01*
X755825Y133417D01*
X755950Y134500D01*
X757075D01*
G01X758758Y134083D02*
X759008Y134333D01*
X759300Y134458D01*
X759633Y134500D01*
X760050Y134417D01*
X760342Y134208D01*
X760425Y133958D01*
X760383Y133708D01*
X760217Y133500D01*
X759383Y133083D01*
X759008Y132792D01*
X758758Y132375D01*
X758675Y132000D01*
X760425D01*
G01X761858Y133042D02*
X762150Y133333D01*
X762400Y133500D01*
X762733Y133583D01*
X763025Y133500D01*
X763233Y133333D01*
X763400Y133083D01*
X763442Y132792D01*
X763400Y132542D01*
X763233Y132292D01*
X762983Y132083D01*
X762692Y132000D01*
X762358Y132083D01*
X762067Y132333D01*
X761900Y132708D01*
X761858Y133125D01*
X761942Y133667D01*
X762067Y133958D01*
X762275Y134250D01*
X762567Y134458D01*
X762858Y134500D01*
X763150Y134417D01*
X763358Y134208D01*
G01X764480Y123860D02*
X769980D01*
Y115860D01*
X764380D01*
G01X752380Y123860D02*
X757880D01*
G01X752380D02*
Y115860D01*
X757880D01*
G01X798600Y186400D02*
X802600D01*
Y193800D01*
G01X799434Y146717D02*
X796934D01*
Y147758D01*
X797059Y148092D01*
X797226Y148300D01*
X797559Y148383D01*
X797892Y148300D01*
X798101Y148050D01*
X798226Y147758D01*
Y146717D01*
G01Y147758D02*
X799434Y148383D01*
G01X798392Y149858D02*
X798101Y150150D01*
X797934Y150400D01*
X797851Y150733D01*
X797934Y151025D01*
X798101Y151233D01*
X798351Y151400D01*
X798642Y151442D01*
X798892Y151400D01*
X799142Y151233D01*
X799351Y150983D01*
X799434Y150692D01*
X799351Y150358D01*
X799101Y150067D01*
X798726Y149900D01*
X798309Y149858D01*
X797767Y149942D01*
X797476Y150067D01*
X797184Y150275D01*
X796976Y150567D01*
X796934Y150858D01*
X797017Y151150D01*
X797226Y151358D01*
G01X798934Y152833D02*
X799226Y153083D01*
X799392Y153417D01*
X799434Y153792D01*
X799392Y154125D01*
X799184Y154458D01*
X798934Y154667D01*
X798684Y154708D01*
X798392Y154625D01*
X798184Y154333D01*
X798101Y154042D01*
Y153667D01*
G01Y154042D02*
X797976Y154292D01*
X797767Y154500D01*
X797517Y154583D01*
X797267Y154500D01*
X797059Y154292D01*
X796934Y153917D01*
X796976Y153542D01*
X797142Y153167D01*
G01X797351Y156058D02*
X797101Y156308D01*
X796976Y156600D01*
X796934Y156933D01*
X797017Y157350D01*
X797226Y157642D01*
X797476Y157725D01*
X797726Y157683D01*
X797934Y157517D01*
X798351Y156683D01*
X798642Y156308D01*
X799059Y156058D01*
X799434Y155975D01*
Y157725D01*
G01X793600Y186400D02*
X797600D01*
Y193800D01*
G01X794934Y146717D02*
X792434D01*
Y147758D01*
X792559Y148092D01*
X792726Y148300D01*
X793059Y148383D01*
X793392Y148300D01*
X793601Y148050D01*
X793726Y147758D01*
Y146717D01*
G01Y147758D02*
X794934Y148383D01*
G01X793892Y149858D02*
X793601Y150150D01*
X793434Y150400D01*
X793351Y150733D01*
X793434Y151025D01*
X793601Y151233D01*
X793851Y151400D01*
X794142Y151442D01*
X794392Y151400D01*
X794642Y151233D01*
X794851Y150983D01*
X794934Y150692D01*
X794851Y150358D01*
X794601Y150067D01*
X794226Y149900D01*
X793809Y149858D01*
X793267Y149942D01*
X792976Y150067D01*
X792684Y150275D01*
X792476Y150567D01*
X792434Y150858D01*
X792517Y151150D01*
X792726Y151358D01*
G01X794434Y152833D02*
X794726Y153083D01*
X794892Y153417D01*
X794934Y153792D01*
X794892Y154125D01*
X794684Y154458D01*
X794434Y154667D01*
X794184Y154708D01*
X793892Y154625D01*
X793684Y154333D01*
X793601Y154042D01*
Y153667D01*
G01Y154042D02*
X793476Y154292D01*
X793267Y154500D01*
X793017Y154583D01*
X792767Y154500D01*
X792559Y154292D01*
X792434Y153917D01*
X792476Y153542D01*
X792642Y153167D01*
G01X794934Y157350D02*
X792434D01*
X794226Y155808D01*
Y157892D01*
G01X788600Y186400D02*
X792600D01*
Y193800D01*
G01X762334Y149517D02*
X759834D01*
Y150558D01*
X759959Y150892D01*
X760126Y151100D01*
X760459Y151183D01*
X760792Y151100D01*
X761001Y150850D01*
X761126Y150558D01*
Y149517D01*
G01Y150558D02*
X762334Y151183D01*
G01X761292Y152658D02*
X761001Y152950D01*
X760834Y153200D01*
X760751Y153533D01*
X760834Y153825D01*
X761001Y154033D01*
X761251Y154200D01*
X761542Y154242D01*
X761792Y154200D01*
X762042Y154033D01*
X762251Y153783D01*
X762334Y153492D01*
X762251Y153158D01*
X762001Y152867D01*
X761626Y152700D01*
X761209Y152658D01*
X760667Y152742D01*
X760376Y152867D01*
X760084Y153075D01*
X759876Y153367D01*
X759834Y153658D01*
X759917Y153950D01*
X760126Y154158D01*
G01X762334Y157050D02*
X759834D01*
X761626Y155508D01*
Y157592D01*
G01X761959Y158733D02*
X762167Y158983D01*
X762292Y159275D01*
X762334Y159650D01*
X762251Y160025D01*
X762084Y160317D01*
X761792Y160525D01*
X761459Y160567D01*
X761126Y160483D01*
X760917Y160275D01*
X760751Y159983D01*
X760709Y159692D01*
X760751Y159400D01*
X760917Y159025D01*
X759834Y159150D01*
Y160275D01*
G01X760200Y186800D02*
X764200D01*
Y194200D01*
G01X745334Y149517D02*
X742834D01*
Y150558D01*
X742959Y150892D01*
X743126Y151100D01*
X743459Y151183D01*
X743792Y151100D01*
X744001Y150850D01*
X744126Y150558D01*
Y149517D01*
G01Y150558D02*
X745334Y151183D01*
G01X744292Y152658D02*
X744001Y152950D01*
X743834Y153200D01*
X743751Y153533D01*
X743834Y153825D01*
X744001Y154033D01*
X744251Y154200D01*
X744542Y154242D01*
X744792Y154200D01*
X745042Y154033D01*
X745251Y153783D01*
X745334Y153492D01*
X745251Y153158D01*
X745001Y152867D01*
X744626Y152700D01*
X744209Y152658D01*
X743667Y152742D01*
X743376Y152867D01*
X743084Y153075D01*
X742876Y153367D01*
X742834Y153658D01*
X742917Y153950D01*
X743126Y154158D01*
G01X745334Y157050D02*
X742834D01*
X744626Y155508D01*
Y157592D01*
G01X744292Y158858D02*
X744001Y159150D01*
X743834Y159400D01*
X743751Y159733D01*
X743834Y160025D01*
X744001Y160233D01*
X744251Y160400D01*
X744542Y160442D01*
X744792Y160400D01*
X745042Y160233D01*
X745251Y159983D01*
X745334Y159692D01*
X745251Y159358D01*
X745001Y159067D01*
X744626Y158900D01*
X744209Y158858D01*
X743667Y158942D01*
X743376Y159067D01*
X743084Y159275D01*
X742876Y159567D01*
X742834Y159858D01*
X742917Y160150D01*
X743126Y160358D01*
G01X743700Y187000D02*
X747700D01*
Y194400D01*
G01X741334Y149317D02*
X738834D01*
Y150358D01*
X738959Y150692D01*
X739126Y150900D01*
X739459Y150983D01*
X739792Y150900D01*
X740001Y150650D01*
X740126Y150358D01*
Y149317D01*
G01Y150358D02*
X741334Y150983D01*
G01X740292Y152458D02*
X740001Y152750D01*
X739834Y153000D01*
X739751Y153333D01*
X739834Y153625D01*
X740001Y153833D01*
X740251Y154000D01*
X740542Y154042D01*
X740792Y154000D01*
X741042Y153833D01*
X741251Y153583D01*
X741334Y153292D01*
X741251Y152958D01*
X741001Y152667D01*
X740626Y152500D01*
X740209Y152458D01*
X739667Y152542D01*
X739376Y152667D01*
X739084Y152875D01*
X738876Y153167D01*
X738834Y153458D01*
X738917Y153750D01*
X739126Y153958D01*
G01X740959Y155433D02*
X741167Y155683D01*
X741292Y155975D01*
X741334Y156350D01*
X741251Y156725D01*
X741084Y157017D01*
X740792Y157225D01*
X740459Y157267D01*
X740126Y157183D01*
X739917Y156975D01*
X739751Y156683D01*
X739709Y156392D01*
X739751Y156100D01*
X739917Y155725D01*
X738834Y155850D01*
Y156975D01*
G01X741334Y159367D02*
X740792Y159450D01*
X740334Y159575D01*
X739917Y159742D01*
X739459Y159950D01*
X738834Y160283D01*
Y158617D01*
G01X743300Y194200D02*
X739300D01*
Y186800D01*
G01X737334Y149517D02*
X734834D01*
Y150558D01*
X734959Y150892D01*
X735126Y151100D01*
X735459Y151183D01*
X735792Y151100D01*
X736001Y150850D01*
X736126Y150558D01*
Y149517D01*
G01Y150558D02*
X737334Y151183D01*
G01X736292Y152658D02*
X736001Y152950D01*
X735834Y153200D01*
X735751Y153533D01*
X735834Y153825D01*
X736001Y154033D01*
X736251Y154200D01*
X736542Y154242D01*
X736792Y154200D01*
X737042Y154033D01*
X737251Y153783D01*
X737334Y153492D01*
X737251Y153158D01*
X737001Y152867D01*
X736626Y152700D01*
X736209Y152658D01*
X735667Y152742D01*
X735376Y152867D01*
X735084Y153075D01*
X734876Y153367D01*
X734834Y153658D01*
X734917Y153950D01*
X735126Y154158D01*
G01X736292Y155758D02*
X736001Y156050D01*
X735834Y156300D01*
X735751Y156633D01*
X735834Y156925D01*
X736001Y157133D01*
X736251Y157300D01*
X736542Y157342D01*
X736792Y157300D01*
X737042Y157133D01*
X737251Y156883D01*
X737334Y156592D01*
X737251Y156258D01*
X737001Y155967D01*
X736626Y155800D01*
X736209Y155758D01*
X735667Y155842D01*
X735376Y155967D01*
X735084Y156175D01*
X734876Y156467D01*
X734834Y156758D01*
X734917Y157050D01*
X735126Y157258D01*
G01X736959Y158733D02*
X737167Y158983D01*
X737292Y159275D01*
X737334Y159650D01*
X737251Y160025D01*
X737084Y160317D01*
X736792Y160525D01*
X736459Y160567D01*
X736126Y160483D01*
X735917Y160275D01*
X735751Y159983D01*
X735709Y159692D01*
X735751Y159400D01*
X735917Y159025D01*
X734834Y159150D01*
Y160275D01*
G01X735000Y187000D02*
X739000D01*
Y194400D01*
G01X778334Y146017D02*
X775834D01*
Y147058D01*
X775959Y147392D01*
X776126Y147600D01*
X776459Y147683D01*
X776792Y147600D01*
X777001Y147350D01*
X777126Y147058D01*
Y146017D01*
G01Y147058D02*
X778334Y147683D01*
G01X777292Y149158D02*
X777001Y149450D01*
X776834Y149700D01*
X776751Y150033D01*
X776834Y150325D01*
X777001Y150533D01*
X777251Y150700D01*
X777542Y150742D01*
X777792Y150700D01*
X778042Y150533D01*
X778251Y150283D01*
X778334Y149992D01*
X778251Y149658D01*
X778001Y149367D01*
X777626Y149200D01*
X777209Y149158D01*
X776667Y149242D01*
X776376Y149367D01*
X776084Y149575D01*
X775876Y149867D01*
X775834Y150158D01*
X775917Y150450D01*
X776126Y150658D01*
G01X777834Y152133D02*
X778126Y152383D01*
X778292Y152717D01*
X778334Y153092D01*
X778292Y153425D01*
X778084Y153758D01*
X777834Y153967D01*
X777584Y154008D01*
X777292Y153925D01*
X777084Y153633D01*
X777001Y153342D01*
Y152967D01*
G01Y153342D02*
X776876Y153592D01*
X776667Y153800D01*
X776417Y153883D01*
X776167Y153800D01*
X775959Y153592D01*
X775834Y153217D01*
X775876Y152842D01*
X776042Y152467D01*
G01X777292Y155358D02*
X777001Y155650D01*
X776834Y155900D01*
X776751Y156233D01*
X776834Y156525D01*
X777001Y156733D01*
X777251Y156900D01*
X777542Y156942D01*
X777792Y156900D01*
X778042Y156733D01*
X778251Y156483D01*
X778334Y156192D01*
X778251Y155858D01*
X778001Y155567D01*
X777626Y155400D01*
X777209Y155358D01*
X776667Y155442D01*
X776376Y155567D01*
X776084Y155775D01*
X775876Y156067D01*
X775834Y156358D01*
X775917Y156650D01*
X776126Y156858D01*
G01X773500Y186300D02*
X777500D01*
Y193700D01*
G01X757834Y149117D02*
X755334D01*
Y150158D01*
X755459Y150492D01*
X755626Y150700D01*
X755959Y150783D01*
X756292Y150700D01*
X756501Y150450D01*
X756626Y150158D01*
Y149117D01*
G01Y150158D02*
X757834Y150783D01*
G01X756792Y152258D02*
X756501Y152550D01*
X756334Y152800D01*
X756251Y153133D01*
X756334Y153425D01*
X756501Y153633D01*
X756751Y153800D01*
X757042Y153842D01*
X757292Y153800D01*
X757542Y153633D01*
X757751Y153383D01*
X757834Y153092D01*
X757751Y152758D01*
X757501Y152467D01*
X757126Y152300D01*
X756709Y152258D01*
X756167Y152342D01*
X755876Y152467D01*
X755584Y152675D01*
X755376Y152967D01*
X755334Y153258D01*
X755417Y153550D01*
X755626Y153758D01*
G01X757459Y155233D02*
X757667Y155483D01*
X757792Y155775D01*
X757834Y156150D01*
X757751Y156525D01*
X757584Y156817D01*
X757292Y157025D01*
X756959Y157067D01*
X756626Y156983D01*
X756417Y156775D01*
X756251Y156483D01*
X756209Y156192D01*
X756251Y155900D01*
X756417Y155525D01*
X755334Y155650D01*
Y156775D01*
G01X757834Y159250D02*
X757792Y159542D01*
X757667Y159875D01*
X757459Y160083D01*
X757167Y160167D01*
X756876Y160083D01*
X756626Y159833D01*
X756501Y159458D01*
Y159042D01*
X756417Y158792D01*
X756209Y158583D01*
X755917Y158500D01*
X755626Y158625D01*
X755417Y158917D01*
X755334Y159250D01*
X755417Y159583D01*
X755626Y159875D01*
X755917Y160000D01*
X756209Y159917D01*
X756417Y159708D01*
X756501Y159458D01*
Y159042D01*
X756626Y158667D01*
X756876Y158417D01*
X757167Y158333D01*
X757459Y158417D01*
X757667Y158625D01*
X757792Y158958D01*
X757834Y159250D01*
G01X760100Y193800D02*
X756100D01*
Y186400D01*
G01X753434Y149217D02*
X750934D01*
Y150258D01*
X751059Y150592D01*
X751226Y150800D01*
X751559Y150883D01*
X751892Y150800D01*
X752101Y150550D01*
X752226Y150258D01*
Y149217D01*
G01Y150258D02*
X753434Y150883D01*
G01X752392Y152358D02*
X752101Y152650D01*
X751934Y152900D01*
X751851Y153233D01*
X751934Y153525D01*
X752101Y153733D01*
X752351Y153900D01*
X752642Y153942D01*
X752892Y153900D01*
X753142Y153733D01*
X753351Y153483D01*
X753434Y153192D01*
X753351Y152858D01*
X753101Y152567D01*
X752726Y152400D01*
X752309Y152358D01*
X751767Y152442D01*
X751476Y152567D01*
X751184Y152775D01*
X750976Y153067D01*
X750934Y153358D01*
X751017Y153650D01*
X751226Y153858D01*
G01X753059Y155333D02*
X753267Y155583D01*
X753392Y155875D01*
X753434Y156250D01*
X753351Y156625D01*
X753184Y156917D01*
X752892Y157125D01*
X752559Y157167D01*
X752226Y157083D01*
X752017Y156875D01*
X751851Y156583D01*
X751809Y156292D01*
X751851Y156000D01*
X752017Y155625D01*
X750934Y155750D01*
Y156875D01*
G01X751351Y158558D02*
X751101Y158808D01*
X750976Y159100D01*
X750934Y159433D01*
X751017Y159850D01*
X751226Y160142D01*
X751476Y160225D01*
X751726Y160183D01*
X751934Y160017D01*
X752351Y159183D01*
X752642Y158808D01*
X753059Y158558D01*
X753434Y158475D01*
Y160225D01*
G01X756000Y194200D02*
X752000D01*
Y186800D01*
G01X749434Y149217D02*
X746934D01*
Y150258D01*
X747059Y150592D01*
X747226Y150800D01*
X747559Y150883D01*
X747892Y150800D01*
X748101Y150550D01*
X748226Y150258D01*
Y149217D01*
G01Y150258D02*
X749434Y150883D01*
G01X748392Y152358D02*
X748101Y152650D01*
X747934Y152900D01*
X747851Y153233D01*
X747934Y153525D01*
X748101Y153733D01*
X748351Y153900D01*
X748642Y153942D01*
X748892Y153900D01*
X749142Y153733D01*
X749351Y153483D01*
X749434Y153192D01*
X749351Y152858D01*
X749101Y152567D01*
X748726Y152400D01*
X748309Y152358D01*
X747767Y152442D01*
X747476Y152567D01*
X747184Y152775D01*
X746976Y153067D01*
X746934Y153358D01*
X747017Y153650D01*
X747226Y153858D01*
G01X749434Y156750D02*
X746934D01*
X748726Y155208D01*
Y157292D01*
G01X746934Y159350D02*
X747017Y159017D01*
X747226Y158767D01*
X747476Y158600D01*
X747809Y158475D01*
X748184Y158433D01*
X748559Y158475D01*
X748892Y158600D01*
X749142Y158767D01*
X749351Y159017D01*
X749434Y159350D01*
X749351Y159683D01*
X749142Y159933D01*
X748892Y160100D01*
X748559Y160225D01*
X748184Y160267D01*
X747809Y160225D01*
X747476Y160100D01*
X747226Y159933D01*
X747017Y159683D01*
X746934Y159350D01*
G01X747900Y186700D02*
X751900D01*
Y194100D01*
G01X790434Y146717D02*
X787934D01*
Y147758D01*
X788059Y148092D01*
X788226Y148300D01*
X788559Y148383D01*
X788892Y148300D01*
X789101Y148050D01*
X789226Y147758D01*
Y146717D01*
G01Y147758D02*
X790434Y148383D01*
G01X789392Y149858D02*
X789101Y150150D01*
X788934Y150400D01*
X788851Y150733D01*
X788934Y151025D01*
X789101Y151233D01*
X789351Y151400D01*
X789642Y151442D01*
X789892Y151400D01*
X790142Y151233D01*
X790351Y150983D01*
X790434Y150692D01*
X790351Y150358D01*
X790101Y150067D01*
X789726Y149900D01*
X789309Y149858D01*
X788767Y149942D01*
X788476Y150067D01*
X788184Y150275D01*
X787976Y150567D01*
X787934Y150858D01*
X788017Y151150D01*
X788226Y151358D01*
G01X789934Y152833D02*
X790226Y153083D01*
X790392Y153417D01*
X790434Y153792D01*
X790392Y154125D01*
X790184Y154458D01*
X789934Y154667D01*
X789684Y154708D01*
X789392Y154625D01*
X789184Y154333D01*
X789101Y154042D01*
Y153667D01*
G01Y154042D02*
X788976Y154292D01*
X788767Y154500D01*
X788517Y154583D01*
X788267Y154500D01*
X788059Y154292D01*
X787934Y153917D01*
X787976Y153542D01*
X788142Y153167D01*
G01X789934Y155933D02*
X790226Y156183D01*
X790392Y156517D01*
X790434Y156892D01*
X790392Y157225D01*
X790184Y157558D01*
X789934Y157767D01*
X789684Y157808D01*
X789392Y157725D01*
X789184Y157433D01*
X789101Y157142D01*
Y156767D01*
G01Y157142D02*
X788976Y157392D01*
X788767Y157600D01*
X788517Y157683D01*
X788267Y157600D01*
X788059Y157392D01*
X787934Y157017D01*
X787976Y156642D01*
X788142Y156267D01*
G01X783600Y186400D02*
X787600D01*
Y193800D01*
G01X753067Y136000D02*
Y138500D01*
X754108D01*
X754442Y138375D01*
X754650Y138208D01*
X754733Y137875D01*
X754650Y137542D01*
X754400Y137333D01*
X754108Y137208D01*
X753067D01*
G01X754108D02*
X754733Y136000D01*
G01X756083Y136500D02*
X756333Y136208D01*
X756667Y136042D01*
X757042Y136000D01*
X757375Y136042D01*
X757708Y136250D01*
X757917Y136500D01*
X757958Y136750D01*
X757875Y137042D01*
X757583Y137250D01*
X757292Y137333D01*
X756917D01*
G01X757292D02*
X757542Y137458D01*
X757750Y137667D01*
X757833Y137917D01*
X757750Y138167D01*
X757542Y138375D01*
X757167Y138500D01*
X756792Y138458D01*
X756417Y138292D01*
G01X759392Y136292D02*
X759683Y136083D01*
X760017Y136000D01*
X760350Y136083D01*
X760642Y136333D01*
X760850Y136708D01*
X760933Y137083D01*
Y137542D01*
X760850Y137917D01*
X760642Y138250D01*
X760392Y138417D01*
X760100Y138500D01*
X759767Y138417D01*
X759517Y138250D01*
X759350Y138000D01*
X759267Y137667D01*
X759350Y137375D01*
X759558Y137083D01*
X759808Y136917D01*
X760100Y136875D01*
X760433Y136958D01*
X760683Y137167D01*
X760933Y137542D01*
G01X789733Y162800D02*
X792233D01*
G01X789733Y161842D02*
Y163758D01*
G01X792233Y165067D02*
X789733D01*
Y166067D01*
X789858Y166400D01*
X790150Y166650D01*
X790483Y166733D01*
X790816Y166650D01*
X791066Y166442D01*
X791191Y166067D01*
Y165067D01*
G01X792233Y169000D02*
X789733D01*
X790233Y168500D01*
G01X792233D02*
Y169500D01*
G01X791733Y171183D02*
X792025Y171433D01*
X792191Y171767D01*
X792233Y172142D01*
X792191Y172475D01*
X791983Y172808D01*
X791733Y173017D01*
X791483Y173058D01*
X791191Y172975D01*
X790983Y172683D01*
X790900Y172392D01*
Y172017D01*
G01Y172392D02*
X790775Y172642D01*
X790566Y172850D01*
X790316Y172933D01*
X790066Y172850D01*
X789858Y172642D01*
X789733Y172267D01*
X789775Y171892D01*
X789941Y171517D01*
G01X792233Y175117D02*
X791691Y175200D01*
X791233Y175325D01*
X790816Y175492D01*
X790358Y175700D01*
X789733Y176033D01*
Y174367D01*
G01X794534Y162800D02*
X797034D01*
G01X794534Y161842D02*
Y163758D01*
G01X797034Y165067D02*
X794534D01*
Y166067D01*
X794659Y166400D01*
X794951Y166650D01*
X795284Y166733D01*
X795617Y166650D01*
X795867Y166442D01*
X795992Y166067D01*
Y165067D01*
G01X797034Y169000D02*
X794534D01*
X795034Y168500D01*
G01X797034D02*
Y169500D01*
G01Y172600D02*
X794534D01*
X796326Y171058D01*
Y173142D01*
G01X794534Y175200D02*
X794617Y174867D01*
X794826Y174617D01*
X795076Y174450D01*
X795409Y174325D01*
X795784Y174283D01*
X796159Y174325D01*
X796492Y174450D01*
X796742Y174617D01*
X796951Y174867D01*
X797034Y175200D01*
X796951Y175533D01*
X796742Y175783D01*
X796492Y175950D01*
X796159Y176075D01*
X795784Y176117D01*
X795409Y176075D01*
X795076Y175950D01*
X794826Y175783D01*
X794617Y175533D01*
X794534Y175200D01*
G01X775634Y161300D02*
X778134D01*
G01X775634Y160342D02*
Y162258D01*
G01X778134Y163567D02*
X775634D01*
Y164567D01*
X775759Y164900D01*
X776051Y165150D01*
X776384Y165233D01*
X776717Y165150D01*
X776967Y164942D01*
X777092Y164567D01*
Y163567D01*
G01X778134Y167500D02*
X775634D01*
X776134Y167000D01*
G01X778134D02*
Y168000D01*
G01X777634Y169683D02*
X777926Y169933D01*
X778092Y170267D01*
X778134Y170642D01*
X778092Y170975D01*
X777884Y171308D01*
X777634Y171517D01*
X777384Y171558D01*
X777092Y171475D01*
X776884Y171183D01*
X776801Y170892D01*
Y170517D01*
G01Y170892D02*
X776676Y171142D01*
X776467Y171350D01*
X776217Y171433D01*
X775967Y171350D01*
X775759Y171142D01*
X775634Y170767D01*
X775676Y170392D01*
X775842Y170017D01*
G01X777759Y172783D02*
X777967Y173033D01*
X778092Y173325D01*
X778134Y173700D01*
X778051Y174075D01*
X777884Y174367D01*
X777592Y174575D01*
X777259Y174617D01*
X776926Y174533D01*
X776717Y174325D01*
X776551Y174033D01*
X776509Y173742D01*
X776551Y173450D01*
X776717Y173075D01*
X775634Y173200D01*
Y174325D01*
G01X780634Y155600D02*
X783134D01*
G01X780634Y154642D02*
Y156558D01*
G01X783134Y157867D02*
X780634D01*
Y158867D01*
X780759Y159200D01*
X781051Y159450D01*
X781384Y159533D01*
X781717Y159450D01*
X781967Y159242D01*
X782092Y158867D01*
Y157867D01*
G01X783134Y161800D02*
X780634D01*
X781134Y161300D01*
G01X783134D02*
Y162300D01*
G01X782634Y163983D02*
X782926Y164233D01*
X783092Y164567D01*
X783134Y164942D01*
X783092Y165275D01*
X782884Y165608D01*
X782634Y165817D01*
X782384Y165858D01*
X782092Y165775D01*
X781884Y165483D01*
X781801Y165192D01*
Y164817D01*
G01Y165192D02*
X781676Y165442D01*
X781467Y165650D01*
X781217Y165733D01*
X780967Y165650D01*
X780759Y165442D01*
X780634Y165067D01*
X780676Y164692D01*
X780842Y164317D01*
G01X783134Y168000D02*
X783092Y168292D01*
X782967Y168625D01*
X782759Y168833D01*
X782467Y168917D01*
X782176Y168833D01*
X781926Y168583D01*
X781801Y168208D01*
Y167792D01*
X781717Y167542D01*
X781509Y167333D01*
X781217Y167250D01*
X780926Y167375D01*
X780717Y167667D01*
X780634Y168000D01*
X780717Y168333D01*
X780926Y168625D01*
X781217Y168750D01*
X781509Y168667D01*
X781717Y168458D01*
X781801Y168208D01*
Y167792D01*
X781926Y167417D01*
X782176Y167167D01*
X782467Y167083D01*
X782759Y167167D01*
X782967Y167375D01*
X783092Y167708D01*
X783134Y168000D01*
G01X784734Y162900D02*
X787234D01*
G01X784734Y161942D02*
Y163858D01*
G01X787234Y165167D02*
X784734D01*
Y166167D01*
X784859Y166500D01*
X785151Y166750D01*
X785484Y166833D01*
X785817Y166750D01*
X786067Y166542D01*
X786192Y166167D01*
Y165167D01*
G01X787234Y169100D02*
X784734D01*
X785234Y168600D01*
G01X787234D02*
Y169600D01*
G01X786734Y171283D02*
X787026Y171533D01*
X787192Y171867D01*
X787234Y172242D01*
X787192Y172575D01*
X786984Y172908D01*
X786734Y173117D01*
X786484Y173158D01*
X786192Y173075D01*
X785984Y172783D01*
X785901Y172492D01*
Y172117D01*
G01Y172492D02*
X785776Y172742D01*
X785567Y172950D01*
X785317Y173033D01*
X785067Y172950D01*
X784859Y172742D01*
X784734Y172367D01*
X784776Y171992D01*
X784942Y171617D01*
G01X786942Y174592D02*
X787151Y174883D01*
X787234Y175217D01*
X787151Y175550D01*
X786901Y175842D01*
X786526Y176050D01*
X786151Y176133D01*
X785692D01*
X785317Y176050D01*
X784984Y175842D01*
X784817Y175592D01*
X784734Y175300D01*
X784817Y174967D01*
X784984Y174717D01*
X785234Y174550D01*
X785567Y174467D01*
X785859Y174550D01*
X786151Y174758D01*
X786317Y175008D01*
X786359Y175300D01*
X786276Y175633D01*
X786067Y175883D01*
X785692Y176133D01*
G01X770234Y163200D02*
X772734D01*
G01X770234Y162242D02*
Y164158D01*
G01X772734Y165467D02*
X770234D01*
Y166467D01*
X770359Y166800D01*
X770651Y167050D01*
X770984Y167133D01*
X771317Y167050D01*
X771567Y166842D01*
X771692Y166467D01*
Y165467D01*
G01X772734Y169400D02*
X770234D01*
X770734Y168900D01*
G01X772734D02*
Y169900D01*
G01Y173000D02*
X770234D01*
X772026Y171458D01*
Y173542D01*
G01X772234Y174683D02*
X772526Y174933D01*
X772692Y175267D01*
X772734Y175642D01*
X772692Y175975D01*
X772484Y176308D01*
X772234Y176517D01*
X771984Y176558D01*
X771692Y176475D01*
X771484Y176183D01*
X771401Y175892D01*
Y175517D01*
G01Y175892D02*
X771276Y176142D01*
X771067Y176350D01*
X770817Y176433D01*
X770567Y176350D01*
X770359Y176142D01*
X770234Y175767D01*
X770276Y175392D01*
X770442Y175017D01*
G01X757834Y163800D02*
X760334D01*
G01X757834Y162842D02*
Y164758D01*
G01X760334Y166067D02*
X757834D01*
Y167067D01*
X757959Y167400D01*
X758251Y167650D01*
X758584Y167733D01*
X758917Y167650D01*
X759167Y167442D01*
X759292Y167067D01*
Y166067D01*
G01X760334Y170000D02*
X757834D01*
X758334Y169500D01*
G01X760334D02*
Y170500D01*
G01X759959Y172183D02*
X760167Y172433D01*
X760292Y172725D01*
X760334Y173100D01*
X760251Y173475D01*
X760084Y173767D01*
X759792Y173975D01*
X759459Y174017D01*
X759126Y173933D01*
X758917Y173725D01*
X758751Y173433D01*
X758709Y173142D01*
X758751Y172850D01*
X758917Y172475D01*
X757834Y172600D01*
Y173725D01*
G01X760334Y176700D02*
X757834D01*
X759626Y175158D01*
Y177242D01*
G01X738000Y163800D02*
X740500D01*
G01X738000Y162842D02*
Y164758D01*
G01X740500Y166067D02*
X738000D01*
Y167067D01*
X738125Y167400D01*
X738417Y167650D01*
X738750Y167733D01*
X739083Y167650D01*
X739333Y167442D01*
X739458Y167067D01*
Y166067D01*
G01X740500Y170000D02*
X738000D01*
X738500Y169500D01*
G01X740500D02*
Y170500D01*
G01X740125Y172183D02*
X740333Y172433D01*
X740458Y172725D01*
X740500Y173100D01*
X740417Y173475D01*
X740250Y173767D01*
X739958Y173975D01*
X739625Y174017D01*
X739292Y173933D01*
X739083Y173725D01*
X738917Y173433D01*
X738875Y173142D01*
X738917Y172850D01*
X739083Y172475D01*
X738000Y172600D01*
Y173725D01*
G01X740500Y176200D02*
X738000D01*
X738500Y175700D01*
G01X740500D02*
Y176700D01*
G01X748834Y163400D02*
X751334D01*
G01X748834Y162442D02*
Y164358D01*
G01X751334Y165667D02*
X748834D01*
Y166667D01*
X748959Y167000D01*
X749251Y167250D01*
X749584Y167333D01*
X749917Y167250D01*
X750167Y167042D01*
X750292Y166667D01*
Y165667D01*
G01X751334Y169600D02*
X748834D01*
X749334Y169100D01*
G01X751334D02*
Y170100D01*
G01X750959Y171783D02*
X751167Y172033D01*
X751292Y172325D01*
X751334Y172700D01*
X751251Y173075D01*
X751084Y173367D01*
X750792Y173575D01*
X750459Y173617D01*
X750126Y173533D01*
X749917Y173325D01*
X749751Y173033D01*
X749709Y172742D01*
X749751Y172450D01*
X749917Y172075D01*
X748834Y172200D01*
Y173325D01*
G01X749251Y175008D02*
X749001Y175258D01*
X748876Y175550D01*
X748834Y175883D01*
X748917Y176300D01*
X749126Y176592D01*
X749376Y176675D01*
X749626Y176633D01*
X749834Y176467D01*
X750251Y175633D01*
X750542Y175258D01*
X750959Y175008D01*
X751334Y174925D01*
Y176675D01*
G01X801850Y207086D02*
G02I-1850J0D01*
G01Y305512D02*
G02I-1850J0D01*
G01X796867Y392459D02*
X796617Y392584D01*
X796325Y392667D01*
X795992D01*
X795617Y392542D01*
X795325Y392334D01*
X795117Y392084D01*
X794950Y391667D01*
X794908Y391292D01*
X794992Y390917D01*
X795117Y390667D01*
X795367Y390417D01*
X795658Y390250D01*
X795950Y390167D01*
X796242D01*
X796533Y390250D01*
X796783Y390375D01*
X796992Y390542D01*
G01X798133Y390667D02*
X798383Y390375D01*
X798717Y390209D01*
X799092Y390167D01*
X799425Y390209D01*
X799758Y390417D01*
X799967Y390667D01*
X800008Y390917D01*
X799925Y391209D01*
X799633Y391417D01*
X799342Y391500D01*
X798967D01*
G01X799342D02*
X799592Y391625D01*
X799800Y391834D01*
X799883Y392084D01*
X799800Y392334D01*
X799592Y392542D01*
X799217Y392667D01*
X798842Y392625D01*
X798467Y392459D01*
G01X801358Y392250D02*
X801608Y392500D01*
X801900Y392625D01*
X802233Y392667D01*
X802650Y392584D01*
X802942Y392375D01*
X803025Y392125D01*
X802983Y391875D01*
X802817Y391667D01*
X801983Y391250D01*
X801608Y390959D01*
X801358Y390542D01*
X801275Y390167D01*
X803025D01*
G01X804333Y390667D02*
X804583Y390375D01*
X804917Y390209D01*
X805292Y390167D01*
X805625Y390209D01*
X805958Y390417D01*
X806167Y390667D01*
X806208Y390917D01*
X806125Y391209D01*
X805833Y391417D01*
X805542Y391500D01*
X805167D01*
G01X805542D02*
X805792Y391625D01*
X806000Y391834D01*
X806083Y392084D01*
X806000Y392334D01*
X805792Y392542D01*
X805417Y392667D01*
X805042Y392625D01*
X804667Y392459D01*
G01X770742Y390167D02*
X770617Y389917D01*
X770534Y389625D01*
Y389292D01*
X770659Y388917D01*
X770867Y388625D01*
X771117Y388417D01*
X771534Y388250D01*
X771909Y388208D01*
X772284Y388292D01*
X772534Y388417D01*
X772784Y388667D01*
X772951Y388958D01*
X773034Y389250D01*
Y389542D01*
X772951Y389833D01*
X772826Y390083D01*
X772659Y390292D01*
G01X770951Y391558D02*
X770701Y391808D01*
X770576Y392100D01*
X770534Y392433D01*
X770617Y392850D01*
X770826Y393142D01*
X771076Y393225D01*
X771326Y393183D01*
X771534Y393017D01*
X771951Y392183D01*
X772242Y391808D01*
X772659Y391558D01*
X773034Y391475D01*
Y393225D01*
G01X771992Y394658D02*
X771701Y394950D01*
X771534Y395200D01*
X771451Y395533D01*
X771534Y395825D01*
X771701Y396033D01*
X771951Y396200D01*
X772242Y396242D01*
X772492Y396200D01*
X772742Y396033D01*
X772951Y395783D01*
X773034Y395492D01*
X772951Y395158D01*
X772701Y394867D01*
X772326Y394700D01*
X771909Y394658D01*
X771367Y394742D01*
X771076Y394867D01*
X770784Y395075D01*
X770576Y395367D01*
X770534Y395658D01*
X770617Y395950D01*
X770826Y396158D01*
G01X770951Y397758D02*
X770701Y398008D01*
X770576Y398300D01*
X770534Y398633D01*
X770617Y399050D01*
X770826Y399342D01*
X771076Y399425D01*
X771326Y399383D01*
X771534Y399217D01*
X771951Y398383D01*
X772242Y398008D01*
X772659Y397758D01*
X773034Y397675D01*
Y399425D01*
G01X795117Y395167D02*
Y397667D01*
X796158D01*
X796492Y397542D01*
X796700Y397375D01*
X796783Y397042D01*
X796700Y396709D01*
X796450Y396500D01*
X796158Y396375D01*
X795117D01*
G01X796158D02*
X796783Y395167D01*
G01X798258Y396209D02*
X798550Y396500D01*
X798800Y396667D01*
X799133Y396750D01*
X799425Y396667D01*
X799633Y396500D01*
X799800Y396250D01*
X799842Y395959D01*
X799800Y395709D01*
X799633Y395459D01*
X799383Y395250D01*
X799092Y395167D01*
X798758Y395250D01*
X798467Y395500D01*
X798300Y395875D01*
X798258Y396292D01*
X798342Y396834D01*
X798467Y397125D01*
X798675Y397417D01*
X798967Y397625D01*
X799258Y397667D01*
X799550Y397584D01*
X799758Y397375D01*
G01X802150Y397667D02*
X801817Y397584D01*
X801567Y397375D01*
X801400Y397125D01*
X801275Y396792D01*
X801233Y396417D01*
X801275Y396042D01*
X801400Y395709D01*
X801567Y395459D01*
X801817Y395250D01*
X802150Y395167D01*
X802483Y395250D01*
X802733Y395459D01*
X802900Y395709D01*
X803025Y396042D01*
X803067Y396417D01*
X803025Y396792D01*
X802900Y397125D01*
X802733Y397375D01*
X802483Y397584D01*
X802150Y397667D01*
G01X804458Y397250D02*
X804708Y397500D01*
X805000Y397625D01*
X805333Y397667D01*
X805750Y397584D01*
X806042Y397375D01*
X806125Y397125D01*
X806083Y396875D01*
X805917Y396667D01*
X805083Y396250D01*
X804708Y395959D01*
X804458Y395542D01*
X804375Y395167D01*
X806125D01*
G01X779034Y388417D02*
X776534D01*
Y389458D01*
X776659Y389792D01*
X776826Y390000D01*
X777159Y390083D01*
X777492Y390000D01*
X777701Y389750D01*
X777826Y389458D01*
Y388417D01*
G01Y389458D02*
X779034Y390083D01*
G01X778659Y391433D02*
X778867Y391683D01*
X778992Y391975D01*
X779034Y392350D01*
X778951Y392725D01*
X778784Y393017D01*
X778492Y393225D01*
X778159Y393267D01*
X777826Y393183D01*
X777617Y392975D01*
X777451Y392683D01*
X777409Y392392D01*
X777451Y392100D01*
X777617Y391725D01*
X776534Y391850D01*
Y392975D01*
G01X778659Y394533D02*
X778867Y394783D01*
X778992Y395075D01*
X779034Y395450D01*
X778951Y395825D01*
X778784Y396117D01*
X778492Y396325D01*
X778159Y396367D01*
X777826Y396283D01*
X777617Y396075D01*
X777451Y395783D01*
X777409Y395492D01*
X777451Y395200D01*
X777617Y394825D01*
X776534Y394950D01*
Y396075D01*
G01X778534Y397633D02*
X778826Y397883D01*
X778992Y398217D01*
X779034Y398592D01*
X778992Y398925D01*
X778784Y399258D01*
X778534Y399467D01*
X778284Y399508D01*
X777992Y399425D01*
X777784Y399133D01*
X777701Y398842D01*
Y398467D01*
G01Y398842D02*
X777576Y399092D01*
X777367Y399300D01*
X777117Y399383D01*
X776867Y399300D01*
X776659Y399092D01*
X776534Y398717D01*
X776576Y398342D01*
X776742Y397967D01*
G01X736804Y379442D02*
X734304D01*
Y380483D01*
X734429Y380817D01*
X734596Y381025D01*
X734929Y381108D01*
X735262Y381025D01*
X735471Y380775D01*
X735596Y380483D01*
Y379442D01*
G01Y380483D02*
X736804Y381108D01*
G01X735762Y382583D02*
X735471Y382875D01*
X735304Y383125D01*
X735221Y383458D01*
X735304Y383750D01*
X735471Y383958D01*
X735721Y384125D01*
X736012Y384167D01*
X736262Y384125D01*
X736512Y383958D01*
X736721Y383708D01*
X736804Y383417D01*
X736721Y383083D01*
X736471Y382792D01*
X736096Y382625D01*
X735679Y382583D01*
X735137Y382667D01*
X734846Y382792D01*
X734554Y383000D01*
X734346Y383292D01*
X734304Y383583D01*
X734387Y383875D01*
X734596Y384083D01*
G01X736804Y386975D02*
X734304D01*
X736096Y385433D01*
Y387517D01*
G01X736304Y388658D02*
X736596Y388908D01*
X736762Y389242D01*
X736804Y389617D01*
X736762Y389950D01*
X736554Y390283D01*
X736304Y390492D01*
X736054Y390533D01*
X735762Y390450D01*
X735554Y390158D01*
X735471Y389867D01*
Y389492D01*
G01Y389867D02*
X735346Y390117D01*
X735137Y390325D01*
X734887Y390408D01*
X734637Y390325D01*
X734429Y390117D01*
X734304Y389742D01*
X734346Y389367D01*
X734512Y388992D01*
G01X740365Y361435D02*
X736365D01*
Y354035D01*
G01X746934Y359217D02*
X744434D01*
Y360258D01*
X744559Y360592D01*
X744726Y360800D01*
X745059Y360883D01*
X745392Y360800D01*
X745601Y360550D01*
X745726Y360258D01*
Y359217D01*
G01Y360258D02*
X746934Y360883D01*
G01X745892Y362358D02*
X745601Y362650D01*
X745434Y362900D01*
X745351Y363233D01*
X745434Y363525D01*
X745601Y363733D01*
X745851Y363900D01*
X746142Y363942D01*
X746392Y363900D01*
X746642Y363733D01*
X746851Y363483D01*
X746934Y363192D01*
X746851Y362858D01*
X746601Y362567D01*
X746226Y362400D01*
X745809Y362358D01*
X745267Y362442D01*
X744976Y362567D01*
X744684Y362775D01*
X744476Y363067D01*
X744434Y363358D01*
X744517Y363650D01*
X744726Y363858D01*
G01X746559Y365333D02*
X746767Y365583D01*
X746892Y365875D01*
X746934Y366250D01*
X746851Y366625D01*
X746684Y366917D01*
X746392Y367125D01*
X746059Y367167D01*
X745726Y367083D01*
X745517Y366875D01*
X745351Y366583D01*
X745309Y366292D01*
X745351Y366000D01*
X745517Y365625D01*
X744434Y365750D01*
Y366875D01*
G01X746559Y368433D02*
X746767Y368683D01*
X746892Y368975D01*
X746934Y369350D01*
X746851Y369725D01*
X746684Y370017D01*
X746392Y370225D01*
X746059Y370267D01*
X745726Y370183D01*
X745517Y369975D01*
X745351Y369683D01*
X745309Y369392D01*
X745351Y369100D01*
X745517Y368725D01*
X744434Y368850D01*
Y369975D01*
G01X736465Y344235D02*
X740465D01*
Y351635D01*
G01X744734Y342900D02*
X747234D01*
G01X744734Y341942D02*
Y343858D01*
G01X747234Y345167D02*
X744734D01*
Y346167D01*
X744859Y346500D01*
X745151Y346750D01*
X745484Y346833D01*
X745817Y346750D01*
X746067Y346542D01*
X746192Y346167D01*
Y345167D01*
G01X747234Y349100D02*
X744734D01*
X745234Y348600D01*
G01X747234D02*
Y349600D01*
G01Y352700D02*
X744734D01*
X746526Y351158D01*
Y353242D01*
G01X746942Y354592D02*
X747151Y354883D01*
X747234Y355217D01*
X747151Y355550D01*
X746901Y355842D01*
X746526Y356050D01*
X746151Y356133D01*
X745692D01*
X745317Y356050D01*
X744984Y355842D01*
X744817Y355592D01*
X744734Y355300D01*
X744817Y354967D01*
X744984Y354717D01*
X745234Y354550D01*
X745567Y354467D01*
X745859Y354550D01*
X746151Y354758D01*
X746317Y355008D01*
X746359Y355300D01*
X746276Y355633D01*
X746067Y355883D01*
X745692Y356133D01*
G01X765242Y390167D02*
X765117Y389917D01*
X765034Y389625D01*
Y389292D01*
X765159Y388917D01*
X765367Y388625D01*
X765617Y388417D01*
X766034Y388250D01*
X766409Y388208D01*
X766784Y388292D01*
X767034Y388417D01*
X767284Y388667D01*
X767451Y388958D01*
X767534Y389250D01*
Y389542D01*
X767451Y389833D01*
X767326Y390083D01*
X767159Y390292D01*
G01X765451Y391558D02*
X765201Y391808D01*
X765076Y392100D01*
X765034Y392433D01*
X765117Y392850D01*
X765326Y393142D01*
X765576Y393225D01*
X765826Y393183D01*
X766034Y393017D01*
X766451Y392183D01*
X766742Y391808D01*
X767159Y391558D01*
X767534Y391475D01*
Y393225D01*
G01X766492Y394658D02*
X766201Y394950D01*
X766034Y395200D01*
X765951Y395533D01*
X766034Y395825D01*
X766201Y396033D01*
X766451Y396200D01*
X766742Y396242D01*
X766992Y396200D01*
X767242Y396033D01*
X767451Y395783D01*
X767534Y395492D01*
X767451Y395158D01*
X767201Y394867D01*
X766826Y394700D01*
X766409Y394658D01*
X765867Y394742D01*
X765576Y394867D01*
X765284Y395075D01*
X765076Y395367D01*
X765034Y395658D01*
X765117Y395950D01*
X765326Y396158D01*
G01X767034Y397633D02*
X767326Y397883D01*
X767492Y398217D01*
X767534Y398592D01*
X767492Y398925D01*
X767284Y399258D01*
X767034Y399467D01*
X766784Y399508D01*
X766492Y399425D01*
X766284Y399133D01*
X766201Y398842D01*
Y398467D01*
G01Y398842D02*
X766076Y399092D01*
X765867Y399300D01*
X765617Y399383D01*
X765367Y399300D01*
X765159Y399092D01*
X765034Y398717D01*
X765076Y398342D01*
X765242Y397967D01*
G01X748742Y390167D02*
X748617Y389917D01*
X748534Y389625D01*
Y389292D01*
X748659Y388917D01*
X748867Y388625D01*
X749117Y388417D01*
X749534Y388250D01*
X749909Y388208D01*
X750284Y388292D01*
X750534Y388417D01*
X750784Y388667D01*
X750951Y388958D01*
X751034Y389250D01*
Y389542D01*
X750951Y389833D01*
X750826Y390083D01*
X750659Y390292D01*
G01X748951Y391558D02*
X748701Y391808D01*
X748576Y392100D01*
X748534Y392433D01*
X748617Y392850D01*
X748826Y393142D01*
X749076Y393225D01*
X749326Y393183D01*
X749534Y393017D01*
X749951Y392183D01*
X750242Y391808D01*
X750659Y391558D01*
X751034Y391475D01*
Y393225D01*
G01X749992Y394658D02*
X749701Y394950D01*
X749534Y395200D01*
X749451Y395533D01*
X749534Y395825D01*
X749701Y396033D01*
X749951Y396200D01*
X750242Y396242D01*
X750492Y396200D01*
X750742Y396033D01*
X750951Y395783D01*
X751034Y395492D01*
X750951Y395158D01*
X750701Y394867D01*
X750326Y394700D01*
X749909Y394658D01*
X749367Y394742D01*
X749076Y394867D01*
X748784Y395075D01*
X748576Y395367D01*
X748534Y395658D01*
X748617Y395950D01*
X748826Y396158D01*
G01X751034Y399050D02*
X748534D01*
X750326Y397508D01*
Y399592D01*
G01X754242Y390167D02*
X754117Y389917D01*
X754034Y389625D01*
Y389292D01*
X754159Y388917D01*
X754367Y388625D01*
X754617Y388417D01*
X755034Y388250D01*
X755409Y388208D01*
X755784Y388292D01*
X756034Y388417D01*
X756284Y388667D01*
X756451Y388958D01*
X756534Y389250D01*
Y389542D01*
X756451Y389833D01*
X756326Y390083D01*
X756159Y390292D01*
G01X754451Y391558D02*
X754201Y391808D01*
X754076Y392100D01*
X754034Y392433D01*
X754117Y392850D01*
X754326Y393142D01*
X754576Y393225D01*
X754826Y393183D01*
X755034Y393017D01*
X755451Y392183D01*
X755742Y391808D01*
X756159Y391558D01*
X756534Y391475D01*
Y393225D01*
G01X755492Y394658D02*
X755201Y394950D01*
X755034Y395200D01*
X754951Y395533D01*
X755034Y395825D01*
X755201Y396033D01*
X755451Y396200D01*
X755742Y396242D01*
X755992Y396200D01*
X756242Y396033D01*
X756451Y395783D01*
X756534Y395492D01*
X756451Y395158D01*
X756201Y394867D01*
X755826Y394700D01*
X755409Y394658D01*
X754867Y394742D01*
X754576Y394867D01*
X754284Y395075D01*
X754076Y395367D01*
X754034Y395658D01*
X754117Y395950D01*
X754326Y396158D01*
G01X755492Y397758D02*
X755201Y398050D01*
X755034Y398300D01*
X754951Y398633D01*
X755034Y398925D01*
X755201Y399133D01*
X755451Y399300D01*
X755742Y399342D01*
X755992Y399300D01*
X756242Y399133D01*
X756451Y398883D01*
X756534Y398592D01*
X756451Y398258D01*
X756201Y397967D01*
X755826Y397800D01*
X755409Y397758D01*
X754867Y397842D01*
X754576Y397967D01*
X754284Y398175D01*
X754076Y398467D01*
X754034Y398758D01*
X754117Y399050D01*
X754326Y399258D01*
G01X759742Y390167D02*
X759617Y389917D01*
X759534Y389625D01*
Y389292D01*
X759659Y388917D01*
X759867Y388625D01*
X760117Y388417D01*
X760534Y388250D01*
X760909Y388208D01*
X761284Y388292D01*
X761534Y388417D01*
X761784Y388667D01*
X761951Y388958D01*
X762034Y389250D01*
Y389542D01*
X761951Y389833D01*
X761826Y390083D01*
X761659Y390292D01*
G01X759951Y391558D02*
X759701Y391808D01*
X759576Y392100D01*
X759534Y392433D01*
X759617Y392850D01*
X759826Y393142D01*
X760076Y393225D01*
X760326Y393183D01*
X760534Y393017D01*
X760951Y392183D01*
X761242Y391808D01*
X761659Y391558D01*
X762034Y391475D01*
Y393225D01*
G01X760992Y394658D02*
X760701Y394950D01*
X760534Y395200D01*
X760451Y395533D01*
X760534Y395825D01*
X760701Y396033D01*
X760951Y396200D01*
X761242Y396242D01*
X761492Y396200D01*
X761742Y396033D01*
X761951Y395783D01*
X762034Y395492D01*
X761951Y395158D01*
X761701Y394867D01*
X761326Y394700D01*
X760909Y394658D01*
X760367Y394742D01*
X760076Y394867D01*
X759784Y395075D01*
X759576Y395367D01*
X759534Y395658D01*
X759617Y395950D01*
X759826Y396158D01*
G01X762034Y398550D02*
X761992Y398842D01*
X761867Y399175D01*
X761659Y399383D01*
X761367Y399467D01*
X761076Y399383D01*
X760826Y399133D01*
X760701Y398758D01*
Y398342D01*
X760617Y398092D01*
X760409Y397883D01*
X760117Y397800D01*
X759826Y397925D01*
X759617Y398217D01*
X759534Y398550D01*
X759617Y398883D01*
X759826Y399175D01*
X760117Y399300D01*
X760409Y399217D01*
X760617Y399008D01*
X760701Y398758D01*
Y398342D01*
X760826Y397967D01*
X761076Y397717D01*
X761367Y397633D01*
X761659Y397717D01*
X761867Y397925D01*
X761992Y398258D01*
X762034Y398550D01*
G01X743742Y390067D02*
X743617Y389817D01*
X743534Y389525D01*
Y389192D01*
X743659Y388817D01*
X743867Y388525D01*
X744117Y388317D01*
X744534Y388150D01*
X744909Y388108D01*
X745284Y388192D01*
X745534Y388317D01*
X745784Y388567D01*
X745951Y388858D01*
X746034Y389150D01*
Y389442D01*
X745951Y389733D01*
X745826Y389983D01*
X745659Y390192D01*
G01X743951Y391458D02*
X743701Y391708D01*
X743576Y392000D01*
X743534Y392333D01*
X743617Y392750D01*
X743826Y393042D01*
X744076Y393125D01*
X744326Y393083D01*
X744534Y392917D01*
X744951Y392083D01*
X745242Y391708D01*
X745659Y391458D01*
X746034Y391375D01*
Y393125D01*
G01X744992Y394558D02*
X744701Y394850D01*
X744534Y395100D01*
X744451Y395433D01*
X744534Y395725D01*
X744701Y395933D01*
X744951Y396100D01*
X745242Y396142D01*
X745492Y396100D01*
X745742Y395933D01*
X745951Y395683D01*
X746034Y395392D01*
X745951Y395058D01*
X745701Y394767D01*
X745326Y394600D01*
X744909Y394558D01*
X744367Y394642D01*
X744076Y394767D01*
X743784Y394975D01*
X743576Y395267D01*
X743534Y395558D01*
X743617Y395850D01*
X743826Y396058D01*
G01X745659Y397533D02*
X745867Y397783D01*
X745992Y398075D01*
X746034Y398450D01*
X745951Y398825D01*
X745784Y399117D01*
X745492Y399325D01*
X745159Y399367D01*
X744826Y399283D01*
X744617Y399075D01*
X744451Y398783D01*
X744409Y398492D01*
X744451Y398200D01*
X744617Y397825D01*
X743534Y397950D01*
Y399075D01*
G01X795117Y400167D02*
Y402667D01*
X796158D01*
X796492Y402542D01*
X796700Y402375D01*
X796783Y402042D01*
X796700Y401709D01*
X796450Y401500D01*
X796158Y401375D01*
X795117D01*
G01X796158D02*
X796783Y400167D01*
G01X798258Y401209D02*
X798550Y401500D01*
X798800Y401667D01*
X799133Y401750D01*
X799425Y401667D01*
X799633Y401500D01*
X799800Y401250D01*
X799842Y400959D01*
X799800Y400709D01*
X799633Y400459D01*
X799383Y400250D01*
X799092Y400167D01*
X798758Y400250D01*
X798467Y400500D01*
X798300Y400875D01*
X798258Y401292D01*
X798342Y401834D01*
X798467Y402125D01*
X798675Y402417D01*
X798967Y402625D01*
X799258Y402667D01*
X799550Y402584D01*
X799758Y402375D01*
G01X802150Y402667D02*
X801817Y402584D01*
X801567Y402375D01*
X801400Y402125D01*
X801275Y401792D01*
X801233Y401417D01*
X801275Y401042D01*
X801400Y400709D01*
X801567Y400459D01*
X801817Y400250D01*
X802150Y400167D01*
X802483Y400250D01*
X802733Y400459D01*
X802900Y400709D01*
X803025Y401042D01*
X803067Y401417D01*
X803025Y401792D01*
X802900Y402125D01*
X802733Y402375D01*
X802483Y402584D01*
X802150Y402667D01*
G01X804458Y401209D02*
X804750Y401500D01*
X805000Y401667D01*
X805333Y401750D01*
X805625Y401667D01*
X805833Y401500D01*
X806000Y401250D01*
X806042Y400959D01*
X806000Y400709D01*
X805833Y400459D01*
X805583Y400250D01*
X805292Y400167D01*
X804958Y400250D01*
X804667Y400500D01*
X804500Y400875D01*
X804458Y401292D01*
X804542Y401834D01*
X804667Y402125D01*
X804875Y402417D01*
X805167Y402625D01*
X805458Y402667D01*
X805750Y402584D01*
X805958Y402375D01*
G01X792400Y421800D02*
X788400D01*
Y414400D01*
G01X762435Y425273D02*
Y419773D01*
G01X754435Y425273D02*
X762435D01*
G01X754435Y419773D02*
Y425273D01*
G01Y407673D02*
Y413173D01*
G01X762435Y407673D02*
X754435D01*
G01X762435Y413173D02*
Y407673D01*
G01X771135Y425273D02*
Y419773D01*
G01X763135Y425273D02*
X771135D01*
G01X763135Y419773D02*
Y425273D01*
G01Y407673D02*
Y413173D01*
G01X771135Y407673D02*
X763135D01*
G01X771135Y413173D02*
Y407673D01*
G01X779835Y425273D02*
Y419773D01*
G01X771835Y425273D02*
X779835D01*
G01X771835Y419773D02*
Y425273D01*
G01Y407673D02*
Y413173D01*
G01X779835Y407673D02*
X771835D01*
G01X779835Y413173D02*
Y407673D01*
G01X792842Y461967D02*
X792717Y461717D01*
X792634Y461425D01*
Y461092D01*
X792759Y460717D01*
X792967Y460425D01*
X793217Y460217D01*
X793634Y460050D01*
X794009Y460008D01*
X794384Y460092D01*
X794634Y460217D01*
X794884Y460467D01*
X795051Y460758D01*
X795134Y461050D01*
Y461342D01*
X795051Y461633D01*
X794926Y461883D01*
X794759Y462092D01*
G01X793051Y463358D02*
X792801Y463608D01*
X792676Y463900D01*
X792634Y464233D01*
X792717Y464650D01*
X792926Y464942D01*
X793176Y465025D01*
X793426Y464983D01*
X793634Y464817D01*
X794051Y463983D01*
X794342Y463608D01*
X794759Y463358D01*
X795134Y463275D01*
Y465025D01*
G01X794759Y466333D02*
X794967Y466583D01*
X795092Y466875D01*
X795134Y467250D01*
X795051Y467625D01*
X794884Y467917D01*
X794592Y468125D01*
X794259Y468167D01*
X793926Y468083D01*
X793717Y467875D01*
X793551Y467583D01*
X793509Y467292D01*
X793551Y467000D01*
X793717Y466625D01*
X792634Y466750D01*
Y467875D01*
G01X794842Y469642D02*
X795051Y469933D01*
X795134Y470267D01*
X795051Y470600D01*
X794801Y470892D01*
X794426Y471100D01*
X794051Y471183D01*
X793592D01*
X793217Y471100D01*
X792884Y470892D01*
X792717Y470642D01*
X792634Y470350D01*
X792717Y470017D01*
X792884Y469767D01*
X793134Y469600D01*
X793467Y469517D01*
X793759Y469600D01*
X794051Y469808D01*
X794217Y470058D01*
X794259Y470350D01*
X794176Y470683D01*
X793967Y470933D01*
X793592Y471183D01*
G01X786300Y438100D02*
Y443600D01*
G01X794300Y438100D02*
X786300D01*
G01X794300Y443600D02*
Y438100D01*
G01Y455700D02*
Y450200D01*
G01X786300Y455700D02*
X794300D01*
G01X786300Y450200D02*
Y455700D01*
G01X753700Y425300D02*
Y419800D01*
G01X745700Y425300D02*
X753700D01*
G01X745700Y419800D02*
Y425300D01*
G01Y407700D02*
Y413200D01*
G01X753700Y407700D02*
X745700D01*
G01X753700Y413200D02*
Y407700D01*
G01X787242Y461767D02*
X787117Y461517D01*
X787034Y461225D01*
Y460892D01*
X787159Y460517D01*
X787367Y460225D01*
X787617Y460017D01*
X788034Y459850D01*
X788409Y459808D01*
X788784Y459892D01*
X789034Y460017D01*
X789284Y460267D01*
X789451Y460558D01*
X789534Y460850D01*
Y461142D01*
X789451Y461433D01*
X789326Y461683D01*
X789159Y461892D01*
G01X787451Y463158D02*
X787201Y463408D01*
X787076Y463700D01*
X787034Y464033D01*
X787117Y464450D01*
X787326Y464742D01*
X787576Y464825D01*
X787826Y464783D01*
X788034Y464617D01*
X788451Y463783D01*
X788742Y463408D01*
X789159Y463158D01*
X789534Y463075D01*
Y464825D01*
G01X789159Y466133D02*
X789367Y466383D01*
X789492Y466675D01*
X789534Y467050D01*
X789451Y467425D01*
X789284Y467717D01*
X788992Y467925D01*
X788659Y467967D01*
X788326Y467883D01*
X788117Y467675D01*
X787951Y467383D01*
X787909Y467092D01*
X787951Y466800D01*
X788117Y466425D01*
X787034Y466550D01*
Y467675D01*
G01X789534Y470150D02*
X789492Y470442D01*
X789367Y470775D01*
X789159Y470983D01*
X788867Y471067D01*
X788576Y470983D01*
X788326Y470733D01*
X788201Y470358D01*
Y469942D01*
X788117Y469692D01*
X787909Y469483D01*
X787617Y469400D01*
X787326Y469525D01*
X787117Y469817D01*
X787034Y470150D01*
X787117Y470483D01*
X787326Y470775D01*
X787617Y470900D01*
X787909Y470817D01*
X788117Y470608D01*
X788201Y470358D01*
Y469942D01*
X788326Y469567D01*
X788576Y469317D01*
X788867Y469233D01*
X789159Y469317D01*
X789367Y469525D01*
X789492Y469858D01*
X789534Y470150D01*
G01X777400Y438100D02*
Y443600D01*
G01X785400Y438100D02*
X777400D01*
G01X785400Y443600D02*
Y438100D01*
G01Y455700D02*
Y450200D01*
G01X777400Y455700D02*
X785400D01*
G01X777400Y450200D02*
Y455700D01*
G01X800467Y417092D02*
X800217Y417217D01*
X799925Y417300D01*
X799592D01*
X799217Y417175D01*
X798925Y416967D01*
X798717Y416717D01*
X798550Y416300D01*
X798508Y415925D01*
X798592Y415550D01*
X798717Y415300D01*
X798967Y415050D01*
X799258Y414883D01*
X799550Y414800D01*
X799842D01*
X800133Y414883D01*
X800383Y415008D01*
X800592Y415175D01*
G01X801733D02*
X801983Y414967D01*
X802275Y414842D01*
X802650Y414800D01*
X803025Y414883D01*
X803317Y415050D01*
X803525Y415342D01*
X803567Y415675D01*
X803483Y416008D01*
X803275Y416217D01*
X802983Y416383D01*
X802692Y416425D01*
X802400Y416383D01*
X802025Y416217D01*
X802150Y417300D01*
X803275D01*
G01X805750D02*
X805417Y417217D01*
X805167Y417008D01*
X805000Y416758D01*
X804875Y416425D01*
X804833Y416050D01*
X804875Y415675D01*
X805000Y415342D01*
X805167Y415092D01*
X805417Y414883D01*
X805750Y414800D01*
X806083Y414883D01*
X806333Y415092D01*
X806500Y415342D01*
X806625Y415675D01*
X806667Y416050D01*
X806625Y416425D01*
X806500Y416758D01*
X806333Y417008D01*
X806083Y417217D01*
X805750Y417300D01*
G01X808142Y415092D02*
X808433Y414883D01*
X808767Y414800D01*
X809100Y414883D01*
X809392Y415133D01*
X809600Y415508D01*
X809683Y415883D01*
Y416342D01*
X809600Y416717D01*
X809392Y417050D01*
X809142Y417217D01*
X808850Y417300D01*
X808517Y417217D01*
X808267Y417050D01*
X808100Y416800D01*
X808017Y416467D01*
X808100Y416175D01*
X808308Y415883D01*
X808558Y415717D01*
X808850Y415675D01*
X809183Y415758D01*
X809433Y415967D01*
X809683Y416342D01*
G01X745620Y428617D02*
X743120D01*
Y429658D01*
X743245Y429992D01*
X743412Y430200D01*
X743745Y430283D01*
X744078Y430200D01*
X744287Y429950D01*
X744412Y429658D01*
Y428617D01*
G01Y429658D02*
X745620Y430283D01*
G01Y432467D02*
X745078Y432550D01*
X744620Y432675D01*
X744203Y432842D01*
X743745Y433050D01*
X743120Y433383D01*
Y431717D01*
G01X745328Y434942D02*
X745537Y435233D01*
X745620Y435567D01*
X745537Y435900D01*
X745287Y436192D01*
X744912Y436400D01*
X744537Y436483D01*
X744078D01*
X743703Y436400D01*
X743370Y436192D01*
X743203Y435942D01*
X743120Y435650D01*
X743203Y435317D01*
X743370Y435067D01*
X743620Y434900D01*
X743953Y434817D01*
X744245Y434900D01*
X744537Y435108D01*
X744703Y435358D01*
X744745Y435650D01*
X744662Y435983D01*
X744453Y436233D01*
X744078Y436483D01*
G01X743120Y438750D02*
X743203Y438417D01*
X743412Y438167D01*
X743662Y438000D01*
X743995Y437875D01*
X744370Y437833D01*
X744745Y437875D01*
X745078Y438000D01*
X745328Y438167D01*
X745537Y438417D01*
X745620Y438750D01*
X745537Y439083D01*
X745328Y439333D01*
X745078Y439500D01*
X744745Y439625D01*
X744370Y439667D01*
X743995Y439625D01*
X743662Y439500D01*
X743412Y439333D01*
X743203Y439083D01*
X743120Y438750D01*
G01X745328Y441142D02*
X745537Y441433D01*
X745620Y441767D01*
X745537Y442100D01*
X745287Y442392D01*
X744912Y442600D01*
X744537Y442683D01*
X744078D01*
X743703Y442600D01*
X743370Y442392D01*
X743203Y442142D01*
X743120Y441850D01*
X743203Y441517D01*
X743370Y441267D01*
X743620Y441100D01*
X743953Y441017D01*
X744245Y441100D01*
X744537Y441308D01*
X744703Y441558D01*
X744745Y441850D01*
X744662Y442183D01*
X744453Y442433D01*
X744078Y442683D01*
G01X739200Y468180D02*
Y460380D01*
G01X746200Y454780D02*
Y463480D01*
G01X739200Y454780D02*
X746200D01*
G01X739200Y461180D02*
Y454780D01*
G01X779716Y461267D02*
X782216D01*
Y462933D01*
G01Y465200D02*
X779716D01*
X780216Y464700D01*
G01X782216D02*
Y465700D01*
G01X780133Y467508D02*
X779883Y467758D01*
X779758Y468050D01*
X779716Y468383D01*
X779799Y468800D01*
X780008Y469092D01*
X780258Y469175D01*
X780508Y469133D01*
X780716Y468967D01*
X781133Y468133D01*
X781424Y467758D01*
X781841Y467508D01*
X782216Y467425D01*
Y469175D01*
G01X747600Y431934D02*
Y468234D01*
X776000D01*
Y431934D01*
X747600D01*
G01X785742Y491967D02*
X785617Y491717D01*
X785534Y491425D01*
Y491092D01*
X785659Y490717D01*
X785867Y490425D01*
X786117Y490217D01*
X786534Y490050D01*
X786909Y490008D01*
X787284Y490092D01*
X787534Y490217D01*
X787784Y490467D01*
X787951Y490758D01*
X788034Y491050D01*
Y491342D01*
X787951Y491633D01*
X787826Y491883D01*
X787659Y492092D01*
G01X785951Y493358D02*
X785701Y493608D01*
X785576Y493900D01*
X785534Y494233D01*
X785617Y494650D01*
X785826Y494942D01*
X786076Y495025D01*
X786326Y494983D01*
X786534Y494817D01*
X786951Y493983D01*
X787242Y493608D01*
X787659Y493358D01*
X788034Y493275D01*
Y495025D01*
G01X787659Y496333D02*
X787867Y496583D01*
X787992Y496875D01*
X788034Y497250D01*
X787951Y497625D01*
X787784Y497917D01*
X787492Y498125D01*
X787159Y498167D01*
X786826Y498083D01*
X786617Y497875D01*
X786451Y497583D01*
X786409Y497292D01*
X786451Y497000D01*
X786617Y496625D01*
X785534Y496750D01*
Y497875D01*
G01X788034Y500267D02*
X787492Y500350D01*
X787034Y500475D01*
X786617Y500642D01*
X786159Y500850D01*
X785534Y501183D01*
Y499517D01*
G01X789542Y491867D02*
X789417Y491617D01*
X789334Y491325D01*
Y490992D01*
X789459Y490617D01*
X789667Y490325D01*
X789917Y490117D01*
X790334Y489950D01*
X790709Y489908D01*
X791084Y489992D01*
X791334Y490117D01*
X791584Y490367D01*
X791751Y490658D01*
X791834Y490950D01*
Y491242D01*
X791751Y491533D01*
X791626Y491783D01*
X791459Y491992D01*
G01X789751Y493258D02*
X789501Y493508D01*
X789376Y493800D01*
X789334Y494133D01*
X789417Y494550D01*
X789626Y494842D01*
X789876Y494925D01*
X790126Y494883D01*
X790334Y494717D01*
X790751Y493883D01*
X791042Y493508D01*
X791459Y493258D01*
X791834Y493175D01*
Y494925D01*
G01X791459Y496233D02*
X791667Y496483D01*
X791792Y496775D01*
X791834Y497150D01*
X791751Y497525D01*
X791584Y497817D01*
X791292Y498025D01*
X790959Y498067D01*
X790626Y497983D01*
X790417Y497775D01*
X790251Y497483D01*
X790209Y497192D01*
X790251Y496900D01*
X790417Y496525D01*
X789334Y496650D01*
Y497775D01*
G01X789751Y499458D02*
X789501Y499708D01*
X789376Y500000D01*
X789334Y500333D01*
X789417Y500750D01*
X789626Y501042D01*
X789876Y501125D01*
X790126Y501083D01*
X790334Y500917D01*
X790751Y500083D01*
X791042Y499708D01*
X791459Y499458D01*
X791834Y499375D01*
Y501125D01*
G01X772542Y476167D02*
X772417Y475917D01*
X772334Y475625D01*
Y475292D01*
X772459Y474917D01*
X772667Y474625D01*
X772917Y474417D01*
X773334Y474250D01*
X773709Y474208D01*
X774084Y474292D01*
X774334Y474417D01*
X774584Y474667D01*
X774751Y474958D01*
X774834Y475250D01*
Y475542D01*
X774751Y475833D01*
X774626Y476083D01*
X774459Y476292D01*
G01X772751Y477558D02*
X772501Y477808D01*
X772376Y478100D01*
X772334Y478433D01*
X772417Y478850D01*
X772626Y479142D01*
X772876Y479225D01*
X773126Y479183D01*
X773334Y479017D01*
X773751Y478183D01*
X774042Y477808D01*
X774459Y477558D01*
X774834Y477475D01*
Y479225D01*
G01Y481367D02*
X774292Y481450D01*
X773834Y481575D01*
X773417Y481742D01*
X772959Y481950D01*
X772334Y482283D01*
Y480617D01*
G01X774542Y483842D02*
X774751Y484133D01*
X774834Y484467D01*
X774751Y484800D01*
X774501Y485092D01*
X774126Y485300D01*
X773751Y485383D01*
X773292D01*
X772917Y485300D01*
X772584Y485092D01*
X772417Y484842D01*
X772334Y484550D01*
X772417Y484217D01*
X772584Y483967D01*
X772834Y483800D01*
X773167Y483717D01*
X773459Y483800D01*
X773751Y484008D01*
X773917Y484258D01*
X773959Y484550D01*
X773876Y484883D01*
X773667Y485133D01*
X773292Y485383D01*
G01X734555Y514794D02*
X734430Y514544D01*
X734347Y514252D01*
Y513919D01*
X734472Y513544D01*
X734680Y513252D01*
X734930Y513044D01*
X735347Y512877D01*
X735722Y512835D01*
X736097Y512919D01*
X736347Y513044D01*
X736597Y513294D01*
X736764Y513585D01*
X736847Y513877D01*
Y514169D01*
X736764Y514460D01*
X736639Y514710D01*
X736472Y514919D01*
G01X734764Y516185D02*
X734514Y516435D01*
X734389Y516727D01*
X734347Y517060D01*
X734430Y517477D01*
X734639Y517769D01*
X734889Y517852D01*
X735139Y517810D01*
X735347Y517644D01*
X735764Y516810D01*
X736055Y516435D01*
X736472Y516185D01*
X736847Y516102D01*
Y517852D01*
G01Y520077D02*
X736805Y520369D01*
X736680Y520702D01*
X736472Y520910D01*
X736180Y520994D01*
X735889Y520910D01*
X735639Y520660D01*
X735514Y520285D01*
Y519869D01*
X735430Y519619D01*
X735222Y519410D01*
X734930Y519327D01*
X734639Y519452D01*
X734430Y519744D01*
X734347Y520077D01*
X734430Y520410D01*
X734639Y520702D01*
X734930Y520827D01*
X735222Y520744D01*
X735430Y520535D01*
X735514Y520285D01*
Y519869D01*
X735639Y519494D01*
X735889Y519244D01*
X736180Y519160D01*
X736472Y519244D01*
X736680Y519452D01*
X736805Y519785D01*
X736847Y520077D01*
G01Y523677D02*
X734347D01*
X736139Y522135D01*
Y524219D01*
G01X764217Y507967D02*
Y510467D01*
X765258D01*
X765592Y510342D01*
X765800Y510175D01*
X765883Y509842D01*
X765800Y509509D01*
X765550Y509300D01*
X765258Y509175D01*
X764217D01*
G01X765258D02*
X765883Y507967D01*
G01X767233Y508342D02*
X767483Y508134D01*
X767775Y508009D01*
X768150Y507967D01*
X768525Y508050D01*
X768817Y508217D01*
X769025Y508509D01*
X769067Y508842D01*
X768983Y509175D01*
X768775Y509384D01*
X768483Y509550D01*
X768192Y509592D01*
X767900Y509550D01*
X767525Y509384D01*
X767650Y510467D01*
X768775D01*
G01X771750Y507967D02*
Y510467D01*
X770208Y508675D01*
X772292D01*
G01X773642Y508259D02*
X773933Y508050D01*
X774267Y507967D01*
X774600Y508050D01*
X774892Y508300D01*
X775100Y508675D01*
X775183Y509050D01*
Y509509D01*
X775100Y509884D01*
X774892Y510217D01*
X774642Y510384D01*
X774350Y510467D01*
X774017Y510384D01*
X773767Y510217D01*
X773600Y509967D01*
X773517Y509634D01*
X773600Y509342D01*
X773808Y509050D01*
X774058Y508884D01*
X774350Y508842D01*
X774683Y508925D01*
X774933Y509134D01*
X775183Y509509D01*
G01X780554Y516350D02*
Y512350D01*
X787954D01*
G01X797922Y528308D02*
X793922D01*
Y520908D01*
G01X770117Y503967D02*
Y506467D01*
X771158D01*
X771492Y506342D01*
X771700Y506175D01*
X771783Y505842D01*
X771700Y505509D01*
X771450Y505300D01*
X771158Y505175D01*
X770117D01*
G01X771158D02*
X771783Y503967D01*
G01X773133Y504342D02*
X773383Y504134D01*
X773675Y504009D01*
X774050Y503967D01*
X774425Y504050D01*
X774717Y504217D01*
X774925Y504509D01*
X774967Y504842D01*
X774883Y505175D01*
X774675Y505384D01*
X774383Y505550D01*
X774092Y505592D01*
X773800Y505550D01*
X773425Y505384D01*
X773550Y506467D01*
X774675D01*
G01X777650Y503967D02*
Y506467D01*
X776108Y504675D01*
X778192D01*
G01X780250Y503967D02*
X780542Y504009D01*
X780875Y504134D01*
X781083Y504342D01*
X781167Y504634D01*
X781083Y504925D01*
X780833Y505175D01*
X780458Y505300D01*
X780042D01*
X779792Y505384D01*
X779583Y505592D01*
X779500Y505884D01*
X779625Y506175D01*
X779917Y506384D01*
X780250Y506467D01*
X780583Y506384D01*
X780875Y506175D01*
X781000Y505884D01*
X780917Y505592D01*
X780708Y505384D01*
X780458Y505300D01*
X780042D01*
X779667Y505175D01*
X779417Y504925D01*
X779333Y504634D01*
X779417Y504342D01*
X779625Y504134D01*
X779958Y504009D01*
X780250Y503967D01*
G01X783284Y507600D02*
Y503600D01*
X790684D01*
G01X781517Y485966D02*
Y488466D01*
X782558D01*
X782892Y488341D01*
X783100Y488174D01*
X783183Y487841D01*
X783100Y487508D01*
X782850Y487299D01*
X782558Y487174D01*
X781517D01*
G01X782558D02*
X783183Y485966D01*
G01X784533Y486341D02*
X784783Y486133D01*
X785075Y486008D01*
X785450Y485966D01*
X785825Y486049D01*
X786117Y486216D01*
X786325Y486508D01*
X786367Y486841D01*
X786283Y487174D01*
X786075Y487383D01*
X785783Y487549D01*
X785492Y487591D01*
X785200Y487549D01*
X784825Y487383D01*
X784950Y488466D01*
X786075D01*
G01X787633Y486341D02*
X787883Y486133D01*
X788175Y486008D01*
X788550Y485966D01*
X788925Y486049D01*
X789217Y486216D01*
X789425Y486508D01*
X789467Y486841D01*
X789383Y487174D01*
X789175Y487383D01*
X788883Y487549D01*
X788592Y487591D01*
X788300Y487549D01*
X787925Y487383D01*
X788050Y488466D01*
X789175D01*
G01X790733Y486341D02*
X790983Y486133D01*
X791275Y486008D01*
X791650Y485966D01*
X792025Y486049D01*
X792317Y486216D01*
X792525Y486508D01*
X792567Y486841D01*
X792483Y487174D01*
X792275Y487383D01*
X791983Y487549D01*
X791692Y487591D01*
X791400Y487549D01*
X791025Y487383D01*
X791150Y488466D01*
X792275D01*
G01X775000Y487100D02*
X779000D01*
Y494500D01*
G01X784134Y490317D02*
X781634D01*
Y491358D01*
X781759Y491692D01*
X781926Y491900D01*
X782259Y491983D01*
X782592Y491900D01*
X782801Y491650D01*
X782926Y491358D01*
Y490317D01*
G01Y491358D02*
X784134Y491983D01*
G01X783759Y493333D02*
X783967Y493583D01*
X784092Y493875D01*
X784134Y494250D01*
X784051Y494625D01*
X783884Y494917D01*
X783592Y495125D01*
X783259Y495167D01*
X782926Y495083D01*
X782717Y494875D01*
X782551Y494583D01*
X782509Y494292D01*
X782551Y494000D01*
X782717Y493625D01*
X781634Y493750D01*
Y494875D01*
G01X783092Y496558D02*
X782801Y496850D01*
X782634Y497100D01*
X782551Y497433D01*
X782634Y497725D01*
X782801Y497933D01*
X783051Y498100D01*
X783342Y498142D01*
X783592Y498100D01*
X783842Y497933D01*
X784051Y497683D01*
X784134Y497392D01*
X784051Y497058D01*
X783801Y496767D01*
X783426Y496600D01*
X783009Y496558D01*
X782467Y496642D01*
X782176Y496767D01*
X781884Y496975D01*
X781676Y497267D01*
X781634Y497558D01*
X781717Y497850D01*
X781926Y498058D01*
G01X783759Y499533D02*
X783967Y499783D01*
X784092Y500075D01*
X784134Y500450D01*
X784051Y500825D01*
X783884Y501117D01*
X783592Y501325D01*
X783259Y501367D01*
X782926Y501283D01*
X782717Y501075D01*
X782551Y500783D01*
X782509Y500492D01*
X782551Y500200D01*
X782717Y499825D01*
X781634Y499950D01*
Y501075D01*
G01X779200Y502200D02*
X775200D01*
Y494800D01*
G01X764117Y512167D02*
Y514667D01*
X765158D01*
X765492Y514542D01*
X765700Y514375D01*
X765783Y514042D01*
X765700Y513709D01*
X765450Y513500D01*
X765158Y513375D01*
X764117D01*
G01X765158D02*
X765783Y512167D01*
G01X767133Y512542D02*
X767383Y512334D01*
X767675Y512209D01*
X768050Y512167D01*
X768425Y512250D01*
X768717Y512417D01*
X768925Y512709D01*
X768967Y513042D01*
X768883Y513375D01*
X768675Y513584D01*
X768383Y513750D01*
X768092Y513792D01*
X767800Y513750D01*
X767425Y513584D01*
X767550Y514667D01*
X768675D01*
G01X770233Y512542D02*
X770483Y512334D01*
X770775Y512209D01*
X771150Y512167D01*
X771525Y512250D01*
X771817Y512417D01*
X772025Y512709D01*
X772067Y513042D01*
X771983Y513375D01*
X771775Y513584D01*
X771483Y513750D01*
X771192Y513792D01*
X770900Y513750D01*
X770525Y513584D01*
X770650Y514667D01*
X771775D01*
G01X774250D02*
X773917Y514584D01*
X773667Y514375D01*
X773500Y514125D01*
X773375Y513792D01*
X773333Y513417D01*
X773375Y513042D01*
X773500Y512709D01*
X773667Y512459D01*
X773917Y512250D01*
X774250Y512167D01*
X774583Y512250D01*
X774833Y512459D01*
X775000Y512709D01*
X775125Y513042D01*
X775167Y513417D01*
X775125Y513792D01*
X775000Y514125D01*
X774833Y514375D01*
X774583Y514584D01*
X774250Y514667D01*
G01X775300Y520500D02*
Y516500D01*
X782700D01*
G01X752217Y516667D02*
Y519167D01*
X753258D01*
X753592Y519042D01*
X753800Y518875D01*
X753883Y518542D01*
X753800Y518209D01*
X753550Y518000D01*
X753258Y517875D01*
X752217D01*
G01X753258D02*
X753883Y516667D01*
G01X755233Y517042D02*
X755483Y516834D01*
X755775Y516709D01*
X756150Y516667D01*
X756525Y516750D01*
X756817Y516917D01*
X757025Y517209D01*
X757067Y517542D01*
X756983Y517875D01*
X756775Y518084D01*
X756483Y518250D01*
X756192Y518292D01*
X755900Y518250D01*
X755525Y518084D01*
X755650Y519167D01*
X756775D01*
G01X758333Y517042D02*
X758583Y516834D01*
X758875Y516709D01*
X759250Y516667D01*
X759625Y516750D01*
X759917Y516917D01*
X760125Y517209D01*
X760167Y517542D01*
X760083Y517875D01*
X759875Y518084D01*
X759583Y518250D01*
X759292Y518292D01*
X759000Y518250D01*
X758625Y518084D01*
X758750Y519167D01*
X759875D01*
G01X762350Y516667D02*
Y519167D01*
X761850Y518667D01*
G01Y516667D02*
X762850D01*
G01X773134Y516500D02*
Y520500D01*
X765734D01*
G01X761200Y506200D02*
X757200D01*
Y498800D01*
G01X755099Y528466D02*
X751099D01*
Y521066D01*
G01X778217Y481567D02*
Y484067D01*
X779258D01*
X779592Y483942D01*
X779800Y483775D01*
X779883Y483442D01*
X779800Y483109D01*
X779550Y482900D01*
X779258Y482775D01*
X778217D01*
G01X779258D02*
X779883Y481567D01*
G01X781233Y481942D02*
X781483Y481734D01*
X781775Y481609D01*
X782150Y481567D01*
X782525Y481650D01*
X782817Y481817D01*
X783025Y482109D01*
X783067Y482442D01*
X782983Y482775D01*
X782775Y482984D01*
X782483Y483150D01*
X782192Y483192D01*
X781900Y483150D01*
X781525Y482984D01*
X781650Y484067D01*
X782775D01*
G01X784333Y481942D02*
X784583Y481734D01*
X784875Y481609D01*
X785250Y481567D01*
X785625Y481650D01*
X785917Y481817D01*
X786125Y482109D01*
X786167Y482442D01*
X786083Y482775D01*
X785875Y482984D01*
X785583Y483150D01*
X785292Y483192D01*
X785000Y483150D01*
X784625Y482984D01*
X784750Y484067D01*
X785875D01*
G01X788267Y481567D02*
X788350Y482109D01*
X788475Y482567D01*
X788642Y482984D01*
X788850Y483442D01*
X789183Y484067D01*
X787517D01*
G01X765619Y490799D02*
Y486799D01*
X773019D01*
G01X750899Y528366D02*
X746899D01*
Y520966D01*
G01X749400Y498800D02*
X753400D01*
Y506200D01*
G01X745500Y499300D02*
Y503300D01*
X738100D01*
G01X741800Y510600D02*
Y506600D01*
X749200D01*
G01X775084Y521050D02*
X779084D01*
Y528450D01*
G01X774184Y521250D02*
Y535250D01*
G01X761184Y521250D02*
X774184D01*
G01X761184Y535250D02*
Y521250D01*
G01X793084Y521750D02*
Y535750D01*
G01X780084Y521750D02*
X793084D01*
G01X780084Y535750D02*
Y521750D01*
G01X779967Y479759D02*
X779717Y479884D01*
X779425Y479967D01*
X779092D01*
X778717Y479842D01*
X778425Y479634D01*
X778217Y479384D01*
X778050Y478967D01*
X778008Y478592D01*
X778092Y478217D01*
X778217Y477967D01*
X778467Y477717D01*
X778758Y477550D01*
X779050Y477467D01*
X779342D01*
X779633Y477550D01*
X779883Y477675D01*
X780092Y477842D01*
G01X781358Y479550D02*
X781608Y479800D01*
X781900Y479925D01*
X782233Y479967D01*
X782650Y479884D01*
X782942Y479675D01*
X783025Y479425D01*
X782983Y479175D01*
X782817Y478967D01*
X781983Y478550D01*
X781608Y478259D01*
X781358Y477842D01*
X781275Y477467D01*
X783025D01*
G01X785250D02*
X785542Y477509D01*
X785875Y477634D01*
X786083Y477842D01*
X786167Y478134D01*
X786083Y478425D01*
X785833Y478675D01*
X785458Y478800D01*
X785042D01*
X784792Y478884D01*
X784583Y479092D01*
X784500Y479384D01*
X784625Y479675D01*
X784917Y479884D01*
X785250Y479967D01*
X785583Y479884D01*
X785875Y479675D01*
X786000Y479384D01*
X785917Y479092D01*
X785708Y478884D01*
X785458Y478800D01*
X785042D01*
X784667Y478675D01*
X784417Y478425D01*
X784333Y478134D01*
X784417Y477842D01*
X784625Y477634D01*
X784958Y477509D01*
X785250Y477467D01*
G01X787558Y479550D02*
X787808Y479800D01*
X788100Y479925D01*
X788433Y479967D01*
X788850Y479884D01*
X789142Y479675D01*
X789225Y479425D01*
X789183Y479175D01*
X789017Y478967D01*
X788183Y478550D01*
X787808Y478259D01*
X787558Y477842D01*
X787475Y477467D01*
X789225D01*
G01X738655Y516294D02*
X738530Y516044D01*
X738447Y515752D01*
Y515419D01*
X738572Y515044D01*
X738780Y514752D01*
X739030Y514544D01*
X739447Y514377D01*
X739822Y514335D01*
X740197Y514419D01*
X740447Y514544D01*
X740697Y514794D01*
X740864Y515085D01*
X740947Y515377D01*
Y515669D01*
X740864Y515960D01*
X740739Y516210D01*
X740572Y516419D01*
G01X738864Y517685D02*
X738614Y517935D01*
X738489Y518227D01*
X738447Y518560D01*
X738530Y518977D01*
X738739Y519269D01*
X738989Y519352D01*
X739239Y519310D01*
X739447Y519144D01*
X739864Y518310D01*
X740155Y517935D01*
X740572Y517685D01*
X740947Y517602D01*
Y519352D01*
G01Y521577D02*
X740905Y521869D01*
X740780Y522202D01*
X740572Y522410D01*
X740280Y522494D01*
X739989Y522410D01*
X739739Y522160D01*
X739614Y521785D01*
Y521369D01*
X739530Y521119D01*
X739322Y520910D01*
X739030Y520827D01*
X738739Y520952D01*
X738530Y521244D01*
X738447Y521577D01*
X738530Y521910D01*
X738739Y522202D01*
X739030Y522327D01*
X739322Y522244D01*
X739530Y522035D01*
X739614Y521785D01*
Y521369D01*
X739739Y520994D01*
X739989Y520744D01*
X740280Y520660D01*
X740572Y520744D01*
X740780Y520952D01*
X740905Y521285D01*
X740947Y521577D01*
G01X740572Y523760D02*
X740780Y524010D01*
X740905Y524302D01*
X740947Y524677D01*
X740864Y525052D01*
X740697Y525344D01*
X740405Y525552D01*
X740072Y525594D01*
X739739Y525510D01*
X739530Y525302D01*
X739364Y525010D01*
X739322Y524719D01*
X739364Y524427D01*
X739530Y524052D01*
X738447Y524177D01*
Y525302D01*
G01X779567Y475859D02*
X779317Y475984D01*
X779025Y476067D01*
X778692D01*
X778317Y475942D01*
X778025Y475734D01*
X777817Y475484D01*
X777650Y475067D01*
X777608Y474692D01*
X777692Y474317D01*
X777817Y474067D01*
X778067Y473817D01*
X778358Y473650D01*
X778650Y473567D01*
X778942D01*
X779233Y473650D01*
X779483Y473775D01*
X779692Y473942D01*
G01X780958Y475650D02*
X781208Y475900D01*
X781500Y476025D01*
X781833Y476067D01*
X782250Y475984D01*
X782542Y475775D01*
X782625Y475525D01*
X782583Y475275D01*
X782417Y475067D01*
X781583Y474650D01*
X781208Y474359D01*
X780958Y473942D01*
X780875Y473567D01*
X782625D01*
G01X784058Y474609D02*
X784350Y474900D01*
X784600Y475067D01*
X784933Y475150D01*
X785225Y475067D01*
X785433Y474900D01*
X785600Y474650D01*
X785642Y474359D01*
X785600Y474109D01*
X785433Y473859D01*
X785183Y473650D01*
X784892Y473567D01*
X784558Y473650D01*
X784267Y473900D01*
X784100Y474275D01*
X784058Y474692D01*
X784142Y475234D01*
X784267Y475525D01*
X784475Y475817D01*
X784767Y476025D01*
X785058Y476067D01*
X785350Y475984D01*
X785558Y475775D01*
G01X787867Y473567D02*
X787950Y474109D01*
X788075Y474567D01*
X788242Y474984D01*
X788450Y475442D01*
X788783Y476067D01*
X787117D01*
G01X746200Y468180D02*
Y462980D01*
G01Y468180D02*
X739200D01*
G01X796364Y491000D02*
Y486000D01*
X801364D01*
G01Y513700D02*
X796364D01*
Y508700D01*
G01X797771Y494732D02*
X795771D01*
G01X755922Y487508D02*
Y492508D01*
X750922D01*
G01Y469508D02*
X755922D01*
Y474508D01*
G01X744762Y491466D02*
Y493466D01*
G01X754830Y483374D02*
X757830D01*
G01X753542Y583167D02*
X753417Y582917D01*
X753334Y582625D01*
Y582292D01*
X753459Y581917D01*
X753667Y581625D01*
X753917Y581417D01*
X754334Y581250D01*
X754709Y581208D01*
X755084Y581292D01*
X755334Y581417D01*
X755584Y581667D01*
X755751Y581958D01*
X755834Y582250D01*
Y582542D01*
X755751Y582833D01*
X755626Y583083D01*
X755459Y583292D01*
G01X755834Y585350D02*
X753334D01*
X753834Y584850D01*
G01X755834D02*
Y585850D01*
G01X754792Y587658D02*
X754501Y587950D01*
X754334Y588200D01*
X754251Y588533D01*
X754334Y588825D01*
X754501Y589033D01*
X754751Y589200D01*
X755042Y589242D01*
X755292Y589200D01*
X755542Y589033D01*
X755751Y588783D01*
X755834Y588492D01*
X755751Y588158D01*
X755501Y587867D01*
X755126Y587700D01*
X754709Y587658D01*
X754167Y587742D01*
X753876Y587867D01*
X753584Y588075D01*
X753376Y588367D01*
X753334Y588658D01*
X753417Y588950D01*
X753626Y589158D01*
G01X753751Y590758D02*
X753501Y591008D01*
X753376Y591300D01*
X753334Y591633D01*
X753417Y592050D01*
X753626Y592342D01*
X753876Y592425D01*
X754126Y592383D01*
X754334Y592217D01*
X754751Y591383D01*
X755042Y591008D01*
X755459Y590758D01*
X755834Y590675D01*
Y592425D01*
G01X757542Y583167D02*
X757417Y582917D01*
X757334Y582625D01*
Y582292D01*
X757459Y581917D01*
X757667Y581625D01*
X757917Y581417D01*
X758334Y581250D01*
X758709Y581208D01*
X759084Y581292D01*
X759334Y581417D01*
X759584Y581667D01*
X759751Y581958D01*
X759834Y582250D01*
Y582542D01*
X759751Y582833D01*
X759626Y583083D01*
X759459Y583292D01*
G01X759834Y585350D02*
X757334D01*
X757834Y584850D01*
G01X759834D02*
Y585850D01*
G01X758792Y587658D02*
X758501Y587950D01*
X758334Y588200D01*
X758251Y588533D01*
X758334Y588825D01*
X758501Y589033D01*
X758751Y589200D01*
X759042Y589242D01*
X759292Y589200D01*
X759542Y589033D01*
X759751Y588783D01*
X759834Y588492D01*
X759751Y588158D01*
X759501Y587867D01*
X759126Y587700D01*
X758709Y587658D01*
X758167Y587742D01*
X757876Y587867D01*
X757584Y588075D01*
X757376Y588367D01*
X757334Y588658D01*
X757417Y588950D01*
X757626Y589158D01*
G01X759334Y590633D02*
X759626Y590883D01*
X759792Y591217D01*
X759834Y591592D01*
X759792Y591925D01*
X759584Y592258D01*
X759334Y592467D01*
X759084Y592508D01*
X758792Y592425D01*
X758584Y592133D01*
X758501Y591842D01*
Y591467D01*
G01Y591842D02*
X758376Y592092D01*
X758167Y592300D01*
X757917Y592383D01*
X757667Y592300D01*
X757459Y592092D01*
X757334Y591717D01*
X757376Y591342D01*
X757542Y590967D01*
G01X748907Y534333D02*
X748782Y534083D01*
X748699Y533791D01*
Y533458D01*
X748824Y533083D01*
X749032Y532791D01*
X749282Y532583D01*
X749699Y532416D01*
X750074Y532374D01*
X750449Y532458D01*
X750699Y532583D01*
X750949Y532833D01*
X751116Y533124D01*
X751199Y533416D01*
Y533708D01*
X751116Y533999D01*
X750991Y534249D01*
X750824Y534458D01*
G01X749116Y535724D02*
X748866Y535974D01*
X748741Y536266D01*
X748699Y536599D01*
X748782Y537016D01*
X748991Y537308D01*
X749241Y537391D01*
X749491Y537349D01*
X749699Y537183D01*
X750116Y536349D01*
X750407Y535974D01*
X750824Y535724D01*
X751199Y535641D01*
Y537391D01*
G01Y539616D02*
X751157Y539908D01*
X751032Y540241D01*
X750824Y540449D01*
X750532Y540533D01*
X750241Y540449D01*
X749991Y540199D01*
X749866Y539824D01*
Y539408D01*
X749782Y539158D01*
X749574Y538949D01*
X749282Y538866D01*
X748991Y538991D01*
X748782Y539283D01*
X748699Y539616D01*
X748782Y539949D01*
X748991Y540241D01*
X749282Y540366D01*
X749574Y540283D01*
X749782Y540074D01*
X749866Y539824D01*
Y539408D01*
X749991Y539033D01*
X750241Y538783D01*
X750532Y538699D01*
X750824Y538783D01*
X751032Y538991D01*
X751157Y539324D01*
X751199Y539616D01*
G01X748699Y542716D02*
X748782Y542383D01*
X748991Y542133D01*
X749241Y541966D01*
X749574Y541841D01*
X749949Y541799D01*
X750324Y541841D01*
X750657Y541966D01*
X750907Y542133D01*
X751116Y542383D01*
X751199Y542716D01*
X751116Y543049D01*
X750907Y543299D01*
X750657Y543466D01*
X750324Y543591D01*
X749949Y543633D01*
X749574Y543591D01*
X749241Y543466D01*
X748991Y543299D01*
X748782Y543049D01*
X748699Y542716D01*
G01X796922Y533625D02*
X794422D01*
Y534666D01*
X794547Y535000D01*
X794714Y535208D01*
X795047Y535291D01*
X795380Y535208D01*
X795589Y534958D01*
X795714Y534666D01*
Y533625D01*
G01Y534666D02*
X796922Y535291D01*
G01X796547Y536641D02*
X796755Y536891D01*
X796880Y537183D01*
X796922Y537558D01*
X796839Y537933D01*
X796672Y538225D01*
X796380Y538433D01*
X796047Y538475D01*
X795714Y538391D01*
X795505Y538183D01*
X795339Y537891D01*
X795297Y537600D01*
X795339Y537308D01*
X795505Y536933D01*
X794422Y537058D01*
Y538183D01*
G01X796922Y541158D02*
X794422D01*
X796214Y539616D01*
Y541700D01*
G01X796922Y543675D02*
X796380Y543758D01*
X795922Y543883D01*
X795505Y544050D01*
X795047Y544258D01*
X794422Y544591D01*
Y542925D01*
G01X740954Y589096D02*
Y591596D01*
X741995D01*
X742329Y591471D01*
X742537Y591304D01*
X742620Y590971D01*
X742537Y590638D01*
X742287Y590429D01*
X741995Y590304D01*
X740954D01*
G01X741995D02*
X742620Y589096D01*
G01X745387D02*
Y591596D01*
X743845Y589804D01*
X745929D01*
G01X747195Y590138D02*
X747487Y590429D01*
X747737Y590596D01*
X748070Y590679D01*
X748362Y590596D01*
X748570Y590429D01*
X748737Y590179D01*
X748779Y589888D01*
X748737Y589638D01*
X748570Y589388D01*
X748320Y589179D01*
X748029Y589096D01*
X747695Y589179D01*
X747404Y589429D01*
X747237Y589804D01*
X747195Y590221D01*
X747279Y590763D01*
X747404Y591054D01*
X747612Y591346D01*
X747904Y591554D01*
X748195Y591596D01*
X748487Y591513D01*
X748695Y591304D01*
G01X750170Y589471D02*
X750420Y589263D01*
X750712Y589138D01*
X751087Y589096D01*
X751462Y589179D01*
X751754Y589346D01*
X751962Y589638D01*
X752004Y589971D01*
X751920Y590304D01*
X751712Y590513D01*
X751420Y590679D01*
X751129Y590721D01*
X750837Y590679D01*
X750462Y590513D01*
X750587Y591596D01*
X751712D01*
G01X740954Y593096D02*
Y595596D01*
X741995D01*
X742329Y595471D01*
X742537Y595304D01*
X742620Y594971D01*
X742537Y594638D01*
X742287Y594429D01*
X741995Y594304D01*
X740954D01*
G01X741995D02*
X742620Y593096D01*
G01X745387D02*
Y595596D01*
X743845Y593804D01*
X745929D01*
G01X747195Y594138D02*
X747487Y594429D01*
X747737Y594596D01*
X748070Y594679D01*
X748362Y594596D01*
X748570Y594429D01*
X748737Y594179D01*
X748779Y593888D01*
X748737Y593638D01*
X748570Y593388D01*
X748320Y593179D01*
X748029Y593096D01*
X747695Y593179D01*
X747404Y593429D01*
X747237Y593804D01*
X747195Y594221D01*
X747279Y594763D01*
X747404Y595054D01*
X747612Y595346D01*
X747904Y595554D01*
X748195Y595596D01*
X748487Y595513D01*
X748695Y595304D01*
G01X750170Y593596D02*
X750420Y593304D01*
X750754Y593138D01*
X751129Y593096D01*
X751462Y593138D01*
X751795Y593346D01*
X752004Y593596D01*
X752045Y593846D01*
X751962Y594138D01*
X751670Y594346D01*
X751379Y594429D01*
X751004D01*
G01X751379D02*
X751629Y594554D01*
X751837Y594763D01*
X751920Y595013D01*
X751837Y595263D01*
X751629Y595471D01*
X751254Y595596D01*
X750879Y595554D01*
X750504Y595388D01*
G01X763834Y581417D02*
X761334D01*
Y582458D01*
X761459Y582792D01*
X761626Y583000D01*
X761959Y583083D01*
X762292Y583000D01*
X762501Y582750D01*
X762626Y582458D01*
Y581417D01*
G01Y582458D02*
X763834Y583083D01*
G01Y585850D02*
X761334D01*
X763126Y584308D01*
Y586392D01*
G01X763834Y588367D02*
X763292Y588450D01*
X762834Y588575D01*
X762417Y588742D01*
X761959Y588950D01*
X761334Y589283D01*
Y587617D01*
G01X763834Y592050D02*
X761334D01*
X763126Y590508D01*
Y592592D01*
G01X759834Y567917D02*
X757334D01*
Y568958D01*
X757459Y569292D01*
X757626Y569500D01*
X757959Y569583D01*
X758292Y569500D01*
X758501Y569250D01*
X758626Y568958D01*
Y567917D01*
G01Y568958D02*
X759834Y569583D01*
G01Y572350D02*
X757334D01*
X759126Y570808D01*
Y572892D01*
G01X759834Y574867D02*
X759292Y574950D01*
X758834Y575075D01*
X758417Y575242D01*
X757959Y575450D01*
X757334Y575783D01*
Y574117D01*
G01X759834Y578050D02*
X759792Y578342D01*
X759667Y578675D01*
X759459Y578883D01*
X759167Y578967D01*
X758876Y578883D01*
X758626Y578633D01*
X758501Y578258D01*
Y577842D01*
X758417Y577592D01*
X758209Y577383D01*
X757917Y577300D01*
X757626Y577425D01*
X757417Y577717D01*
X757334Y578050D01*
X757417Y578383D01*
X757626Y578675D01*
X757917Y578800D01*
X758209Y578717D01*
X758417Y578508D01*
X758501Y578258D01*
Y577842D01*
X758626Y577467D01*
X758876Y577217D01*
X759167Y577133D01*
X759459Y577217D01*
X759667Y577425D01*
X759792Y577758D01*
X759834Y578050D01*
G01X747199Y532583D02*
X744699D01*
Y533624D01*
X744824Y533958D01*
X744991Y534166D01*
X745324Y534249D01*
X745657Y534166D01*
X745866Y533916D01*
X745991Y533624D01*
Y532583D01*
G01Y533624D02*
X747199Y534249D01*
G01X746824Y535599D02*
X747032Y535849D01*
X747157Y536141D01*
X747199Y536516D01*
X747116Y536891D01*
X746949Y537183D01*
X746657Y537391D01*
X746324Y537433D01*
X745991Y537349D01*
X745782Y537141D01*
X745616Y536849D01*
X745574Y536558D01*
X745616Y536266D01*
X745782Y535891D01*
X744699Y536016D01*
Y537141D01*
G01X746824Y538699D02*
X747032Y538949D01*
X747157Y539241D01*
X747199Y539616D01*
X747116Y539991D01*
X746949Y540283D01*
X746657Y540491D01*
X746324Y540533D01*
X745991Y540449D01*
X745782Y540241D01*
X745616Y539949D01*
X745574Y539658D01*
X745616Y539366D01*
X745782Y538991D01*
X744699Y539116D01*
Y540241D01*
G01X746157Y541924D02*
X745866Y542216D01*
X745699Y542466D01*
X745616Y542799D01*
X745699Y543091D01*
X745866Y543299D01*
X746116Y543466D01*
X746407Y543508D01*
X746657Y543466D01*
X746907Y543299D01*
X747116Y543049D01*
X747199Y542758D01*
X747116Y542424D01*
X746866Y542133D01*
X746491Y541966D01*
X746074Y541924D01*
X745532Y542008D01*
X745241Y542133D01*
X744949Y542341D01*
X744741Y542633D01*
X744699Y542924D01*
X744782Y543216D01*
X744991Y543424D01*
G01X743699Y532583D02*
X741199D01*
Y533624D01*
X741324Y533958D01*
X741491Y534166D01*
X741824Y534249D01*
X742157Y534166D01*
X742366Y533916D01*
X742491Y533624D01*
Y532583D01*
G01Y533624D02*
X743699Y534249D01*
G01X743324Y535599D02*
X743532Y535849D01*
X743657Y536141D01*
X743699Y536516D01*
X743616Y536891D01*
X743449Y537183D01*
X743157Y537391D01*
X742824Y537433D01*
X742491Y537349D01*
X742282Y537141D01*
X742116Y536849D01*
X742074Y536558D01*
X742116Y536266D01*
X742282Y535891D01*
X741199Y536016D01*
Y537141D01*
G01X743324Y538699D02*
X743532Y538949D01*
X743657Y539241D01*
X743699Y539616D01*
X743616Y539991D01*
X743449Y540283D01*
X743157Y540491D01*
X742824Y540533D01*
X742491Y540449D01*
X742282Y540241D01*
X742116Y539949D01*
X742074Y539658D01*
X742116Y539366D01*
X742282Y538991D01*
X741199Y539116D01*
Y540241D01*
G01X743699Y542716D02*
X743657Y543008D01*
X743532Y543341D01*
X743324Y543549D01*
X743032Y543633D01*
X742741Y543549D01*
X742491Y543299D01*
X742366Y542924D01*
Y542508D01*
X742282Y542258D01*
X742074Y542049D01*
X741782Y541966D01*
X741491Y542091D01*
X741282Y542383D01*
X741199Y542716D01*
X741282Y543049D01*
X741491Y543341D01*
X741782Y543466D01*
X742074Y543383D01*
X742282Y543174D01*
X742366Y542924D01*
Y542508D01*
X742491Y542133D01*
X742741Y541883D01*
X743032Y541799D01*
X743324Y541883D01*
X743532Y542091D01*
X743657Y542424D01*
X743699Y542716D01*
G01X778934Y535417D02*
X776434D01*
Y536458D01*
X776559Y536792D01*
X776726Y537000D01*
X777059Y537083D01*
X777392Y537000D01*
X777601Y536750D01*
X777726Y536458D01*
Y535417D01*
G01Y536458D02*
X778934Y537083D01*
G01X778559Y538433D02*
X778767Y538683D01*
X778892Y538975D01*
X778934Y539350D01*
X778851Y539725D01*
X778684Y540017D01*
X778392Y540225D01*
X778059Y540267D01*
X777726Y540183D01*
X777517Y539975D01*
X777351Y539683D01*
X777309Y539392D01*
X777351Y539100D01*
X777517Y538725D01*
X776434Y538850D01*
Y539975D01*
G01X778559Y541533D02*
X778767Y541783D01*
X778892Y542075D01*
X778934Y542450D01*
X778851Y542825D01*
X778684Y543117D01*
X778392Y543325D01*
X778059Y543367D01*
X777726Y543283D01*
X777517Y543075D01*
X777351Y542783D01*
X777309Y542492D01*
X777351Y542200D01*
X777517Y541825D01*
X776434Y541950D01*
Y543075D01*
G01X776851Y544758D02*
X776601Y545008D01*
X776476Y545300D01*
X776434Y545633D01*
X776517Y546050D01*
X776726Y546342D01*
X776976Y546425D01*
X777226Y546383D01*
X777434Y546217D01*
X777851Y545383D01*
X778142Y545008D01*
X778559Y544758D01*
X778934Y544675D01*
Y546425D01*
G01X769334Y537450D02*
X769292Y537117D01*
X769126Y536825D01*
X768876Y536575D01*
X768584Y536408D01*
X768251Y536325D01*
X767917D01*
X767584Y536408D01*
X767292Y536575D01*
X767042Y536825D01*
X766876Y537117D01*
X766834Y537450D01*
X766876Y537783D01*
X767042Y538075D01*
X767292Y538325D01*
X767584Y538492D01*
X767917Y538575D01*
X768251D01*
X768584Y538492D01*
X768876Y538325D01*
X769126Y538075D01*
X769292Y537783D01*
X769334Y537450D01*
G01X768667Y537783D02*
X769334Y538283D01*
G01X769042Y539842D02*
X769251Y540133D01*
X769334Y540467D01*
X769251Y540800D01*
X769001Y541092D01*
X768626Y541300D01*
X768251Y541383D01*
X767792D01*
X767417Y541300D01*
X767084Y541092D01*
X766917Y540842D01*
X766834Y540550D01*
X766917Y540217D01*
X767084Y539967D01*
X767334Y539800D01*
X767667Y539717D01*
X767959Y539800D01*
X768251Y540008D01*
X768417Y540258D01*
X768459Y540550D01*
X768376Y540883D01*
X768167Y541133D01*
X767792Y541383D01*
G01X774184Y535250D02*
X761184D01*
G01X783350Y539367D02*
X783017Y539409D01*
X782725Y539575D01*
X782475Y539825D01*
X782308Y540117D01*
X782225Y540450D01*
Y540784D01*
X782308Y541117D01*
X782475Y541409D01*
X782725Y541659D01*
X783017Y541825D01*
X783350Y541867D01*
X783683Y541825D01*
X783975Y541659D01*
X784225Y541409D01*
X784392Y541117D01*
X784475Y540784D01*
Y540450D01*
X784392Y540117D01*
X784225Y539825D01*
X783975Y539575D01*
X783683Y539409D01*
X783350Y539367D01*
G01X783683Y540034D02*
X784183Y539367D01*
G01X786450D02*
X786742Y539409D01*
X787075Y539534D01*
X787283Y539742D01*
X787367Y540034D01*
X787283Y540325D01*
X787033Y540575D01*
X786658Y540700D01*
X786242D01*
X785992Y540784D01*
X785783Y540992D01*
X785700Y541284D01*
X785825Y541575D01*
X786117Y541784D01*
X786450Y541867D01*
X786783Y541784D01*
X787075Y541575D01*
X787200Y541284D01*
X787117Y540992D01*
X786908Y540784D01*
X786658Y540700D01*
X786242D01*
X785867Y540575D01*
X785617Y540325D01*
X785533Y540034D01*
X785617Y539742D01*
X785825Y539534D01*
X786158Y539409D01*
X786450Y539367D01*
G01X793084Y535750D02*
X780084D01*
G01X738500Y577117D02*
X739333D01*
Y576367D01*
X739083Y576117D01*
X738792Y575950D01*
X738375Y575867D01*
X737958Y575950D01*
X737667Y576117D01*
X737417Y576367D01*
X737250Y576659D01*
X737167Y576992D01*
Y577284D01*
X737250Y577534D01*
X737417Y577825D01*
X737667Y578075D01*
X737917Y578242D01*
X738250Y578367D01*
X738542D01*
X738875Y578284D01*
X739125Y578117D01*
G01X740558Y577950D02*
X740808Y578200D01*
X741100Y578325D01*
X741433Y578367D01*
X741850Y578284D01*
X742142Y578075D01*
X742225Y577825D01*
X742183Y577575D01*
X742017Y577367D01*
X741183Y576950D01*
X740808Y576659D01*
X740558Y576242D01*
X740475Y575867D01*
X742225D01*
G01X786600Y602700D02*
Y574900D01*
X814400D01*
Y602700D01*
X786600D01*
G01X736534Y602517D02*
X734034D01*
Y603558D01*
X734159Y603892D01*
X734326Y604100D01*
X734659Y604183D01*
X734992Y604100D01*
X735201Y603850D01*
X735326Y603558D01*
Y602517D01*
G01Y603558D02*
X736534Y604183D01*
G01Y606950D02*
X734034D01*
X735826Y605408D01*
Y607492D01*
G01X735492Y608758D02*
X735201Y609050D01*
X735034Y609300D01*
X734951Y609633D01*
X735034Y609925D01*
X735201Y610133D01*
X735451Y610300D01*
X735742Y610342D01*
X735992Y610300D01*
X736242Y610133D01*
X736451Y609883D01*
X736534Y609592D01*
X736451Y609258D01*
X736201Y608967D01*
X735826Y608800D01*
X735409Y608758D01*
X734867Y608842D01*
X734576Y608967D01*
X734284Y609175D01*
X734076Y609467D01*
X734034Y609758D01*
X734117Y610050D01*
X734326Y610258D01*
G01X736534Y612567D02*
X735992Y612650D01*
X735534Y612775D01*
X735117Y612942D01*
X734659Y613150D01*
X734034Y613483D01*
Y611817D01*
G01X740534Y602517D02*
X738034D01*
Y603558D01*
X738159Y603892D01*
X738326Y604100D01*
X738659Y604183D01*
X738992Y604100D01*
X739201Y603850D01*
X739326Y603558D01*
Y602517D01*
G01Y603558D02*
X740534Y604183D01*
G01Y606950D02*
X738034D01*
X739826Y605408D01*
Y607492D01*
G01X740534Y609467D02*
X739992Y609550D01*
X739534Y609675D01*
X739117Y609842D01*
X738659Y610050D01*
X738034Y610383D01*
Y608717D01*
G01X740534Y612650D02*
X738034D01*
X738534Y612150D01*
G01X740534D02*
Y613150D01*
G01X745671Y604946D02*
X743171D01*
Y605987D01*
X743296Y606321D01*
X743463Y606529D01*
X743796Y606612D01*
X744129Y606529D01*
X744338Y606279D01*
X744463Y605987D01*
Y604946D01*
G01Y605987D02*
X745671Y606612D01*
G01Y608796D02*
X745129Y608879D01*
X744671Y609004D01*
X744254Y609171D01*
X743796Y609379D01*
X743171Y609712D01*
Y608046D01*
G01X745671Y611979D02*
X743171D01*
X743671Y611479D01*
G01X745671D02*
Y612479D01*
G01X745171Y614162D02*
X745463Y614412D01*
X745629Y614746D01*
X745671Y615121D01*
X745629Y615454D01*
X745421Y615787D01*
X745171Y615996D01*
X744921Y616037D01*
X744629Y615954D01*
X744421Y615662D01*
X744338Y615371D01*
Y614996D01*
G01Y615371D02*
X744213Y615621D01*
X744004Y615829D01*
X743754Y615912D01*
X743504Y615829D01*
X743296Y615621D01*
X743171Y615246D01*
X743213Y614871D01*
X743379Y614496D01*
G01X763834Y594417D02*
X761334D01*
Y595458D01*
X761459Y595792D01*
X761626Y596000D01*
X761959Y596083D01*
X762292Y596000D01*
X762501Y595750D01*
X762626Y595458D01*
Y594417D01*
G01Y595458D02*
X763834Y596083D01*
G01Y598850D02*
X761334D01*
X763126Y597308D01*
Y599392D01*
G01X763834Y601367D02*
X763292Y601450D01*
X762834Y601575D01*
X762417Y601742D01*
X761959Y601950D01*
X761334Y602283D01*
Y600617D01*
G01X763334Y603633D02*
X763626Y603883D01*
X763792Y604217D01*
X763834Y604592D01*
X763792Y604925D01*
X763584Y605258D01*
X763334Y605467D01*
X763084Y605508D01*
X762792Y605425D01*
X762584Y605133D01*
X762501Y604842D01*
Y604467D01*
G01Y604842D02*
X762376Y605092D01*
X762167Y605300D01*
X761917Y605383D01*
X761667Y605300D01*
X761459Y605092D01*
X761334Y604717D01*
X761376Y604342D01*
X761542Y603967D01*
G01X742704Y599888D02*
X742454Y600013D01*
X742162Y600096D01*
X741829D01*
X741454Y599971D01*
X741162Y599763D01*
X740954Y599513D01*
X740787Y599096D01*
X740745Y598721D01*
X740829Y598346D01*
X740954Y598096D01*
X741204Y597846D01*
X741495Y597679D01*
X741787Y597596D01*
X742079D01*
X742370Y597679D01*
X742620Y597804D01*
X742829Y597971D01*
G01X744887Y597596D02*
Y600096D01*
X744387Y599596D01*
G01Y597596D02*
X745387D01*
G01X747070Y597971D02*
X747320Y597763D01*
X747612Y597638D01*
X747987Y597596D01*
X748362Y597679D01*
X748654Y597846D01*
X748862Y598138D01*
X748904Y598471D01*
X748820Y598804D01*
X748612Y599013D01*
X748320Y599179D01*
X748029Y599221D01*
X747737Y599179D01*
X747362Y599013D01*
X747487Y600096D01*
X748612D01*
G01X750295Y598638D02*
X750587Y598929D01*
X750837Y599096D01*
X751170Y599179D01*
X751462Y599096D01*
X751670Y598929D01*
X751837Y598679D01*
X751879Y598388D01*
X751837Y598138D01*
X751670Y597888D01*
X751420Y597679D01*
X751129Y597596D01*
X750795Y597679D01*
X750504Y597929D01*
X750337Y598304D01*
X750295Y598721D01*
X750379Y599263D01*
X750504Y599554D01*
X750712Y599846D01*
X751004Y600054D01*
X751295Y600096D01*
X751587Y600013D01*
X751795Y599804D01*
G01X753767Y683367D02*
X752100Y685033D01*
X751267Y686700D01*
Y693366D01*
X752100Y695033D01*
X753767Y696700D01*
G01X761033Y693366D02*
X763033Y686700D01*
X765200Y693366D01*
X767367Y686700D01*
X769367Y693366D01*
G01X772800Y686367D02*
X778800Y696700D01*
G01X795000D02*
X799000D01*
G01X797000D02*
Y686700D01*
G01X795000D02*
X799000D01*
G01X807600D02*
X806266Y686867D01*
X805100Y687533D01*
X804100Y688533D01*
X803433Y689700D01*
X803100Y691033D01*
Y692367D01*
X803433Y693700D01*
X804100Y694867D01*
X805100Y695867D01*
X806266Y696533D01*
X807600Y696700D01*
X808933Y696533D01*
X810100Y695867D01*
X811100Y694867D01*
X811767Y693700D01*
X812100Y692367D01*
Y691033D01*
X811767Y689700D01*
X811100Y688533D01*
X810100Y687533D01*
X808933Y686867D01*
X807600Y686700D01*
G01X821867Y695867D02*
X820867Y696367D01*
X819700Y696700D01*
X818367D01*
X816866Y696200D01*
X815700Y695367D01*
X814867Y694367D01*
X814200Y692700D01*
X814033Y691200D01*
X814367Y689700D01*
X814867Y688700D01*
X815867Y687700D01*
X817033Y687033D01*
X818200Y686700D01*
X819367D01*
X820533Y687033D01*
X821533Y687533D01*
X822367Y688200D01*
G01X829633Y683367D02*
X831300Y685033D01*
X832133Y686700D01*
Y693366D01*
X831300Y695033D01*
X829633Y696700D01*
G01X753904Y668489D02*
Y678489D01*
X751904Y676489D01*
G01Y668489D02*
X755904D01*
G01X761337Y672655D02*
X762504Y673822D01*
X763504Y674489D01*
X764837Y674822D01*
X766004Y674489D01*
X766837Y673822D01*
X767504Y672822D01*
X767671Y671656D01*
X767504Y670656D01*
X766837Y669655D01*
X765837Y668822D01*
X764671Y668489D01*
X763337Y668822D01*
X762171Y669822D01*
X761504Y671322D01*
X761337Y672989D01*
X761671Y675155D01*
X762171Y676322D01*
X763004Y677489D01*
X764171Y678322D01*
X765337Y678489D01*
X766504Y678156D01*
X767337Y677322D01*
G01X771437Y670489D02*
X772437Y669322D01*
X773770Y668656D01*
X775271Y668489D01*
X776604Y668656D01*
X777937Y669489D01*
X778771Y670489D01*
X778937Y671489D01*
X778604Y672655D01*
X777437Y673489D01*
X776271Y673822D01*
X774771D01*
G01X776271D02*
X777271Y674322D01*
X778104Y675155D01*
X778437Y676156D01*
X778104Y677156D01*
X777271Y677989D01*
X775771Y678489D01*
X774271Y678322D01*
X772771Y677656D01*
G01X785704Y668489D02*
Y678489D01*
X783704Y676489D01*
G01Y668489D02*
X787704D01*
G01X796304D02*
X797471Y668656D01*
X798804Y669156D01*
X799637Y669989D01*
X799971Y671156D01*
X799637Y672322D01*
X798637Y673322D01*
X797137Y673822D01*
X795471D01*
X794471Y674156D01*
X793637Y674989D01*
X793304Y676156D01*
X793804Y677322D01*
X794970Y678156D01*
X796304Y678489D01*
X797637Y678156D01*
X798804Y677322D01*
X799304Y676156D01*
X798971Y674989D01*
X798137Y674156D01*
X797137Y673822D01*
X795471D01*
X793971Y673322D01*
X792971Y672322D01*
X792637Y671156D01*
X792971Y669989D01*
X793804Y669156D01*
X795137Y668656D01*
X796304Y668489D01*
G01X804737Y671822D02*
X809071D01*
G01X814337Y676822D02*
X815337Y677822D01*
X816504Y678322D01*
X817837Y678489D01*
X819504Y678156D01*
X820671Y677322D01*
X821004Y676322D01*
X820837Y675322D01*
X820171Y674489D01*
X816837Y672822D01*
X815337Y671656D01*
X814337Y669989D01*
X814004Y668489D01*
X821004D01*
G01X807349Y64636D02*
X811349D01*
Y72036D01*
G01X854256Y55169D02*
X851756D01*
Y56210D01*
X851881Y56544D01*
X852048Y56752D01*
X852381Y56835D01*
X852714Y56752D01*
X852923Y56502D01*
X853048Y56210D01*
Y55169D01*
G01Y56210D02*
X854256Y56835D01*
G01Y59019D02*
X853714Y59102D01*
X853256Y59227D01*
X852839Y59394D01*
X852381Y59602D01*
X851756Y59935D01*
Y58269D01*
G01X854256Y62702D02*
X851756D01*
X853548Y61160D01*
Y63244D01*
G01X853214Y64510D02*
X852923Y64802D01*
X852756Y65052D01*
X852673Y65385D01*
X852756Y65677D01*
X852923Y65885D01*
X853173Y66052D01*
X853464Y66094D01*
X853714Y66052D01*
X853964Y65885D01*
X854173Y65635D01*
X854256Y65344D01*
X854173Y65010D01*
X853923Y64719D01*
X853548Y64552D01*
X853131Y64510D01*
X852589Y64594D01*
X852298Y64719D01*
X852006Y64927D01*
X851798Y65219D01*
X851756Y65510D01*
X851839Y65802D01*
X852048Y66010D01*
G01X839300Y55880D02*
X843300D01*
Y63280D01*
G01X811449Y64636D02*
X815449D01*
Y72036D01*
G01X849180Y57500D02*
X849138Y57167D01*
X848972Y56875D01*
X848722Y56625D01*
X848430Y56458D01*
X848097Y56375D01*
X847763D01*
X847430Y56458D01*
X847138Y56625D01*
X846888Y56875D01*
X846722Y57167D01*
X846680Y57500D01*
X846722Y57833D01*
X846888Y58125D01*
X847138Y58375D01*
X847430Y58542D01*
X847763Y58625D01*
X848097D01*
X848430Y58542D01*
X848722Y58375D01*
X848972Y58125D01*
X849138Y57833D01*
X849180Y57500D01*
G01X848513Y57833D02*
X849180Y58333D01*
G01X847097Y59808D02*
X846847Y60058D01*
X846722Y60350D01*
X846680Y60683D01*
X846763Y61100D01*
X846972Y61392D01*
X847222Y61475D01*
X847472Y61433D01*
X847680Y61267D01*
X848097Y60433D01*
X848388Y60058D01*
X848805Y59808D01*
X849180Y59725D01*
Y61475D01*
G01X848888Y62992D02*
X849097Y63283D01*
X849180Y63617D01*
X849097Y63950D01*
X848847Y64242D01*
X848472Y64450D01*
X848097Y64533D01*
X847638D01*
X847263Y64450D01*
X846930Y64242D01*
X846763Y63992D01*
X846680Y63700D01*
X846763Y63367D01*
X846930Y63117D01*
X847180Y62950D01*
X847513Y62867D01*
X847805Y62950D01*
X848097Y63158D01*
X848263Y63408D01*
X848305Y63700D01*
X848222Y64033D01*
X848013Y64283D01*
X847638Y64533D01*
G01X833220Y67800D02*
X819220D01*
G01X833220Y54800D02*
Y67800D01*
G01X819220Y54800D02*
X833220D01*
G01X819220Y67800D02*
Y54800D01*
G01X831617Y42400D02*
Y44900D01*
X832658D01*
X832992Y44775D01*
X833200Y44608D01*
X833283Y44275D01*
X833200Y43942D01*
X832950Y43733D01*
X832658Y43608D01*
X831617D01*
G01X832658D02*
X833283Y42400D01*
G01X835467D02*
X835550Y42942D01*
X835675Y43400D01*
X835842Y43817D01*
X836050Y44275D01*
X836383Y44900D01*
X834717D01*
G01X839150Y42400D02*
Y44900D01*
X837608Y43108D01*
X839692D01*
G01X840833Y42775D02*
X841083Y42567D01*
X841375Y42442D01*
X841750Y42400D01*
X842125Y42483D01*
X842417Y42650D01*
X842625Y42942D01*
X842667Y43275D01*
X842583Y43608D01*
X842375Y43817D01*
X842083Y43983D01*
X841792Y44025D01*
X841500Y43983D01*
X841125Y43817D01*
X841250Y44900D01*
X842375D01*
G01X804117Y40900D02*
Y43400D01*
X805158D01*
X805492Y43275D01*
X805700Y43108D01*
X805783Y42775D01*
X805700Y42442D01*
X805450Y42233D01*
X805158Y42108D01*
X804117D01*
G01X805158D02*
X805783Y40900D01*
G01X808050D02*
X808342Y40942D01*
X808675Y41067D01*
X808883Y41275D01*
X808967Y41567D01*
X808883Y41858D01*
X808633Y42108D01*
X808258Y42233D01*
X807842D01*
X807592Y42317D01*
X807383Y42525D01*
X807300Y42817D01*
X807425Y43108D01*
X807717Y43317D01*
X808050Y43400D01*
X808383Y43317D01*
X808675Y43108D01*
X808800Y42817D01*
X808717Y42525D01*
X808508Y42317D01*
X808258Y42233D01*
X807842D01*
X807467Y42108D01*
X807217Y41858D01*
X807133Y41567D01*
X807217Y41275D01*
X807425Y41067D01*
X807758Y40942D01*
X808050Y40900D01*
G01X811150D02*
Y43400D01*
X810650Y42900D01*
G01Y40900D02*
X811650D01*
G01X814167D02*
X814250Y41442D01*
X814375Y41900D01*
X814542Y42317D01*
X814750Y42775D01*
X815083Y43400D01*
X813417D01*
G01X809219Y15199D02*
X813319D01*
G01X804119Y10099D02*
X809219Y15199D01*
G01X804119Y20299D02*
Y10099D01*
G01X809219Y15199D02*
X804119Y20299D01*
G01X818419Y10099D02*
X813319Y15199D01*
G01X818419Y20299D02*
Y10099D01*
G01X813319Y15199D02*
X818419Y20299D01*
G01Y15199D02*
X822119D01*
G01X809219Y12399D02*
Y18799D01*
G01X813319Y12399D02*
Y18799D01*
G01X809606Y59252D02*
Y58992D01*
X811041Y57557D01*
X812476Y58992D01*
G01X809606Y59252D02*
X812476D01*
Y48252D01*
G01X809606D02*
Y59252D01*
G01Y48252D02*
X812476D01*
G01X810900Y75217D02*
X808400D01*
Y76258D01*
X808525Y76592D01*
X808692Y76800D01*
X809025Y76883D01*
X809358Y76800D01*
X809567Y76550D01*
X809692Y76258D01*
Y75217D01*
G01Y76258D02*
X810900Y76883D01*
G01X809858Y78358D02*
X809567Y78650D01*
X809400Y78900D01*
X809317Y79233D01*
X809400Y79525D01*
X809567Y79733D01*
X809817Y79900D01*
X810108Y79942D01*
X810358Y79900D01*
X810608Y79733D01*
X810817Y79483D01*
X810900Y79192D01*
X810817Y78858D01*
X810567Y78567D01*
X810192Y78400D01*
X809775Y78358D01*
X809233Y78442D01*
X808942Y78567D01*
X808650Y78775D01*
X808442Y79067D01*
X808400Y79358D01*
X808483Y79650D01*
X808692Y79858D01*
G01X808400Y82250D02*
X808483Y81917D01*
X808692Y81667D01*
X808942Y81500D01*
X809275Y81375D01*
X809650Y81333D01*
X810025Y81375D01*
X810358Y81500D01*
X810608Y81667D01*
X810817Y81917D01*
X810900Y82250D01*
X810817Y82583D01*
X810608Y82833D01*
X810358Y83000D01*
X810025Y83125D01*
X809650Y83167D01*
X809275Y83125D01*
X808942Y83000D01*
X808692Y82833D01*
X808483Y82583D01*
X808400Y82250D01*
G01X810608Y84642D02*
X810817Y84933D01*
X810900Y85267D01*
X810817Y85600D01*
X810567Y85892D01*
X810192Y86100D01*
X809817Y86183D01*
X809358D01*
X808983Y86100D01*
X808650Y85892D01*
X808483Y85642D01*
X808400Y85350D01*
X808483Y85017D01*
X808650Y84767D01*
X808900Y84600D01*
X809233Y84517D01*
X809525Y84600D01*
X809817Y84808D01*
X809983Y85058D01*
X810025Y85350D01*
X809942Y85683D01*
X809733Y85933D01*
X809358Y86183D01*
G01X815212Y75320D02*
X812712D01*
Y76361D01*
X812837Y76695D01*
X813004Y76903D01*
X813337Y76986D01*
X813670Y76903D01*
X813879Y76653D01*
X814004Y76361D01*
Y75320D01*
G01Y76361D02*
X815212Y76986D01*
G01X814170Y78461D02*
X813879Y78753D01*
X813712Y79003D01*
X813629Y79336D01*
X813712Y79628D01*
X813879Y79836D01*
X814129Y80003D01*
X814420Y80045D01*
X814670Y80003D01*
X814920Y79836D01*
X815129Y79586D01*
X815212Y79295D01*
X815129Y78961D01*
X814879Y78670D01*
X814504Y78503D01*
X814087Y78461D01*
X813545Y78545D01*
X813254Y78670D01*
X812962Y78878D01*
X812754Y79170D01*
X812712Y79461D01*
X812795Y79753D01*
X813004Y79961D01*
G01X815212Y82353D02*
X812712D01*
X813212Y81853D01*
G01X815212D02*
Y82853D01*
G01Y85953D02*
X812712D01*
X814504Y84411D01*
Y86495D01*
G01X808434Y146717D02*
X805934D01*
Y147758D01*
X806059Y148092D01*
X806226Y148300D01*
X806559Y148383D01*
X806892Y148300D01*
X807101Y148050D01*
X807226Y147758D01*
Y146717D01*
G01Y147758D02*
X808434Y148383D01*
G01X807392Y149858D02*
X807101Y150150D01*
X806934Y150400D01*
X806851Y150733D01*
X806934Y151025D01*
X807101Y151233D01*
X807351Y151400D01*
X807642Y151442D01*
X807892Y151400D01*
X808142Y151233D01*
X808351Y150983D01*
X808434Y150692D01*
X808351Y150358D01*
X808101Y150067D01*
X807726Y149900D01*
X807309Y149858D01*
X806767Y149942D01*
X806476Y150067D01*
X806184Y150275D01*
X805976Y150567D01*
X805934Y150858D01*
X806017Y151150D01*
X806226Y151358D01*
G01X806351Y152958D02*
X806101Y153208D01*
X805976Y153500D01*
X805934Y153833D01*
X806017Y154250D01*
X806226Y154542D01*
X806476Y154625D01*
X806726Y154583D01*
X806934Y154417D01*
X807351Y153583D01*
X807642Y153208D01*
X808059Y152958D01*
X808434Y152875D01*
Y154625D01*
G01X808142Y156142D02*
X808351Y156433D01*
X808434Y156767D01*
X808351Y157100D01*
X808101Y157392D01*
X807726Y157600D01*
X807351Y157683D01*
X806892D01*
X806517Y157600D01*
X806184Y157392D01*
X806017Y157142D01*
X805934Y156850D01*
X806017Y156517D01*
X806184Y156267D01*
X806434Y156100D01*
X806767Y156017D01*
X807059Y156100D01*
X807351Y156308D01*
X807517Y156558D01*
X807559Y156850D01*
X807476Y157183D01*
X807267Y157433D01*
X806892Y157683D01*
G01X803600Y186400D02*
X807600D01*
Y193800D01*
G01X803934Y146717D02*
X801434D01*
Y147758D01*
X801559Y148092D01*
X801726Y148300D01*
X802059Y148383D01*
X802392Y148300D01*
X802601Y148050D01*
X802726Y147758D01*
Y146717D01*
G01Y147758D02*
X803934Y148383D01*
G01X802892Y149858D02*
X802601Y150150D01*
X802434Y150400D01*
X802351Y150733D01*
X802434Y151025D01*
X802601Y151233D01*
X802851Y151400D01*
X803142Y151442D01*
X803392Y151400D01*
X803642Y151233D01*
X803851Y150983D01*
X803934Y150692D01*
X803851Y150358D01*
X803601Y150067D01*
X803226Y149900D01*
X802809Y149858D01*
X802267Y149942D01*
X801976Y150067D01*
X801684Y150275D01*
X801476Y150567D01*
X801434Y150858D01*
X801517Y151150D01*
X801726Y151358D01*
G01X803434Y152833D02*
X803726Y153083D01*
X803892Y153417D01*
X803934Y153792D01*
X803892Y154125D01*
X803684Y154458D01*
X803434Y154667D01*
X803184Y154708D01*
X802892Y154625D01*
X802684Y154333D01*
X802601Y154042D01*
Y153667D01*
G01Y154042D02*
X802476Y154292D01*
X802267Y154500D01*
X802017Y154583D01*
X801767Y154500D01*
X801559Y154292D01*
X801434Y153917D01*
X801476Y153542D01*
X801642Y153167D01*
G01X803934Y156850D02*
X801434D01*
X801934Y156350D01*
G01X803934D02*
Y157350D01*
G01X812934Y146717D02*
X810434D01*
Y147758D01*
X810559Y148092D01*
X810726Y148300D01*
X811059Y148383D01*
X811392Y148300D01*
X811601Y148050D01*
X811726Y147758D01*
Y146717D01*
G01Y147758D02*
X812934Y148383D01*
G01X811892Y149858D02*
X811601Y150150D01*
X811434Y150400D01*
X811351Y150733D01*
X811434Y151025D01*
X811601Y151233D01*
X811851Y151400D01*
X812142Y151442D01*
X812392Y151400D01*
X812642Y151233D01*
X812851Y150983D01*
X812934Y150692D01*
X812851Y150358D01*
X812601Y150067D01*
X812226Y149900D01*
X811809Y149858D01*
X811267Y149942D01*
X810976Y150067D01*
X810684Y150275D01*
X810476Y150567D01*
X810434Y150858D01*
X810517Y151150D01*
X810726Y151358D01*
G01X812434Y152833D02*
X812726Y153083D01*
X812892Y153417D01*
X812934Y153792D01*
X812892Y154125D01*
X812684Y154458D01*
X812434Y154667D01*
X812184Y154708D01*
X811892Y154625D01*
X811684Y154333D01*
X811601Y154042D01*
Y153667D01*
G01Y154042D02*
X811476Y154292D01*
X811267Y154500D01*
X811017Y154583D01*
X810767Y154500D01*
X810559Y154292D01*
X810434Y153917D01*
X810476Y153542D01*
X810642Y153167D01*
G01X812559Y155933D02*
X812767Y156183D01*
X812892Y156475D01*
X812934Y156850D01*
X812851Y157225D01*
X812684Y157517D01*
X812392Y157725D01*
X812059Y157767D01*
X811726Y157683D01*
X811517Y157475D01*
X811351Y157183D01*
X811309Y156892D01*
X811351Y156600D01*
X811517Y156225D01*
X810434Y156350D01*
Y157475D01*
G01X808600Y186400D02*
X812600D01*
Y193800D01*
G01X810334Y162800D02*
X812834D01*
G01X810334Y161842D02*
Y163758D01*
G01X812834Y165067D02*
X810334D01*
Y166067D01*
X810459Y166400D01*
X810751Y166650D01*
X811084Y166733D01*
X811417Y166650D01*
X811667Y166442D01*
X811792Y166067D01*
Y165067D01*
G01X812834Y169000D02*
X810334D01*
X810834Y168500D01*
G01X812834D02*
Y169500D01*
G01X812334Y171183D02*
X812626Y171433D01*
X812792Y171767D01*
X812834Y172142D01*
X812792Y172475D01*
X812584Y172808D01*
X812334Y173017D01*
X812084Y173058D01*
X811792Y172975D01*
X811584Y172683D01*
X811501Y172392D01*
Y172017D01*
G01Y172392D02*
X811376Y172642D01*
X811167Y172850D01*
X810917Y172933D01*
X810667Y172850D01*
X810459Y172642D01*
X810334Y172267D01*
X810376Y171892D01*
X810542Y171517D01*
G01X811792Y174408D02*
X811501Y174700D01*
X811334Y174950D01*
X811251Y175283D01*
X811334Y175575D01*
X811501Y175783D01*
X811751Y175950D01*
X812042Y175992D01*
X812292Y175950D01*
X812542Y175783D01*
X812751Y175533D01*
X812834Y175242D01*
X812751Y174908D01*
X812501Y174617D01*
X812126Y174450D01*
X811709Y174408D01*
X811167Y174492D01*
X810876Y174617D01*
X810584Y174825D01*
X810376Y175117D01*
X810334Y175408D01*
X810417Y175700D01*
X810626Y175908D01*
G01X799534Y162800D02*
X802034D01*
G01X799534Y161842D02*
Y163758D01*
G01X802034Y165067D02*
X799534D01*
Y166067D01*
X799659Y166400D01*
X799951Y166650D01*
X800284Y166733D01*
X800617Y166650D01*
X800867Y166442D01*
X800992Y166067D01*
Y165067D01*
G01X802034Y169000D02*
X799534D01*
X800034Y168500D01*
G01X802034D02*
Y169500D01*
G01Y172600D02*
X799534D01*
X801326Y171058D01*
Y173142D01*
G01X802034Y175200D02*
X799534D01*
X800034Y174700D01*
G01X802034D02*
Y175700D01*
G01X804934Y162900D02*
X807434D01*
G01X804934Y161942D02*
Y163858D01*
G01X807434Y165167D02*
X804934D01*
Y166167D01*
X805059Y166500D01*
X805351Y166750D01*
X805684Y166833D01*
X806017Y166750D01*
X806267Y166542D01*
X806392Y166167D01*
Y165167D01*
G01X807434Y169100D02*
X804934D01*
X805434Y168600D01*
G01X807434D02*
Y169600D01*
G01Y172700D02*
X804934D01*
X806726Y171158D01*
Y173242D01*
G01X807434Y175800D02*
X804934D01*
X806726Y174258D01*
Y176342D01*
G01X822033Y199167D02*
Y197375D01*
X822200Y197000D01*
X822533Y196750D01*
X822950Y196667D01*
X823367Y196750D01*
X823700Y197000D01*
X823867Y197375D01*
Y199167D01*
G01X826050Y196667D02*
Y199167D01*
X825550Y198667D01*
G01Y196667D02*
X826550D01*
G01X808268Y217204D02*
Y295394D01*
G01Y208936D02*
Y213504D01*
G01X806418Y207086D02*
X801850D01*
G01X810118D02*
G02I-1850J0D01*
G01Y215354D02*
G02I-1850J0D01*
G01X861267Y239959D02*
X861017Y240084D01*
X860725Y240167D01*
X860392D01*
X860017Y240042D01*
X859725Y239834D01*
X859517Y239584D01*
X859350Y239167D01*
X859308Y238792D01*
X859392Y238417D01*
X859517Y238167D01*
X859767Y237917D01*
X860058Y237750D01*
X860350Y237667D01*
X860642D01*
X860933Y237750D01*
X861183Y237875D01*
X861392Y238042D01*
G01X862533Y238167D02*
X862783Y237875D01*
X863117Y237709D01*
X863492Y237667D01*
X863825Y237709D01*
X864158Y237917D01*
X864367Y238167D01*
X864408Y238417D01*
X864325Y238709D01*
X864033Y238917D01*
X863742Y239000D01*
X863367D01*
G01X863742D02*
X863992Y239125D01*
X864200Y239334D01*
X864283Y239584D01*
X864200Y239834D01*
X863992Y240042D01*
X863617Y240167D01*
X863242Y240125D01*
X862867Y239959D01*
G01X865758Y239750D02*
X866008Y240000D01*
X866300Y240125D01*
X866633Y240167D01*
X867050Y240084D01*
X867342Y239875D01*
X867425Y239625D01*
X867383Y239375D01*
X867217Y239167D01*
X866383Y238750D01*
X866008Y238459D01*
X865758Y238042D01*
X865675Y237667D01*
X867425D01*
G01X869650Y240167D02*
X869317Y240084D01*
X869067Y239875D01*
X868900Y239625D01*
X868775Y239292D01*
X868733Y238917D01*
X868775Y238542D01*
X868900Y238209D01*
X869067Y237959D01*
X869317Y237750D01*
X869650Y237667D01*
X869983Y237750D01*
X870233Y237959D01*
X870400Y238209D01*
X870525Y238542D01*
X870567Y238917D01*
X870525Y239292D01*
X870400Y239625D01*
X870233Y239875D01*
X869983Y240084D01*
X869650Y240167D01*
G01X861267Y243959D02*
X861017Y244084D01*
X860725Y244167D01*
X860392D01*
X860017Y244042D01*
X859725Y243834D01*
X859517Y243584D01*
X859350Y243167D01*
X859308Y242792D01*
X859392Y242417D01*
X859517Y242167D01*
X859767Y241917D01*
X860058Y241750D01*
X860350Y241667D01*
X860642D01*
X860933Y241750D01*
X861183Y241875D01*
X861392Y242042D01*
G01X862533Y242167D02*
X862783Y241875D01*
X863117Y241709D01*
X863492Y241667D01*
X863825Y241709D01*
X864158Y241917D01*
X864367Y242167D01*
X864408Y242417D01*
X864325Y242709D01*
X864033Y242917D01*
X863742Y243000D01*
X863367D01*
G01X863742D02*
X863992Y243125D01*
X864200Y243334D01*
X864283Y243584D01*
X864200Y243834D01*
X863992Y244042D01*
X863617Y244167D01*
X863242Y244125D01*
X862867Y243959D01*
G01X866550Y241667D02*
Y244167D01*
X866050Y243667D01*
G01Y241667D02*
X867050D01*
G01X868942Y241959D02*
X869233Y241750D01*
X869567Y241667D01*
X869900Y241750D01*
X870192Y242000D01*
X870400Y242375D01*
X870483Y242750D01*
Y243209D01*
X870400Y243584D01*
X870192Y243917D01*
X869942Y244084D01*
X869650Y244167D01*
X869317Y244084D01*
X869067Y243917D01*
X868900Y243667D01*
X868817Y243334D01*
X868900Y243042D01*
X869108Y242750D01*
X869358Y242584D01*
X869650Y242542D01*
X869983Y242625D01*
X870233Y242834D01*
X870483Y243209D01*
G01X861267Y251459D02*
X861017Y251584D01*
X860725Y251667D01*
X860392D01*
X860017Y251542D01*
X859725Y251334D01*
X859517Y251084D01*
X859350Y250667D01*
X859308Y250292D01*
X859392Y249917D01*
X859517Y249667D01*
X859767Y249417D01*
X860058Y249250D01*
X860350Y249167D01*
X860642D01*
X860933Y249250D01*
X861183Y249375D01*
X861392Y249542D01*
G01X862533Y249667D02*
X862783Y249375D01*
X863117Y249209D01*
X863492Y249167D01*
X863825Y249209D01*
X864158Y249417D01*
X864367Y249667D01*
X864408Y249917D01*
X864325Y250209D01*
X864033Y250417D01*
X863742Y250500D01*
X863367D01*
G01X863742D02*
X863992Y250625D01*
X864200Y250834D01*
X864283Y251084D01*
X864200Y251334D01*
X863992Y251542D01*
X863617Y251667D01*
X863242Y251625D01*
X862867Y251459D01*
G01X866550Y249167D02*
Y251667D01*
X866050Y251167D01*
G01Y249167D02*
X867050D01*
G01X869650D02*
X869942Y249209D01*
X870275Y249334D01*
X870483Y249542D01*
X870567Y249834D01*
X870483Y250125D01*
X870233Y250375D01*
X869858Y250500D01*
X869442D01*
X869192Y250584D01*
X868983Y250792D01*
X868900Y251084D01*
X869025Y251375D01*
X869317Y251584D01*
X869650Y251667D01*
X869983Y251584D01*
X870275Y251375D01*
X870400Y251084D01*
X870317Y250792D01*
X870108Y250584D01*
X869858Y250500D01*
X869442D01*
X869067Y250375D01*
X868817Y250125D01*
X868733Y249834D01*
X868817Y249542D01*
X869025Y249334D01*
X869358Y249209D01*
X869650Y249167D01*
G01X861267Y255459D02*
X861017Y255584D01*
X860725Y255667D01*
X860392D01*
X860017Y255542D01*
X859725Y255334D01*
X859517Y255084D01*
X859350Y254667D01*
X859308Y254292D01*
X859392Y253917D01*
X859517Y253667D01*
X859767Y253417D01*
X860058Y253250D01*
X860350Y253167D01*
X860642D01*
X860933Y253250D01*
X861183Y253375D01*
X861392Y253542D01*
G01X862533Y253667D02*
X862783Y253375D01*
X863117Y253209D01*
X863492Y253167D01*
X863825Y253209D01*
X864158Y253417D01*
X864367Y253667D01*
X864408Y253917D01*
X864325Y254209D01*
X864033Y254417D01*
X863742Y254500D01*
X863367D01*
G01X863742D02*
X863992Y254625D01*
X864200Y254834D01*
X864283Y255084D01*
X864200Y255334D01*
X863992Y255542D01*
X863617Y255667D01*
X863242Y255625D01*
X862867Y255459D01*
G01X866550Y253167D02*
Y255667D01*
X866050Y255167D01*
G01Y253167D02*
X867050D01*
G01X869567D02*
X869650Y253709D01*
X869775Y254167D01*
X869942Y254584D01*
X870150Y255042D01*
X870483Y255667D01*
X868817D01*
G01X861267Y263459D02*
X861017Y263584D01*
X860725Y263667D01*
X860392D01*
X860017Y263542D01*
X859725Y263334D01*
X859517Y263084D01*
X859350Y262667D01*
X859308Y262292D01*
X859392Y261917D01*
X859517Y261667D01*
X859767Y261417D01*
X860058Y261250D01*
X860350Y261167D01*
X860642D01*
X860933Y261250D01*
X861183Y261375D01*
X861392Y261542D01*
G01X862533Y261667D02*
X862783Y261375D01*
X863117Y261209D01*
X863492Y261167D01*
X863825Y261209D01*
X864158Y261417D01*
X864367Y261667D01*
X864408Y261917D01*
X864325Y262209D01*
X864033Y262417D01*
X863742Y262500D01*
X863367D01*
G01X863742D02*
X863992Y262625D01*
X864200Y262834D01*
X864283Y263084D01*
X864200Y263334D01*
X863992Y263542D01*
X863617Y263667D01*
X863242Y263625D01*
X862867Y263459D01*
G01X866550Y261167D02*
Y263667D01*
X866050Y263167D01*
G01Y261167D02*
X867050D01*
G01X868858Y262209D02*
X869150Y262500D01*
X869400Y262667D01*
X869733Y262750D01*
X870025Y262667D01*
X870233Y262500D01*
X870400Y262250D01*
X870442Y261959D01*
X870400Y261709D01*
X870233Y261459D01*
X869983Y261250D01*
X869692Y261167D01*
X869358Y261250D01*
X869067Y261500D01*
X868900Y261875D01*
X868858Y262292D01*
X868942Y262834D01*
X869067Y263125D01*
X869275Y263417D01*
X869567Y263625D01*
X869858Y263667D01*
X870150Y263584D01*
X870358Y263375D01*
G01X861267Y267459D02*
X861017Y267584D01*
X860725Y267667D01*
X860392D01*
X860017Y267542D01*
X859725Y267334D01*
X859517Y267084D01*
X859350Y266667D01*
X859308Y266292D01*
X859392Y265917D01*
X859517Y265667D01*
X859767Y265417D01*
X860058Y265250D01*
X860350Y265167D01*
X860642D01*
X860933Y265250D01*
X861183Y265375D01*
X861392Y265542D01*
G01X862533Y265667D02*
X862783Y265375D01*
X863117Y265209D01*
X863492Y265167D01*
X863825Y265209D01*
X864158Y265417D01*
X864367Y265667D01*
X864408Y265917D01*
X864325Y266209D01*
X864033Y266417D01*
X863742Y266500D01*
X863367D01*
G01X863742D02*
X863992Y266625D01*
X864200Y266834D01*
X864283Y267084D01*
X864200Y267334D01*
X863992Y267542D01*
X863617Y267667D01*
X863242Y267625D01*
X862867Y267459D01*
G01X866550Y265167D02*
Y267667D01*
X866050Y267167D01*
G01Y265167D02*
X867050D01*
G01X868733Y265542D02*
X868983Y265334D01*
X869275Y265209D01*
X869650Y265167D01*
X870025Y265250D01*
X870317Y265417D01*
X870525Y265709D01*
X870567Y266042D01*
X870483Y266375D01*
X870275Y266584D01*
X869983Y266750D01*
X869692Y266792D01*
X869400Y266750D01*
X869025Y266584D01*
X869150Y267667D01*
X870275D01*
G01X862767Y231959D02*
X862517Y232084D01*
X862225Y232167D01*
X861892D01*
X861517Y232042D01*
X861225Y231834D01*
X861017Y231584D01*
X860850Y231167D01*
X860808Y230792D01*
X860892Y230417D01*
X861017Y230167D01*
X861267Y229917D01*
X861558Y229750D01*
X861850Y229667D01*
X862142D01*
X862433Y229750D01*
X862683Y229875D01*
X862892Y230042D01*
G01X864033Y230167D02*
X864283Y229875D01*
X864617Y229709D01*
X864992Y229667D01*
X865325Y229709D01*
X865658Y229917D01*
X865867Y230167D01*
X865908Y230417D01*
X865825Y230709D01*
X865533Y230917D01*
X865242Y231000D01*
X864867D01*
G01X865242D02*
X865492Y231125D01*
X865700Y231334D01*
X865783Y231584D01*
X865700Y231834D01*
X865492Y232042D01*
X865117Y232167D01*
X864742Y232125D01*
X864367Y231959D01*
G01X867258Y231750D02*
X867508Y232000D01*
X867800Y232125D01*
X868133Y232167D01*
X868550Y232084D01*
X868842Y231875D01*
X868925Y231625D01*
X868883Y231375D01*
X868717Y231167D01*
X867883Y230750D01*
X867508Y230459D01*
X867258Y230042D01*
X867175Y229667D01*
X868925D01*
G01X871150D02*
Y232167D01*
X870650Y231667D01*
G01Y229667D02*
X871650D01*
G01X862767Y227459D02*
X862517Y227584D01*
X862225Y227667D01*
X861892D01*
X861517Y227542D01*
X861225Y227334D01*
X861017Y227084D01*
X860850Y226667D01*
X860808Y226292D01*
X860892Y225917D01*
X861017Y225667D01*
X861267Y225417D01*
X861558Y225250D01*
X861850Y225167D01*
X862142D01*
X862433Y225250D01*
X862683Y225375D01*
X862892Y225542D01*
G01X864033Y225667D02*
X864283Y225375D01*
X864617Y225209D01*
X864992Y225167D01*
X865325Y225209D01*
X865658Y225417D01*
X865867Y225667D01*
X865908Y225917D01*
X865825Y226209D01*
X865533Y226417D01*
X865242Y226500D01*
X864867D01*
G01X865242D02*
X865492Y226625D01*
X865700Y226834D01*
X865783Y227084D01*
X865700Y227334D01*
X865492Y227542D01*
X865117Y227667D01*
X864742Y227625D01*
X864367Y227459D01*
G01X867258Y227250D02*
X867508Y227500D01*
X867800Y227625D01*
X868133Y227667D01*
X868550Y227584D01*
X868842Y227375D01*
X868925Y227125D01*
X868883Y226875D01*
X868717Y226667D01*
X867883Y226250D01*
X867508Y225959D01*
X867258Y225542D01*
X867175Y225167D01*
X868925D01*
G01X870358Y227250D02*
X870608Y227500D01*
X870900Y227625D01*
X871233Y227667D01*
X871650Y227584D01*
X871942Y227375D01*
X872025Y227125D01*
X871983Y226875D01*
X871817Y226667D01*
X870983Y226250D01*
X870608Y225959D01*
X870358Y225542D01*
X870275Y225167D01*
X872025D01*
G01X827917Y322800D02*
Y325300D01*
X828958D01*
X829292Y325175D01*
X829500Y325008D01*
X829583Y324675D01*
X829500Y324342D01*
X829250Y324133D01*
X828958Y324008D01*
X827917D01*
G01X828958D02*
X829583Y322800D01*
G01X830933Y323175D02*
X831183Y322967D01*
X831475Y322842D01*
X831850Y322800D01*
X832225Y322883D01*
X832517Y323050D01*
X832725Y323342D01*
X832767Y323675D01*
X832683Y324008D01*
X832475Y324217D01*
X832183Y324383D01*
X831892Y324425D01*
X831600Y324383D01*
X831225Y324217D01*
X831350Y325300D01*
X832475D01*
G01X834867Y322800D02*
X834950Y323342D01*
X835075Y323800D01*
X835242Y324217D01*
X835450Y324675D01*
X835783Y325300D01*
X834117D01*
G01X838050D02*
X837717Y325217D01*
X837467Y325008D01*
X837300Y324758D01*
X837175Y324425D01*
X837133Y324050D01*
X837175Y323675D01*
X837300Y323342D01*
X837467Y323092D01*
X837717Y322883D01*
X838050Y322800D01*
X838383Y322883D01*
X838633Y323092D01*
X838800Y323342D01*
X838925Y323675D01*
X838967Y324050D01*
X838925Y324425D01*
X838800Y324758D01*
X838633Y325008D01*
X838383Y325217D01*
X838050Y325300D01*
G01X817200Y320500D02*
Y324500D01*
X809800D01*
G01X833017Y318267D02*
Y320767D01*
X834058D01*
X834392Y320642D01*
X834600Y320475D01*
X834683Y320142D01*
X834600Y319809D01*
X834350Y319600D01*
X834058Y319475D01*
X833017D01*
G01X834058D02*
X834683Y318267D01*
G01X836033Y318642D02*
X836283Y318434D01*
X836575Y318309D01*
X836950Y318267D01*
X837325Y318350D01*
X837617Y318517D01*
X837825Y318809D01*
X837867Y319142D01*
X837783Y319475D01*
X837575Y319684D01*
X837283Y319850D01*
X836992Y319892D01*
X836700Y319850D01*
X836325Y319684D01*
X836450Y320767D01*
X837575D01*
G01X839258Y319309D02*
X839550Y319600D01*
X839800Y319767D01*
X840133Y319850D01*
X840425Y319767D01*
X840633Y319600D01*
X840800Y319350D01*
X840842Y319059D01*
X840800Y318809D01*
X840633Y318559D01*
X840383Y318350D01*
X840092Y318267D01*
X839758Y318350D01*
X839467Y318600D01*
X839300Y318975D01*
X839258Y319392D01*
X839342Y319934D01*
X839467Y320225D01*
X839675Y320517D01*
X839967Y320725D01*
X840258Y320767D01*
X840550Y320684D01*
X840758Y320475D01*
G01X842442Y318559D02*
X842733Y318350D01*
X843067Y318267D01*
X843400Y318350D01*
X843692Y318600D01*
X843900Y318975D01*
X843983Y319350D01*
Y319809D01*
X843900Y320184D01*
X843692Y320517D01*
X843442Y320684D01*
X843150Y320767D01*
X842817Y320684D01*
X842567Y320517D01*
X842400Y320267D01*
X842317Y319934D01*
X842400Y319642D01*
X842608Y319350D01*
X842858Y319184D01*
X843150Y319142D01*
X843483Y319225D01*
X843733Y319434D01*
X843983Y319809D01*
G01X817800Y324500D02*
Y320500D01*
X825200D01*
G01X808268Y303662D02*
Y299094D01*
G01X806418Y305512D02*
X801850D01*
G01X810118D02*
G02I-1850J0D01*
G01Y297244D02*
G02I-1850J0D01*
G01X863667Y274359D02*
X863417Y274484D01*
X863125Y274567D01*
X862792D01*
X862417Y274442D01*
X862125Y274234D01*
X861917Y273984D01*
X861750Y273567D01*
X861708Y273192D01*
X861792Y272817D01*
X861917Y272567D01*
X862167Y272317D01*
X862458Y272150D01*
X862750Y272067D01*
X863042D01*
X863333Y272150D01*
X863583Y272275D01*
X863792Y272442D01*
G01X864933Y272567D02*
X865183Y272275D01*
X865517Y272109D01*
X865892Y272067D01*
X866225Y272109D01*
X866558Y272317D01*
X866767Y272567D01*
X866808Y272817D01*
X866725Y273109D01*
X866433Y273317D01*
X866142Y273400D01*
X865767D01*
G01X866142D02*
X866392Y273525D01*
X866600Y273734D01*
X866683Y273984D01*
X866600Y274234D01*
X866392Y274442D01*
X866017Y274567D01*
X865642Y274525D01*
X865267Y274359D01*
G01X868950Y272067D02*
Y274567D01*
X868450Y274067D01*
G01Y272067D02*
X869450D01*
G01X872550D02*
Y274567D01*
X871008Y272775D01*
X873092D01*
G01X863667Y278359D02*
X863417Y278484D01*
X863125Y278567D01*
X862792D01*
X862417Y278442D01*
X862125Y278234D01*
X861917Y277984D01*
X861750Y277567D01*
X861708Y277192D01*
X861792Y276817D01*
X861917Y276567D01*
X862167Y276317D01*
X862458Y276150D01*
X862750Y276067D01*
X863042D01*
X863333Y276150D01*
X863583Y276275D01*
X863792Y276442D01*
G01X864933Y276567D02*
X865183Y276275D01*
X865517Y276109D01*
X865892Y276067D01*
X866225Y276109D01*
X866558Y276317D01*
X866767Y276567D01*
X866808Y276817D01*
X866725Y277109D01*
X866433Y277317D01*
X866142Y277400D01*
X865767D01*
G01X866142D02*
X866392Y277525D01*
X866600Y277734D01*
X866683Y277984D01*
X866600Y278234D01*
X866392Y278442D01*
X866017Y278567D01*
X865642Y278525D01*
X865267Y278359D01*
G01X868950Y276067D02*
Y278567D01*
X868450Y278067D01*
G01Y276067D02*
X869450D01*
G01X871133Y276567D02*
X871383Y276275D01*
X871717Y276109D01*
X872092Y276067D01*
X872425Y276109D01*
X872758Y276317D01*
X872967Y276567D01*
X873008Y276817D01*
X872925Y277109D01*
X872633Y277317D01*
X872342Y277400D01*
X871967D01*
G01X872342D02*
X872592Y277525D01*
X872800Y277734D01*
X872883Y277984D01*
X872800Y278234D01*
X872592Y278442D01*
X872217Y278567D01*
X871842Y278525D01*
X871467Y278359D01*
G01X863667Y282859D02*
X863417Y282984D01*
X863125Y283067D01*
X862792D01*
X862417Y282942D01*
X862125Y282734D01*
X861917Y282484D01*
X861750Y282067D01*
X861708Y281692D01*
X861792Y281317D01*
X861917Y281067D01*
X862167Y280817D01*
X862458Y280650D01*
X862750Y280567D01*
X863042D01*
X863333Y280650D01*
X863583Y280775D01*
X863792Y280942D01*
G01X864933Y281067D02*
X865183Y280775D01*
X865517Y280609D01*
X865892Y280567D01*
X866225Y280609D01*
X866558Y280817D01*
X866767Y281067D01*
X866808Y281317D01*
X866725Y281609D01*
X866433Y281817D01*
X866142Y281900D01*
X865767D01*
G01X866142D02*
X866392Y282025D01*
X866600Y282234D01*
X866683Y282484D01*
X866600Y282734D01*
X866392Y282942D01*
X866017Y283067D01*
X865642Y283025D01*
X865267Y282859D01*
G01X868950Y280567D02*
Y283067D01*
X868450Y282567D01*
G01Y280567D02*
X869450D01*
G01X871258Y282650D02*
X871508Y282900D01*
X871800Y283025D01*
X872133Y283067D01*
X872550Y282984D01*
X872842Y282775D01*
X872925Y282525D01*
X872883Y282275D01*
X872717Y282067D01*
X871883Y281650D01*
X871508Y281359D01*
X871258Y280942D01*
X871175Y280567D01*
X872925D01*
G01X863667Y286859D02*
X863417Y286984D01*
X863125Y287067D01*
X862792D01*
X862417Y286942D01*
X862125Y286734D01*
X861917Y286484D01*
X861750Y286067D01*
X861708Y285692D01*
X861792Y285317D01*
X861917Y285067D01*
X862167Y284817D01*
X862458Y284650D01*
X862750Y284567D01*
X863042D01*
X863333Y284650D01*
X863583Y284775D01*
X863792Y284942D01*
G01X864933Y285067D02*
X865183Y284775D01*
X865517Y284609D01*
X865892Y284567D01*
X866225Y284609D01*
X866558Y284817D01*
X866767Y285067D01*
X866808Y285317D01*
X866725Y285609D01*
X866433Y285817D01*
X866142Y285900D01*
X865767D01*
G01X866142D02*
X866392Y286025D01*
X866600Y286234D01*
X866683Y286484D01*
X866600Y286734D01*
X866392Y286942D01*
X866017Y287067D01*
X865642Y287025D01*
X865267Y286859D01*
G01X868950Y284567D02*
Y287067D01*
X868450Y286567D01*
G01Y284567D02*
X869450D01*
G01X872050D02*
Y287067D01*
X871550Y286567D01*
G01Y284567D02*
X872550D01*
G01X863167Y292359D02*
X862917Y292484D01*
X862625Y292567D01*
X862292D01*
X861917Y292442D01*
X861625Y292234D01*
X861417Y291984D01*
X861250Y291567D01*
X861208Y291192D01*
X861292Y290817D01*
X861417Y290567D01*
X861667Y290317D01*
X861958Y290150D01*
X862250Y290067D01*
X862542D01*
X862833Y290150D01*
X863083Y290275D01*
X863292Y290442D01*
G01X864433Y290567D02*
X864683Y290275D01*
X865017Y290109D01*
X865392Y290067D01*
X865725Y290109D01*
X866058Y290317D01*
X866267Y290567D01*
X866308Y290817D01*
X866225Y291109D01*
X865933Y291317D01*
X865642Y291400D01*
X865267D01*
G01X865642D02*
X865892Y291525D01*
X866100Y291734D01*
X866183Y291984D01*
X866100Y292234D01*
X865892Y292442D01*
X865517Y292567D01*
X865142Y292525D01*
X864767Y292359D01*
G01X868450Y290067D02*
Y292567D01*
X867950Y292067D01*
G01Y290067D02*
X868950D01*
G01X871550Y292567D02*
X871217Y292484D01*
X870967Y292275D01*
X870800Y292025D01*
X870675Y291692D01*
X870633Y291317D01*
X870675Y290942D01*
X870800Y290609D01*
X870967Y290359D01*
X871217Y290150D01*
X871550Y290067D01*
X871883Y290150D01*
X872133Y290359D01*
X872300Y290609D01*
X872425Y290942D01*
X872467Y291317D01*
X872425Y291692D01*
X872300Y292025D01*
X872133Y292275D01*
X871883Y292484D01*
X871550Y292567D01*
G01X863167Y296359D02*
X862917Y296484D01*
X862625Y296567D01*
X862292D01*
X861917Y296442D01*
X861625Y296234D01*
X861417Y295984D01*
X861250Y295567D01*
X861208Y295192D01*
X861292Y294817D01*
X861417Y294567D01*
X861667Y294317D01*
X861958Y294150D01*
X862250Y294067D01*
X862542D01*
X862833Y294150D01*
X863083Y294275D01*
X863292Y294442D01*
G01X864433Y294567D02*
X864683Y294275D01*
X865017Y294109D01*
X865392Y294067D01*
X865725Y294109D01*
X866058Y294317D01*
X866267Y294567D01*
X866308Y294817D01*
X866225Y295109D01*
X865933Y295317D01*
X865642Y295400D01*
X865267D01*
G01X865642D02*
X865892Y295525D01*
X866100Y295734D01*
X866183Y295984D01*
X866100Y296234D01*
X865892Y296442D01*
X865517Y296567D01*
X865142Y296525D01*
X864767Y296359D01*
G01X868450Y296567D02*
X868117Y296484D01*
X867867Y296275D01*
X867700Y296025D01*
X867575Y295692D01*
X867533Y295317D01*
X867575Y294942D01*
X867700Y294609D01*
X867867Y294359D01*
X868117Y294150D01*
X868450Y294067D01*
X868783Y294150D01*
X869033Y294359D01*
X869200Y294609D01*
X869325Y294942D01*
X869367Y295317D01*
X869325Y295692D01*
X869200Y296025D01*
X869033Y296275D01*
X868783Y296484D01*
X868450Y296567D01*
G01X870842Y294359D02*
X871133Y294150D01*
X871467Y294067D01*
X871800Y294150D01*
X872092Y294400D01*
X872300Y294775D01*
X872383Y295150D01*
Y295609D01*
X872300Y295984D01*
X872092Y296317D01*
X871842Y296484D01*
X871550Y296567D01*
X871217Y296484D01*
X870967Y296317D01*
X870800Y296067D01*
X870717Y295734D01*
X870800Y295442D01*
X871008Y295150D01*
X871258Y294984D01*
X871550Y294942D01*
X871883Y295025D01*
X872133Y295234D01*
X872383Y295609D01*
G01X818267Y308459D02*
X818017Y308584D01*
X817725Y308667D01*
X817392D01*
X817017Y308542D01*
X816725Y308334D01*
X816517Y308084D01*
X816350Y307667D01*
X816308Y307292D01*
X816392Y306917D01*
X816517Y306667D01*
X816767Y306417D01*
X817058Y306250D01*
X817350Y306167D01*
X817642D01*
X817933Y306250D01*
X818183Y306375D01*
X818392Y306542D01*
G01X819533Y306667D02*
X819783Y306375D01*
X820117Y306209D01*
X820492Y306167D01*
X820825Y306209D01*
X821158Y306417D01*
X821367Y306667D01*
X821408Y306917D01*
X821325Y307209D01*
X821033Y307417D01*
X820742Y307500D01*
X820367D01*
G01X820742D02*
X820992Y307625D01*
X821200Y307834D01*
X821283Y308084D01*
X821200Y308334D01*
X820992Y308542D01*
X820617Y308667D01*
X820242Y308625D01*
X819867Y308459D01*
G01X823550Y308667D02*
X823217Y308584D01*
X822967Y308375D01*
X822800Y308125D01*
X822675Y307792D01*
X822633Y307417D01*
X822675Y307042D01*
X822800Y306709D01*
X822967Y306459D01*
X823217Y306250D01*
X823550Y306167D01*
X823883Y306250D01*
X824133Y306459D01*
X824300Y306709D01*
X824425Y307042D01*
X824467Y307417D01*
X824425Y307792D01*
X824300Y308125D01*
X824133Y308375D01*
X823883Y308584D01*
X823550Y308667D01*
G01X826650Y306167D02*
X826942Y306209D01*
X827275Y306334D01*
X827483Y306542D01*
X827567Y306834D01*
X827483Y307125D01*
X827233Y307375D01*
X826858Y307500D01*
X826442D01*
X826192Y307584D01*
X825983Y307792D01*
X825900Y308084D01*
X826025Y308375D01*
X826317Y308584D01*
X826650Y308667D01*
X826983Y308584D01*
X827275Y308375D01*
X827400Y308084D01*
X827317Y307792D01*
X827108Y307584D01*
X826858Y307500D01*
X826442D01*
X826067Y307375D01*
X825817Y307125D01*
X825733Y306834D01*
X825817Y306542D01*
X826025Y306334D01*
X826358Y306209D01*
X826650Y306167D01*
G01X818267Y312459D02*
X818017Y312584D01*
X817725Y312667D01*
X817392D01*
X817017Y312542D01*
X816725Y312334D01*
X816517Y312084D01*
X816350Y311667D01*
X816308Y311292D01*
X816392Y310917D01*
X816517Y310667D01*
X816767Y310417D01*
X817058Y310250D01*
X817350Y310167D01*
X817642D01*
X817933Y310250D01*
X818183Y310375D01*
X818392Y310542D01*
G01X819533Y310667D02*
X819783Y310375D01*
X820117Y310209D01*
X820492Y310167D01*
X820825Y310209D01*
X821158Y310417D01*
X821367Y310667D01*
X821408Y310917D01*
X821325Y311209D01*
X821033Y311417D01*
X820742Y311500D01*
X820367D01*
G01X820742D02*
X820992Y311625D01*
X821200Y311834D01*
X821283Y312084D01*
X821200Y312334D01*
X820992Y312542D01*
X820617Y312667D01*
X820242Y312625D01*
X819867Y312459D01*
G01X823550Y312667D02*
X823217Y312584D01*
X822967Y312375D01*
X822800Y312125D01*
X822675Y311792D01*
X822633Y311417D01*
X822675Y311042D01*
X822800Y310709D01*
X822967Y310459D01*
X823217Y310250D01*
X823550Y310167D01*
X823883Y310250D01*
X824133Y310459D01*
X824300Y310709D01*
X824425Y311042D01*
X824467Y311417D01*
X824425Y311792D01*
X824300Y312125D01*
X824133Y312375D01*
X823883Y312584D01*
X823550Y312667D01*
G01X826567Y310167D02*
X826650Y310709D01*
X826775Y311167D01*
X826942Y311584D01*
X827150Y312042D01*
X827483Y312667D01*
X825817D01*
G01X819972Y391639D02*
Y395639D01*
X812572D01*
G01X858734Y369167D02*
X856234D01*
Y370208D01*
X856359Y370542D01*
X856526Y370750D01*
X856859Y370833D01*
X857192Y370750D01*
X857401Y370500D01*
X857526Y370208D01*
Y369167D01*
G01Y370208D02*
X858734Y370833D01*
G01X857692Y372308D02*
X857401Y372600D01*
X857234Y372850D01*
X857151Y373183D01*
X857234Y373475D01*
X857401Y373683D01*
X857651Y373850D01*
X857942Y373892D01*
X858192Y373850D01*
X858442Y373683D01*
X858651Y373433D01*
X858734Y373142D01*
X858651Y372808D01*
X858401Y372517D01*
X858026Y372350D01*
X857609Y372308D01*
X857067Y372392D01*
X856776Y372517D01*
X856484Y372725D01*
X856276Y373017D01*
X856234Y373308D01*
X856317Y373600D01*
X856526Y373808D01*
G01X856234Y376200D02*
X856317Y375867D01*
X856526Y375617D01*
X856776Y375450D01*
X857109Y375325D01*
X857484Y375283D01*
X857859Y375325D01*
X858192Y375450D01*
X858442Y375617D01*
X858651Y375867D01*
X858734Y376200D01*
X858651Y376533D01*
X858442Y376783D01*
X858192Y376950D01*
X857859Y377075D01*
X857484Y377117D01*
X857109Y377075D01*
X856776Y376950D01*
X856526Y376783D01*
X856317Y376533D01*
X856234Y376200D01*
G01X858234Y378383D02*
X858526Y378633D01*
X858692Y378967D01*
X858734Y379342D01*
X858692Y379675D01*
X858484Y380008D01*
X858234Y380217D01*
X857984Y380258D01*
X857692Y380175D01*
X857484Y379883D01*
X857401Y379592D01*
Y379217D01*
G01Y379592D02*
X857276Y379842D01*
X857067Y380050D01*
X856817Y380133D01*
X856567Y380050D01*
X856359Y379842D01*
X856234Y379467D01*
X856276Y379092D01*
X856442Y378717D01*
G01X855569Y382933D02*
X859569D01*
Y390333D01*
G01X836483Y383667D02*
Y381875D01*
X836650Y381500D01*
X836983Y381250D01*
X837400Y381167D01*
X837817Y381250D01*
X838150Y381500D01*
X838317Y381875D01*
Y383667D01*
G01X839583Y381667D02*
X839833Y381375D01*
X840167Y381209D01*
X840542Y381167D01*
X840875Y381209D01*
X841208Y381417D01*
X841417Y381667D01*
X841458Y381917D01*
X841375Y382209D01*
X841083Y382417D01*
X840792Y382500D01*
X840417D01*
G01X840792D02*
X841042Y382625D01*
X841250Y382834D01*
X841333Y383084D01*
X841250Y383334D01*
X841042Y383542D01*
X840667Y383667D01*
X840292Y383625D01*
X839917Y383459D01*
G01X843600Y381167D02*
X843892Y381209D01*
X844225Y381334D01*
X844433Y381542D01*
X844517Y381834D01*
X844433Y382125D01*
X844183Y382375D01*
X843808Y382500D01*
X843392D01*
X843142Y382584D01*
X842933Y382792D01*
X842850Y383084D01*
X842975Y383375D01*
X843267Y383584D01*
X843600Y383667D01*
X843933Y383584D01*
X844225Y383375D01*
X844350Y383084D01*
X844267Y382792D01*
X844058Y382584D01*
X843808Y382500D01*
X843392D01*
X843017Y382375D01*
X842767Y382125D01*
X842683Y381834D01*
X842767Y381542D01*
X842975Y381334D01*
X843308Y381209D01*
X843600Y381167D01*
G01X838300Y385600D02*
X840100Y387700D01*
X842300Y385600D01*
G01X845900Y385500D02*
Y404700D01*
X834700D01*
Y385500D01*
X845900D01*
Y385900D01*
G01X861892Y367317D02*
X861767Y367067D01*
X861684Y366775D01*
Y366442D01*
X861809Y366067D01*
X862017Y365775D01*
X862267Y365567D01*
X862684Y365400D01*
X863059Y365358D01*
X863434Y365442D01*
X863684Y365567D01*
X863934Y365817D01*
X864101Y366108D01*
X864184Y366400D01*
Y366692D01*
X864101Y366983D01*
X863976Y367233D01*
X863809Y367442D01*
G01X863684Y368583D02*
X863976Y368833D01*
X864142Y369167D01*
X864184Y369542D01*
X864142Y369875D01*
X863934Y370208D01*
X863684Y370417D01*
X863434Y370458D01*
X863142Y370375D01*
X862934Y370083D01*
X862851Y369792D01*
Y369417D01*
G01Y369792D02*
X862726Y370042D01*
X862517Y370250D01*
X862267Y370333D01*
X862017Y370250D01*
X861809Y370042D01*
X861684Y369667D01*
X861726Y369292D01*
X861892Y368917D01*
G01X864184Y372517D02*
X863642Y372600D01*
X863184Y372725D01*
X862767Y372892D01*
X862309Y373100D01*
X861684Y373433D01*
Y371767D01*
G01X863684Y374783D02*
X863976Y375033D01*
X864142Y375367D01*
X864184Y375742D01*
X864142Y376075D01*
X863934Y376408D01*
X863684Y376617D01*
X863434Y376658D01*
X863142Y376575D01*
X862934Y376283D01*
X862851Y375992D01*
Y375617D01*
G01Y375992D02*
X862726Y376242D01*
X862517Y376450D01*
X862267Y376533D01*
X862017Y376450D01*
X861809Y376242D01*
X861684Y375867D01*
X861726Y375492D01*
X861892Y375117D01*
G01X860928Y390892D02*
Y396392D01*
G01Y378792D02*
Y384292D01*
G01X868928Y378792D02*
X860928D01*
G01X820267Y396968D02*
Y400968D01*
X812867D01*
G01X811017Y411267D02*
Y413767D01*
X812058D01*
X812392Y413642D01*
X812600Y413475D01*
X812683Y413142D01*
X812600Y412809D01*
X812350Y412600D01*
X812058Y412475D01*
X811017D01*
G01X812058D02*
X812683Y411267D01*
G01X814158Y412309D02*
X814450Y412600D01*
X814700Y412767D01*
X815033Y412850D01*
X815325Y412767D01*
X815533Y412600D01*
X815700Y412350D01*
X815742Y412059D01*
X815700Y411809D01*
X815533Y411559D01*
X815283Y411350D01*
X814992Y411267D01*
X814658Y411350D01*
X814367Y411600D01*
X814200Y411975D01*
X814158Y412392D01*
X814242Y412934D01*
X814367Y413225D01*
X814575Y413517D01*
X814867Y413725D01*
X815158Y413767D01*
X815450Y413684D01*
X815658Y413475D01*
G01X818050Y413767D02*
X817717Y413684D01*
X817467Y413475D01*
X817300Y413225D01*
X817175Y412892D01*
X817133Y412517D01*
X817175Y412142D01*
X817300Y411809D01*
X817467Y411559D01*
X817717Y411350D01*
X818050Y411267D01*
X818383Y411350D01*
X818633Y411559D01*
X818800Y411809D01*
X818925Y412142D01*
X818967Y412517D01*
X818925Y412892D01*
X818800Y413225D01*
X818633Y413475D01*
X818383Y413684D01*
X818050Y413767D01*
G01X821150Y411267D02*
X821442Y411309D01*
X821775Y411434D01*
X821983Y411642D01*
X822067Y411934D01*
X821983Y412225D01*
X821733Y412475D01*
X821358Y412600D01*
X820942D01*
X820692Y412684D01*
X820483Y412892D01*
X820400Y413184D01*
X820525Y413475D01*
X820817Y413684D01*
X821150Y413767D01*
X821483Y413684D01*
X821775Y413475D01*
X821900Y413184D01*
X821817Y412892D01*
X821608Y412684D01*
X821358Y412600D01*
X820942D01*
X820567Y412475D01*
X820317Y412225D01*
X820233Y411934D01*
X820317Y411642D01*
X820525Y411434D01*
X820858Y411309D01*
X821150Y411267D01*
G01X820688Y408655D02*
X816688D01*
Y401255D01*
G01X849334Y410817D02*
X846834D01*
Y411858D01*
X846959Y412192D01*
X847126Y412400D01*
X847459Y412483D01*
X847792Y412400D01*
X848001Y412150D01*
X848126Y411858D01*
Y410817D01*
G01Y411858D02*
X849334Y412483D01*
G01X848292Y413958D02*
X848001Y414250D01*
X847834Y414500D01*
X847751Y414833D01*
X847834Y415125D01*
X848001Y415333D01*
X848251Y415500D01*
X848542Y415542D01*
X848792Y415500D01*
X849042Y415333D01*
X849251Y415083D01*
X849334Y414792D01*
X849251Y414458D01*
X849001Y414167D01*
X848626Y414000D01*
X848209Y413958D01*
X847667Y414042D01*
X847376Y414167D01*
X847084Y414375D01*
X846876Y414667D01*
X846834Y414958D01*
X846917Y415250D01*
X847126Y415458D01*
G01X846834Y417850D02*
X846917Y417517D01*
X847126Y417267D01*
X847376Y417100D01*
X847709Y416975D01*
X848084Y416933D01*
X848459Y416975D01*
X848792Y417100D01*
X849042Y417267D01*
X849251Y417517D01*
X849334Y417850D01*
X849251Y418183D01*
X849042Y418433D01*
X848792Y418600D01*
X848459Y418725D01*
X848084Y418767D01*
X847709Y418725D01*
X847376Y418600D01*
X847126Y418433D01*
X846917Y418183D01*
X846834Y417850D01*
G01Y420950D02*
X846917Y420617D01*
X847126Y420367D01*
X847376Y420200D01*
X847709Y420075D01*
X848084Y420033D01*
X848459Y420075D01*
X848792Y420200D01*
X849042Y420367D01*
X849251Y420617D01*
X849334Y420950D01*
X849251Y421283D01*
X849042Y421533D01*
X848792Y421700D01*
X848459Y421825D01*
X848084Y421867D01*
X847709Y421825D01*
X847376Y421700D01*
X847126Y421533D01*
X846917Y421283D01*
X846834Y420950D01*
G01X859000Y408800D02*
X855000D01*
Y401400D01*
G01X863550Y405400D02*
Y401400D01*
X870950D01*
G01X853834Y410817D02*
X851334D01*
Y411858D01*
X851459Y412192D01*
X851626Y412400D01*
X851959Y412483D01*
X852292Y412400D01*
X852501Y412150D01*
X852626Y411858D01*
Y410817D01*
G01Y411858D02*
X853834Y412483D01*
G01X852792Y413958D02*
X852501Y414250D01*
X852334Y414500D01*
X852251Y414833D01*
X852334Y415125D01*
X852501Y415333D01*
X852751Y415500D01*
X853042Y415542D01*
X853292Y415500D01*
X853542Y415333D01*
X853751Y415083D01*
X853834Y414792D01*
X853751Y414458D01*
X853501Y414167D01*
X853126Y414000D01*
X852709Y413958D01*
X852167Y414042D01*
X851876Y414167D01*
X851584Y414375D01*
X851376Y414667D01*
X851334Y414958D01*
X851417Y415250D01*
X851626Y415458D01*
G01X851334Y417850D02*
X851417Y417517D01*
X851626Y417267D01*
X851876Y417100D01*
X852209Y416975D01*
X852584Y416933D01*
X852959Y416975D01*
X853292Y417100D01*
X853542Y417267D01*
X853751Y417517D01*
X853834Y417850D01*
X853751Y418183D01*
X853542Y418433D01*
X853292Y418600D01*
X852959Y418725D01*
X852584Y418767D01*
X852209Y418725D01*
X851876Y418600D01*
X851626Y418433D01*
X851417Y418183D01*
X851334Y417850D01*
G01X853459Y420033D02*
X853667Y420283D01*
X853792Y420575D01*
X853834Y420950D01*
X853751Y421325D01*
X853584Y421617D01*
X853292Y421825D01*
X852959Y421867D01*
X852626Y421783D01*
X852417Y421575D01*
X852251Y421283D01*
X852209Y420992D01*
X852251Y420700D01*
X852417Y420325D01*
X851334Y420450D01*
Y421575D01*
G01X859000Y401400D02*
X863000D01*
Y408800D01*
G01X860928Y396392D02*
X868928D01*
G01X827267Y417392D02*
X827017Y417517D01*
X826725Y417600D01*
X826392D01*
X826017Y417475D01*
X825725Y417267D01*
X825517Y417017D01*
X825350Y416600D01*
X825308Y416225D01*
X825392Y415850D01*
X825517Y415600D01*
X825767Y415350D01*
X826058Y415183D01*
X826350Y415100D01*
X826642D01*
X826933Y415183D01*
X827183Y415308D01*
X827392Y415475D01*
G01X828533Y415600D02*
X828783Y415308D01*
X829117Y415142D01*
X829492Y415100D01*
X829825Y415142D01*
X830158Y415350D01*
X830367Y415600D01*
X830408Y415850D01*
X830325Y416142D01*
X830033Y416350D01*
X829742Y416433D01*
X829367D01*
G01X829742D02*
X829992Y416558D01*
X830200Y416767D01*
X830283Y417017D01*
X830200Y417267D01*
X829992Y417475D01*
X829617Y417600D01*
X829242Y417558D01*
X828867Y417392D01*
G01X831758Y417183D02*
X832008Y417433D01*
X832300Y417558D01*
X832633Y417600D01*
X833050Y417517D01*
X833342Y417308D01*
X833425Y417058D01*
X833383Y416808D01*
X833217Y416600D01*
X832383Y416183D01*
X832008Y415892D01*
X831758Y415475D01*
X831675Y415100D01*
X833425D01*
G01X836150D02*
Y417600D01*
X834608Y415808D01*
X836692D01*
G01X842400Y420000D02*
Y431200D01*
G01X824400Y420000D02*
X842400D01*
G01X824400Y431200D02*
Y420000D01*
G01X842400Y458400D02*
Y447200D01*
G01X824400Y458400D02*
X842400D01*
G01X824400Y447200D02*
Y458400D01*
G01X817200Y420000D02*
Y431200D01*
G01X799200Y420000D02*
X817200D01*
G01X799200Y431200D02*
Y420000D01*
G01X817200Y458400D02*
Y447200D01*
G01X799200Y458400D02*
X817200D01*
G01X799200Y447200D02*
Y458400D01*
G01X815567Y473359D02*
X815317Y473484D01*
X815025Y473567D01*
X814692D01*
X814317Y473442D01*
X814025Y473234D01*
X813817Y472984D01*
X813650Y472567D01*
X813608Y472192D01*
X813692Y471817D01*
X813817Y471567D01*
X814067Y471317D01*
X814358Y471150D01*
X814650Y471067D01*
X814942D01*
X815233Y471150D01*
X815483Y471275D01*
X815692Y471442D01*
G01X816958Y473150D02*
X817208Y473400D01*
X817500Y473525D01*
X817833Y473567D01*
X818250Y473484D01*
X818542Y473275D01*
X818625Y473025D01*
X818583Y472775D01*
X818417Y472567D01*
X817583Y472150D01*
X817208Y471859D01*
X816958Y471442D01*
X816875Y471067D01*
X818625D01*
G01X821350D02*
Y473567D01*
X819808Y471775D01*
X821892D01*
G01X823158Y472109D02*
X823450Y472400D01*
X823700Y472567D01*
X824033Y472650D01*
X824325Y472567D01*
X824533Y472400D01*
X824700Y472150D01*
X824742Y471859D01*
X824700Y471609D01*
X824533Y471359D01*
X824283Y471150D01*
X823992Y471067D01*
X823658Y471150D01*
X823367Y471400D01*
X823200Y471775D01*
X823158Y472192D01*
X823242Y472734D01*
X823367Y473025D01*
X823575Y473317D01*
X823867Y473525D01*
X824158Y473567D01*
X824450Y473484D01*
X824658Y473275D01*
G01X835042Y505767D02*
X834917Y505517D01*
X834834Y505225D01*
Y504892D01*
X834959Y504517D01*
X835167Y504225D01*
X835417Y504017D01*
X835834Y503850D01*
X836209Y503808D01*
X836584Y503892D01*
X836834Y504017D01*
X837084Y504267D01*
X837251Y504558D01*
X837334Y504850D01*
Y505142D01*
X837251Y505433D01*
X837126Y505683D01*
X836959Y505892D01*
G01X835251Y507158D02*
X835001Y507408D01*
X834876Y507700D01*
X834834Y508033D01*
X834917Y508450D01*
X835126Y508742D01*
X835376Y508825D01*
X835626Y508783D01*
X835834Y508617D01*
X836251Y507783D01*
X836542Y507408D01*
X836959Y507158D01*
X837334Y507075D01*
Y508825D01*
G01X836959Y510133D02*
X837167Y510383D01*
X837292Y510675D01*
X837334Y511050D01*
X837251Y511425D01*
X837084Y511717D01*
X836792Y511925D01*
X836459Y511967D01*
X836126Y511883D01*
X835917Y511675D01*
X835751Y511383D01*
X835709Y511092D01*
X835751Y510800D01*
X835917Y510425D01*
X834834Y510550D01*
Y511675D01*
G01X837334Y514650D02*
X834834D01*
X836626Y513108D01*
Y515192D01*
G01X853167Y477292D02*
X852917Y477417D01*
X852625Y477500D01*
X852292D01*
X851917Y477375D01*
X851625Y477167D01*
X851417Y476917D01*
X851250Y476500D01*
X851208Y476125D01*
X851292Y475750D01*
X851417Y475500D01*
X851667Y475250D01*
X851958Y475083D01*
X852250Y475000D01*
X852542D01*
X852833Y475083D01*
X853083Y475208D01*
X853292Y475375D01*
G01X854558Y477083D02*
X854808Y477333D01*
X855100Y477458D01*
X855433Y477500D01*
X855850Y477417D01*
X856142Y477208D01*
X856225Y476958D01*
X856183Y476708D01*
X856017Y476500D01*
X855183Y476083D01*
X854808Y475792D01*
X854558Y475375D01*
X854475Y475000D01*
X856225D01*
G01X857533Y475375D02*
X857783Y475167D01*
X858075Y475042D01*
X858450Y475000D01*
X858825Y475083D01*
X859117Y475250D01*
X859325Y475542D01*
X859367Y475875D01*
X859283Y476208D01*
X859075Y476417D01*
X858783Y476583D01*
X858492Y476625D01*
X858200Y476583D01*
X857825Y476417D01*
X857950Y477500D01*
X859075D01*
G01X861550Y475000D02*
Y477500D01*
X861050Y477000D01*
G01Y475000D02*
X862050D01*
G01X840458Y489021D02*
X840333Y488771D01*
X840250Y488479D01*
Y488146D01*
X840375Y487771D01*
X840583Y487479D01*
X840833Y487271D01*
X841250Y487104D01*
X841625Y487062D01*
X842000Y487146D01*
X842250Y487271D01*
X842500Y487521D01*
X842667Y487812D01*
X842750Y488104D01*
Y488396D01*
X842667Y488687D01*
X842542Y488937D01*
X842375Y489146D01*
G01X840667Y490412D02*
X840417Y490662D01*
X840292Y490954D01*
X840250Y491287D01*
X840333Y491704D01*
X840542Y491996D01*
X840792Y492079D01*
X841042Y492037D01*
X841250Y491871D01*
X841667Y491037D01*
X841958Y490662D01*
X842375Y490412D01*
X842750Y490329D01*
Y492079D01*
G01Y494804D02*
X840250D01*
X842042Y493262D01*
Y495346D01*
G01X842750Y497404D02*
X842708Y497696D01*
X842583Y498029D01*
X842375Y498237D01*
X842083Y498321D01*
X841792Y498237D01*
X841542Y497987D01*
X841417Y497612D01*
Y497196D01*
X841333Y496946D01*
X841125Y496737D01*
X840833Y496654D01*
X840542Y496779D01*
X840333Y497071D01*
X840250Y497404D01*
X840333Y497737D01*
X840542Y498029D01*
X840833Y498154D01*
X841125Y498071D01*
X841333Y497862D01*
X841417Y497612D01*
Y497196D01*
X841542Y496821D01*
X841792Y496571D01*
X842083Y496487D01*
X842375Y496571D01*
X842583Y496779D01*
X842708Y497112D01*
X842750Y497404D01*
G01X845042Y488767D02*
X844917Y488517D01*
X844834Y488225D01*
Y487892D01*
X844959Y487517D01*
X845167Y487225D01*
X845417Y487017D01*
X845834Y486850D01*
X846209Y486808D01*
X846584Y486892D01*
X846834Y487017D01*
X847084Y487267D01*
X847251Y487558D01*
X847334Y487850D01*
Y488142D01*
X847251Y488433D01*
X847126Y488683D01*
X846959Y488892D01*
G01X845251Y490158D02*
X845001Y490408D01*
X844876Y490700D01*
X844834Y491033D01*
X844917Y491450D01*
X845126Y491742D01*
X845376Y491825D01*
X845626Y491783D01*
X845834Y491617D01*
X846251Y490783D01*
X846542Y490408D01*
X846959Y490158D01*
X847334Y490075D01*
Y491825D01*
G01Y494550D02*
X844834D01*
X846626Y493008D01*
Y495092D01*
G01X847042Y496442D02*
X847251Y496733D01*
X847334Y497067D01*
X847251Y497400D01*
X847001Y497692D01*
X846626Y497900D01*
X846251Y497983D01*
X845792D01*
X845417Y497900D01*
X845084Y497692D01*
X844917Y497442D01*
X844834Y497150D01*
X844917Y496817D01*
X845084Y496567D01*
X845334Y496400D01*
X845667Y496317D01*
X845959Y496400D01*
X846251Y496608D01*
X846417Y496858D01*
X846459Y497150D01*
X846376Y497483D01*
X846167Y497733D01*
X845792Y497983D01*
G01X853221Y483442D02*
X852971Y483567D01*
X852679Y483650D01*
X852346D01*
X851971Y483525D01*
X851679Y483317D01*
X851471Y483067D01*
X851304Y482650D01*
X851262Y482275D01*
X851346Y481900D01*
X851471Y481650D01*
X851721Y481400D01*
X852012Y481233D01*
X852304Y481150D01*
X852596D01*
X852887Y481233D01*
X853137Y481358D01*
X853346Y481525D01*
G01X854612Y483233D02*
X854862Y483483D01*
X855154Y483608D01*
X855487Y483650D01*
X855904Y483567D01*
X856196Y483358D01*
X856279Y483108D01*
X856237Y482858D01*
X856071Y482650D01*
X855237Y482233D01*
X854862Y481942D01*
X854612Y481525D01*
X854529Y481150D01*
X856279D01*
G01X857587Y481525D02*
X857837Y481317D01*
X858129Y481192D01*
X858504Y481150D01*
X858879Y481233D01*
X859171Y481400D01*
X859379Y481692D01*
X859421Y482025D01*
X859337Y482358D01*
X859129Y482567D01*
X858837Y482733D01*
X858546Y482775D01*
X858254Y482733D01*
X857879Y482567D01*
X858004Y483650D01*
X859129D01*
G01X861604D02*
X861271Y483567D01*
X861021Y483358D01*
X860854Y483108D01*
X860729Y482775D01*
X860687Y482400D01*
X860729Y482025D01*
X860854Y481692D01*
X861021Y481442D01*
X861271Y481233D01*
X861604Y481150D01*
X861937Y481233D01*
X862187Y481442D01*
X862354Y481692D01*
X862479Y482025D01*
X862521Y482400D01*
X862479Y482775D01*
X862354Y483108D01*
X862187Y483358D01*
X861937Y483567D01*
X861604Y483650D01*
G01X807249Y525277D02*
X803249D01*
Y517877D01*
G01X814317Y466467D02*
Y468967D01*
X815358D01*
X815692Y468842D01*
X815900Y468675D01*
X815983Y468342D01*
X815900Y468009D01*
X815650Y467800D01*
X815358Y467675D01*
X814317D01*
G01X815358D02*
X815983Y466467D01*
G01X817333Y466842D02*
X817583Y466634D01*
X817875Y466509D01*
X818250Y466467D01*
X818625Y466550D01*
X818917Y466717D01*
X819125Y467009D01*
X819167Y467342D01*
X819083Y467675D01*
X818875Y467884D01*
X818583Y468050D01*
X818292Y468092D01*
X818000Y468050D01*
X817625Y467884D01*
X817750Y468967D01*
X818875D01*
G01X821850Y466467D02*
Y468967D01*
X820308Y467175D01*
X822392D01*
G01X824950Y466467D02*
Y468967D01*
X823408Y467175D01*
X825492D01*
G01X811300Y471500D02*
Y475500D01*
X803900D01*
G01X814017Y475367D02*
Y477867D01*
X815058D01*
X815392Y477742D01*
X815600Y477575D01*
X815683Y477242D01*
X815600Y476909D01*
X815350Y476700D01*
X815058Y476575D01*
X814017D01*
G01X815058D02*
X815683Y475367D01*
G01X817033Y475742D02*
X817283Y475534D01*
X817575Y475409D01*
X817950Y475367D01*
X818325Y475450D01*
X818617Y475617D01*
X818825Y475909D01*
X818867Y476242D01*
X818783Y476575D01*
X818575Y476784D01*
X818283Y476950D01*
X817992Y476992D01*
X817700Y476950D01*
X817325Y476784D01*
X817450Y477867D01*
X818575D01*
G01X821550Y475367D02*
Y477867D01*
X820008Y476075D01*
X822092D01*
G01X823233Y475742D02*
X823483Y475534D01*
X823775Y475409D01*
X824150Y475367D01*
X824525Y475450D01*
X824817Y475617D01*
X825025Y475909D01*
X825067Y476242D01*
X824983Y476575D01*
X824775Y476784D01*
X824483Y476950D01*
X824192Y476992D01*
X823900Y476950D01*
X823525Y476784D01*
X823650Y477867D01*
X824775D01*
G01X803934Y482900D02*
Y478900D01*
X811334D01*
G01X851717Y469000D02*
Y471500D01*
X852758D01*
X853092Y471375D01*
X853300Y471208D01*
X853383Y470875D01*
X853300Y470542D01*
X853050Y470333D01*
X852758Y470208D01*
X851717D01*
G01X852758D02*
X853383Y469000D01*
G01X854733Y469375D02*
X854983Y469167D01*
X855275Y469042D01*
X855650Y469000D01*
X856025Y469083D01*
X856317Y469250D01*
X856525Y469542D01*
X856567Y469875D01*
X856483Y470208D01*
X856275Y470417D01*
X855983Y470583D01*
X855692Y470625D01*
X855400Y470583D01*
X855025Y470417D01*
X855150Y471500D01*
X856275D01*
G01X859250Y469000D02*
Y471500D01*
X857708Y469708D01*
X859792D01*
G01X860933Y469500D02*
X861183Y469208D01*
X861517Y469042D01*
X861892Y469000D01*
X862225Y469042D01*
X862558Y469250D01*
X862767Y469500D01*
X862808Y469750D01*
X862725Y470042D01*
X862433Y470250D01*
X862142Y470333D01*
X861767D01*
G01X862142D02*
X862392Y470458D01*
X862600Y470667D01*
X862683Y470917D01*
X862600Y471167D01*
X862392Y471375D01*
X862017Y471500D01*
X861642Y471458D01*
X861267Y471292D01*
G01X846400Y466000D02*
X841200D01*
G01X846400Y473000D02*
X838600D01*
G01X846400Y466000D02*
Y473000D01*
G01X833000Y466000D02*
X841700D01*
G01X833000Y473000D02*
Y466000D01*
G01X839400Y473000D02*
X833000D01*
G01X822367Y480567D02*
Y483067D01*
X823367D01*
X823700Y482942D01*
X823950Y482650D01*
X824033Y482317D01*
X823950Y481984D01*
X823742Y481734D01*
X823367Y481609D01*
X822367D01*
G01X825383Y483067D02*
Y481275D01*
X825550Y480900D01*
X825883Y480650D01*
X826300Y480567D01*
X826717Y480650D01*
X827050Y480900D01*
X827217Y481275D01*
Y483067D01*
G01X829317Y480567D02*
X829400Y481109D01*
X829525Y481567D01*
X829692Y481984D01*
X829900Y482442D01*
X830233Y483067D01*
X828567D01*
G01X824064Y508700D02*
Y513700D01*
X819064D01*
G01X815332Y487407D02*
Y484407D01*
G01X805096Y512293D02*
Y515293D01*
G01X822657Y504968D02*
X824657D01*
G01X820458Y537021D02*
X820333Y536771D01*
X820250Y536479D01*
Y536146D01*
X820375Y535771D01*
X820583Y535479D01*
X820833Y535271D01*
X821250Y535104D01*
X821625Y535062D01*
X822000Y535146D01*
X822250Y535271D01*
X822500Y535521D01*
X822667Y535812D01*
X822750Y536104D01*
Y536396D01*
X822667Y536687D01*
X822542Y536937D01*
X822375Y537146D01*
G01X820667Y538412D02*
X820417Y538662D01*
X820292Y538954D01*
X820250Y539287D01*
X820333Y539704D01*
X820542Y539996D01*
X820792Y540079D01*
X821042Y540037D01*
X821250Y539871D01*
X821667Y539037D01*
X821958Y538662D01*
X822375Y538412D01*
X822750Y538329D01*
Y540079D01*
G01X822375Y541387D02*
X822583Y541637D01*
X822708Y541929D01*
X822750Y542304D01*
X822667Y542679D01*
X822500Y542971D01*
X822208Y543179D01*
X821875Y543221D01*
X821542Y543137D01*
X821333Y542929D01*
X821167Y542637D01*
X821125Y542346D01*
X821167Y542054D01*
X821333Y541679D01*
X820250Y541804D01*
Y542929D01*
G01X822375Y544487D02*
X822583Y544737D01*
X822708Y545029D01*
X822750Y545404D01*
X822667Y545779D01*
X822500Y546071D01*
X822208Y546279D01*
X821875Y546321D01*
X821542Y546237D01*
X821333Y546029D01*
X821167Y545737D01*
X821125Y545446D01*
X821167Y545154D01*
X821333Y544779D01*
X820250Y544904D01*
Y546029D01*
G01X812558Y537021D02*
X812433Y536771D01*
X812350Y536479D01*
Y536146D01*
X812475Y535771D01*
X812683Y535479D01*
X812933Y535271D01*
X813350Y535104D01*
X813725Y535062D01*
X814100Y535146D01*
X814350Y535271D01*
X814600Y535521D01*
X814767Y535812D01*
X814850Y536104D01*
Y536396D01*
X814767Y536687D01*
X814642Y536937D01*
X814475Y537146D01*
G01X812767Y538412D02*
X812517Y538662D01*
X812392Y538954D01*
X812350Y539287D01*
X812433Y539704D01*
X812642Y539996D01*
X812892Y540079D01*
X813142Y540037D01*
X813350Y539871D01*
X813767Y539037D01*
X814058Y538662D01*
X814475Y538412D01*
X814850Y538329D01*
Y540079D01*
G01X814475Y541387D02*
X814683Y541637D01*
X814808Y541929D01*
X814850Y542304D01*
X814767Y542679D01*
X814600Y542971D01*
X814308Y543179D01*
X813975Y543221D01*
X813642Y543137D01*
X813433Y542929D01*
X813267Y542637D01*
X813225Y542346D01*
X813267Y542054D01*
X813433Y541679D01*
X812350Y541804D01*
Y542929D01*
G01X813808Y544612D02*
X813517Y544904D01*
X813350Y545154D01*
X813267Y545487D01*
X813350Y545779D01*
X813517Y545987D01*
X813767Y546154D01*
X814058Y546196D01*
X814308Y546154D01*
X814558Y545987D01*
X814767Y545737D01*
X814850Y545446D01*
X814767Y545112D01*
X814517Y544821D01*
X814142Y544654D01*
X813725Y544612D01*
X813183Y544696D01*
X812892Y544821D01*
X812600Y545029D01*
X812392Y545321D01*
X812350Y545612D01*
X812433Y545904D01*
X812642Y546112D01*
G01X805949Y530694D02*
X803449D01*
Y531735D01*
X803574Y532069D01*
X803741Y532277D01*
X804074Y532360D01*
X804407Y532277D01*
X804616Y532027D01*
X804741Y531735D01*
Y530694D01*
G01Y531735D02*
X805949Y532360D01*
G01X805574Y533710D02*
X805782Y533960D01*
X805907Y534252D01*
X805949Y534627D01*
X805866Y535002D01*
X805699Y535294D01*
X805407Y535502D01*
X805074Y535544D01*
X804741Y535460D01*
X804532Y535252D01*
X804366Y534960D01*
X804324Y534669D01*
X804366Y534377D01*
X804532Y534002D01*
X803449Y534127D01*
Y535252D01*
G01X805949Y538227D02*
X803449D01*
X805241Y536685D01*
Y538769D01*
G01X804907Y540035D02*
X804616Y540327D01*
X804449Y540577D01*
X804366Y540910D01*
X804449Y541202D01*
X804616Y541410D01*
X804866Y541577D01*
X805157Y541619D01*
X805407Y541577D01*
X805657Y541410D01*
X805866Y541160D01*
X805949Y540869D01*
X805866Y540535D01*
X805616Y540244D01*
X805241Y540077D01*
X804824Y540035D01*
X804282Y540119D01*
X803991Y540244D01*
X803699Y540452D01*
X803491Y540744D01*
X803449Y541035D01*
X803532Y541327D01*
X803741Y541535D01*
G01X799742Y530367D02*
X799617Y530117D01*
X799534Y529825D01*
Y529492D01*
X799659Y529117D01*
X799867Y528825D01*
X800117Y528617D01*
X800534Y528450D01*
X800909Y528408D01*
X801284Y528492D01*
X801534Y528617D01*
X801784Y528867D01*
X801951Y529158D01*
X802034Y529450D01*
Y529742D01*
X801951Y530033D01*
X801826Y530283D01*
X801659Y530492D01*
G01X799951Y531758D02*
X799701Y532008D01*
X799576Y532300D01*
X799534Y532633D01*
X799617Y533050D01*
X799826Y533342D01*
X800076Y533425D01*
X800326Y533383D01*
X800534Y533217D01*
X800951Y532383D01*
X801242Y532008D01*
X801659Y531758D01*
X802034Y531675D01*
Y533425D01*
G01X801659Y534733D02*
X801867Y534983D01*
X801992Y535275D01*
X802034Y535650D01*
X801951Y536025D01*
X801784Y536317D01*
X801492Y536525D01*
X801159Y536567D01*
X800826Y536483D01*
X800617Y536275D01*
X800451Y535983D01*
X800409Y535692D01*
X800451Y535400D01*
X800617Y535025D01*
X799534Y535150D01*
Y536275D01*
G01X801534Y537833D02*
X801826Y538083D01*
X801992Y538417D01*
X802034Y538792D01*
X801992Y539125D01*
X801784Y539458D01*
X801534Y539667D01*
X801284Y539708D01*
X800992Y539625D01*
X800784Y539333D01*
X800701Y539042D01*
Y538667D01*
G01Y539042D02*
X800576Y539292D01*
X800367Y539500D01*
X800117Y539583D01*
X799867Y539500D01*
X799659Y539292D01*
X799534Y538917D01*
X799576Y538542D01*
X799742Y538167D01*
G01X878778Y226758D02*
X876278D01*
Y227799D01*
X876403Y228133D01*
X876570Y228341D01*
X876903Y228424D01*
X877236Y228341D01*
X877445Y228091D01*
X877570Y227799D01*
Y226758D01*
G01Y227799D02*
X878778Y228424D01*
G01X878403Y229774D02*
X878611Y230024D01*
X878736Y230316D01*
X878778Y230691D01*
X878695Y231066D01*
X878528Y231358D01*
X878236Y231566D01*
X877903Y231608D01*
X877570Y231524D01*
X877361Y231316D01*
X877195Y231024D01*
X877153Y230733D01*
X877195Y230441D01*
X877361Y230066D01*
X876278Y230191D01*
Y231316D01*
G01X878778Y233708D02*
X878236Y233791D01*
X877778Y233916D01*
X877361Y234083D01*
X876903Y234291D01*
X876278Y234624D01*
Y232958D01*
G01X878778Y236891D02*
X876278D01*
X876778Y236391D01*
G01X878778D02*
Y237391D01*
G01X880913Y226798D02*
X884913D01*
Y234198D01*
G01X882099Y244602D02*
X881974Y244352D01*
X881891Y244060D01*
Y243727D01*
X882016Y243352D01*
X882224Y243060D01*
X882474Y242852D01*
X882891Y242685D01*
X883266Y242643D01*
X883641Y242727D01*
X883891Y242852D01*
X884141Y243102D01*
X884308Y243393D01*
X884391Y243685D01*
Y243977D01*
X884308Y244268D01*
X884183Y244518D01*
X884016Y244727D01*
G01X883891Y245868D02*
X884183Y246118D01*
X884349Y246452D01*
X884391Y246827D01*
X884349Y247160D01*
X884141Y247493D01*
X883891Y247702D01*
X883641Y247743D01*
X883349Y247660D01*
X883141Y247368D01*
X883058Y247077D01*
Y246702D01*
G01Y247077D02*
X882933Y247327D01*
X882724Y247535D01*
X882474Y247618D01*
X882224Y247535D01*
X882016Y247327D01*
X881891Y246952D01*
X881933Y246577D01*
X882099Y246202D01*
G01X881891Y249885D02*
X881974Y249552D01*
X882183Y249302D01*
X882433Y249135D01*
X882766Y249010D01*
X883141Y248968D01*
X883516Y249010D01*
X883849Y249135D01*
X884099Y249302D01*
X884308Y249552D01*
X884391Y249885D01*
X884308Y250218D01*
X884099Y250468D01*
X883849Y250635D01*
X883516Y250760D01*
X883141Y250802D01*
X882766Y250760D01*
X882433Y250635D01*
X882183Y250468D01*
X881974Y250218D01*
X881891Y249885D01*
G01X884016Y252068D02*
X884224Y252318D01*
X884349Y252610D01*
X884391Y252985D01*
X884308Y253360D01*
X884141Y253652D01*
X883849Y253860D01*
X883516Y253902D01*
X883183Y253818D01*
X882974Y253610D01*
X882808Y253318D01*
X882766Y253027D01*
X882808Y252735D01*
X882974Y252360D01*
X881891Y252485D01*
Y253610D01*
G01X882442Y206867D02*
X882317Y206617D01*
X882234Y206325D01*
Y205992D01*
X882359Y205617D01*
X882567Y205325D01*
X882817Y205117D01*
X883234Y204950D01*
X883609Y204908D01*
X883984Y204992D01*
X884234Y205117D01*
X884484Y205367D01*
X884651Y205658D01*
X884734Y205950D01*
Y206242D01*
X884651Y206533D01*
X884526Y206783D01*
X884359Y206992D01*
G01X884234Y208133D02*
X884526Y208383D01*
X884692Y208717D01*
X884734Y209092D01*
X884692Y209425D01*
X884484Y209758D01*
X884234Y209967D01*
X883984Y210008D01*
X883692Y209925D01*
X883484Y209633D01*
X883401Y209342D01*
Y208967D01*
G01Y209342D02*
X883276Y209592D01*
X883067Y209800D01*
X882817Y209883D01*
X882567Y209800D01*
X882359Y209592D01*
X882234Y209217D01*
X882276Y208842D01*
X882442Y208467D01*
G01X882234Y212150D02*
X882317Y211817D01*
X882526Y211567D01*
X882776Y211400D01*
X883109Y211275D01*
X883484Y211233D01*
X883859Y211275D01*
X884192Y211400D01*
X884442Y211567D01*
X884651Y211817D01*
X884734Y212150D01*
X884651Y212483D01*
X884442Y212733D01*
X884192Y212900D01*
X883859Y213025D01*
X883484Y213067D01*
X883109Y213025D01*
X882776Y212900D01*
X882526Y212733D01*
X882317Y212483D01*
X882234Y212150D01*
G01X883692Y214458D02*
X883401Y214750D01*
X883234Y215000D01*
X883151Y215333D01*
X883234Y215625D01*
X883401Y215833D01*
X883651Y216000D01*
X883942Y216042D01*
X884192Y216000D01*
X884442Y215833D01*
X884651Y215583D01*
X884734Y215292D01*
X884651Y214958D01*
X884401Y214667D01*
X884026Y214500D01*
X883609Y214458D01*
X883067Y214542D01*
X882776Y214667D01*
X882484Y214875D01*
X882276Y215167D01*
X882234Y215458D01*
X882317Y215750D01*
X882526Y215958D01*
G01X899639Y230669D02*
X899847Y231002D01*
X899972Y231377D01*
Y231711D01*
X899847Y232044D01*
X899639Y232294D01*
X899347Y232419D01*
X899055Y232336D01*
X898805Y232127D01*
X898639Y231752D01*
X898555Y231252D01*
X898389Y230961D01*
X898097Y230836D01*
X897805Y230919D01*
X897597Y231127D01*
X897472Y231419D01*
Y231711D01*
X897555Y232002D01*
X897764Y232252D01*
G01X899972Y233769D02*
X897472Y235519D01*
G01Y233769D02*
X899972Y235519D01*
G01Y237744D02*
X897472D01*
X897972Y237244D01*
G01X899972D02*
Y238244D01*
G01X886100Y227800D02*
Y240200D01*
X894900D01*
Y227800D01*
G01X886834Y327517D02*
X884334D01*
Y328558D01*
X884459Y328892D01*
X884626Y329100D01*
X884959Y329183D01*
X885292Y329100D01*
X885501Y328850D01*
X885626Y328558D01*
Y327517D01*
G01Y328558D02*
X886834Y329183D01*
G01X885792Y330658D02*
X885501Y330950D01*
X885334Y331200D01*
X885251Y331533D01*
X885334Y331825D01*
X885501Y332033D01*
X885751Y332200D01*
X886042Y332242D01*
X886292Y332200D01*
X886542Y332033D01*
X886751Y331783D01*
X886834Y331492D01*
X886751Y331158D01*
X886501Y330867D01*
X886126Y330700D01*
X885709Y330658D01*
X885167Y330742D01*
X884876Y330867D01*
X884584Y331075D01*
X884376Y331367D01*
X884334Y331658D01*
X884417Y331950D01*
X884626Y332158D01*
G01X884751Y333758D02*
X884501Y334008D01*
X884376Y334300D01*
X884334Y334633D01*
X884417Y335050D01*
X884626Y335342D01*
X884876Y335425D01*
X885126Y335383D01*
X885334Y335217D01*
X885751Y334383D01*
X886042Y334008D01*
X886459Y333758D01*
X886834Y333675D01*
Y335425D01*
G01X884751Y336858D02*
X884501Y337108D01*
X884376Y337400D01*
X884334Y337733D01*
X884417Y338150D01*
X884626Y338442D01*
X884876Y338525D01*
X885126Y338483D01*
X885334Y338317D01*
X885751Y337483D01*
X886042Y337108D01*
X886459Y336858D01*
X886834Y336775D01*
Y338525D01*
G01X887568Y324041D02*
X883568D01*
Y316641D01*
G01X908834Y299800D02*
X908792Y299467D01*
X908626Y299175D01*
X908376Y298925D01*
X908084Y298758D01*
X907751Y298675D01*
X907417D01*
X907084Y298758D01*
X906792Y298925D01*
X906542Y299175D01*
X906376Y299467D01*
X906334Y299800D01*
X906376Y300133D01*
X906542Y300425D01*
X906792Y300675D01*
X907084Y300842D01*
X907417Y300925D01*
X907751D01*
X908084Y300842D01*
X908376Y300675D01*
X908626Y300425D01*
X908792Y300133D01*
X908834Y299800D01*
G01X908167Y300133D02*
X908834Y300633D01*
G01Y302900D02*
X906334D01*
X906834Y302400D01*
G01X908834D02*
Y303400D01*
G01Y306500D02*
X906334D01*
X908126Y304958D01*
Y307042D01*
G01X890844Y310041D02*
Y296041D01*
G01X903844Y310041D02*
X890844D01*
G01X903844Y296041D02*
Y310041D01*
G01X890844Y296041D02*
X903844D01*
G01X883834Y288017D02*
X886334D01*
Y289683D01*
G01Y292783D02*
Y291117D01*
X883834D01*
Y292783D01*
G01X885042Y292117D02*
Y291117D01*
G01X886334Y294133D02*
X883834D01*
Y294967D01*
X883959Y295300D01*
X884126Y295550D01*
X884376Y295758D01*
X884667Y295925D01*
X885084Y295967D01*
X885501Y295925D01*
X885792Y295758D01*
X886042Y295550D01*
X886209Y295300D01*
X886334Y294967D01*
Y294133D01*
G01Y298650D02*
X883834D01*
X885626Y297108D01*
Y299192D01*
G01X882962Y305355D02*
Y316155D01*
X888162D01*
Y305355D01*
X882962D01*
G01X881834Y367567D02*
X879334D01*
Y368608D01*
X879459Y368942D01*
X879626Y369150D01*
X879959Y369233D01*
X880292Y369150D01*
X880501Y368900D01*
X880626Y368608D01*
Y367567D01*
G01Y368608D02*
X881834Y369233D01*
G01X880792Y370708D02*
X880501Y371000D01*
X880334Y371250D01*
X880251Y371583D01*
X880334Y371875D01*
X880501Y372083D01*
X880751Y372250D01*
X881042Y372292D01*
X881292Y372250D01*
X881542Y372083D01*
X881751Y371833D01*
X881834Y371542D01*
X881751Y371208D01*
X881501Y370917D01*
X881126Y370750D01*
X880709Y370708D01*
X880167Y370792D01*
X879876Y370917D01*
X879584Y371125D01*
X879376Y371417D01*
X879334Y371708D01*
X879417Y372000D01*
X879626Y372208D01*
G01X881834Y374600D02*
X881792Y374892D01*
X881667Y375225D01*
X881459Y375433D01*
X881167Y375517D01*
X880876Y375433D01*
X880626Y375183D01*
X880501Y374808D01*
Y374392D01*
X880417Y374142D01*
X880209Y373933D01*
X879917Y373850D01*
X879626Y373975D01*
X879417Y374267D01*
X879334Y374600D01*
X879417Y374933D01*
X879626Y375225D01*
X879917Y375350D01*
X880209Y375267D01*
X880417Y375058D01*
X880501Y374808D01*
Y374392D01*
X880626Y374017D01*
X880876Y373767D01*
X881167Y373683D01*
X881459Y373767D01*
X881667Y373975D01*
X881792Y374308D01*
X881834Y374600D01*
G01Y377617D02*
X881292Y377700D01*
X880834Y377825D01*
X880417Y377992D01*
X879959Y378200D01*
X879334Y378533D01*
Y376867D01*
G01X868928Y396392D02*
Y390892D01*
G01Y384292D02*
Y378792D01*
G01X872841Y366767D02*
X872716Y366517D01*
X872633Y366225D01*
Y365892D01*
X872758Y365517D01*
X872966Y365225D01*
X873216Y365017D01*
X873633Y364850D01*
X874008Y364808D01*
X874383Y364892D01*
X874633Y365017D01*
X874883Y365267D01*
X875050Y365558D01*
X875133Y365850D01*
Y366142D01*
X875050Y366433D01*
X874925Y366683D01*
X874758Y366892D01*
G01X874633Y368033D02*
X874925Y368283D01*
X875091Y368617D01*
X875133Y368992D01*
X875091Y369325D01*
X874883Y369658D01*
X874633Y369867D01*
X874383Y369908D01*
X874091Y369825D01*
X873883Y369533D01*
X873800Y369242D01*
Y368867D01*
G01Y369242D02*
X873675Y369492D01*
X873466Y369700D01*
X873216Y369783D01*
X872966Y369700D01*
X872758Y369492D01*
X872633Y369117D01*
X872675Y368742D01*
X872841Y368367D01*
G01X875133Y371967D02*
X874591Y372050D01*
X874133Y372175D01*
X873716Y372342D01*
X873258Y372550D01*
X872633Y372883D01*
Y371217D01*
G01X875133Y375650D02*
X872633D01*
X874425Y374108D01*
Y376192D01*
G01X877623Y396338D02*
Y390838D01*
G01X869623D02*
Y396338D01*
G01Y378738D02*
Y384238D01*
G01X877623Y378738D02*
X869623D01*
G01X877623Y384238D02*
Y378738D01*
G01X893334Y347567D02*
X895834D01*
Y349233D01*
G01X893751Y350708D02*
X893501Y350958D01*
X893376Y351250D01*
X893334Y351583D01*
X893417Y352000D01*
X893626Y352292D01*
X893876Y352375D01*
X894126Y352333D01*
X894334Y352167D01*
X894751Y351333D01*
X895042Y350958D01*
X895459Y350708D01*
X895834Y350625D01*
Y352375D01*
G01Y354600D02*
X893334D01*
X893834Y354100D01*
G01X895834D02*
Y355100D01*
G01X883634Y358859D02*
X903634D01*
Y403459D01*
X883634D01*
Y358859D01*
G01X866017Y406500D02*
Y409000D01*
X867058D01*
X867392Y408875D01*
X867600Y408708D01*
X867683Y408375D01*
X867600Y408042D01*
X867350Y407833D01*
X867058Y407708D01*
X866017D01*
G01X867058D02*
X867683Y406500D01*
G01X869158Y407542D02*
X869450Y407833D01*
X869700Y408000D01*
X870033Y408083D01*
X870325Y408000D01*
X870533Y407833D01*
X870700Y407583D01*
X870742Y407292D01*
X870700Y407042D01*
X870533Y406792D01*
X870283Y406583D01*
X869992Y406500D01*
X869658Y406583D01*
X869367Y406833D01*
X869200Y407208D01*
X869158Y407625D01*
X869242Y408167D01*
X869367Y408458D01*
X869575Y408750D01*
X869867Y408958D01*
X870158Y409000D01*
X870450Y408917D01*
X870658Y408708D01*
G01X873050Y409000D02*
X872717Y408917D01*
X872467Y408708D01*
X872300Y408458D01*
X872175Y408125D01*
X872133Y407750D01*
X872175Y407375D01*
X872300Y407042D01*
X872467Y406792D01*
X872717Y406583D01*
X873050Y406500D01*
X873383Y406583D01*
X873633Y406792D01*
X873800Y407042D01*
X873925Y407375D01*
X873967Y407750D01*
X873925Y408125D01*
X873800Y408458D01*
X873633Y408708D01*
X873383Y408917D01*
X873050Y409000D01*
G01X876650Y406500D02*
Y409000D01*
X875108Y407208D01*
X877192D01*
G01X869623Y396338D02*
X877623D01*
G54D11*
G01X369618Y52623D02*
Y55023D01*
G01Y48023D02*
Y50423D01*
G01X373200Y60350D02*
X370800D01*
G01X369444Y83495D02*
Y85895D01*
G01Y78895D02*
Y81295D01*
G01X346158Y104928D02*
X343758D01*
G01X370800Y74050D02*
X373200D01*
G01X458292Y763780D02*
G03X468765I5236J0D01*
G01X489787D02*
G03X500260I5236J0D01*
G54D21*
G01X41480Y50950D02*
X45480D01*
G01X69800Y688700D02*
X73800D01*
G01X82616Y57675D02*
X86616D01*
G01X113619Y709995D02*
X117619D01*
G01X156349Y686915D02*
Y685815D01*
G01Y689615D02*
Y688515D01*
G01X319421Y554267D02*
X340921D01*
G01X324921Y557767D02*
X321421Y554267D01*
G01X324921Y557767D02*
X328421Y554267D01*
G01X330421Y580767D02*
Y554267D01*
X331921D01*
G01X319421Y580767D02*
X330421D01*
G01X319421Y554267D02*
Y580767D01*
G01X293018Y658582D02*
X297018D01*
G01X276523Y733405D02*
X280523D01*
G01X372000Y113000D02*
Y109000D01*
G01Y118000D02*
Y114000D01*
G01Y123000D02*
Y119000D01*
G01X351972Y189944D02*
X355972D01*
G01X371969Y583558D02*
X367969D01*
G01X350980Y639114D02*
X354980D01*
G01X369010Y697980D02*
X347510D01*
G01X363510Y694480D02*
X367010Y697980D01*
G01X363510Y694480D02*
X360010Y697980D01*
G01X358010Y671480D02*
Y697980D01*
X356510D01*
G01X369010Y671480D02*
X358010D01*
G01X369010Y697980D02*
Y671480D01*
G01X437300Y50457D02*
Y54457D01*
G01Y40657D02*
Y44657D01*
G01X451800Y58700D02*
X455800D01*
G01X437300Y45557D02*
Y49557D01*
G01X508122Y25193D02*
X509222D01*
G01X505422D02*
X506522D01*
G01X504622D02*
X500622D01*
G01X531940Y70410D02*
X535940D01*
G01X563070Y52403D02*
X561970D01*
G01X565770D02*
X564670D01*
G01X582890Y51680D02*
X583990D01*
G01X580190D02*
X581290D01*
G01X632660Y519543D02*
Y523543D01*
G01X649700Y501600D02*
Y497600D01*
G01X643460Y565043D02*
X644560D01*
G01X640760D02*
X641860D01*
G01X648400Y545900D02*
Y547000D01*
G01Y543200D02*
Y544300D01*
G01X626160Y562543D02*
X630160D01*
G01X647100Y542300D02*
Y538300D01*
G01X610500Y537800D02*
X614500D01*
G01X710000Y454500D02*
X706000D01*
G01X722900Y491000D02*
X726900D01*
G01X718200D02*
X722200D01*
G01X677174Y462079D02*
X673174D01*
G01X706200Y556300D02*
Y560300D01*
G01X731876Y598629D02*
X732976D01*
G01X729176D02*
X730276D01*
G01X711000Y621000D02*
Y617000D01*
G01X719300Y605700D02*
Y601700D01*
G01X750700Y51230D02*
X749600D01*
G01X753400D02*
X752300D01*
G01X769755Y40535D02*
Y41635D01*
G01Y37835D02*
Y38935D01*
G01X798024Y41200D02*
Y40100D01*
G01Y43900D02*
Y42800D01*
G01X784500Y418000D02*
X780500D01*
G01X765500Y485800D02*
Y481800D01*
G01X765247Y499627D02*
X769247D01*
G01X764400Y475900D02*
X760400D01*
G01X798388Y520156D02*
X802388D01*
G01X824024Y41200D02*
Y40100D01*
G01Y43900D02*
Y42800D01*
G01X881023Y387617D02*
X882123D01*
G01X878323D02*
X879423D01*
G54D12*
G01X-13131Y-65072D02*
Y-145072D01*
G01D02*
X1244069D01*
G01X-29131Y-65072D02*
Y-33072D01*
G01X-13131Y-65072D02*
X1244069D01*
G01X-13131Y-100572D02*
X1244069D01*
G01X-17131Y-49072D02*
G02I-12000J0D01*
G01X-22281D02*
G02I-6850J0D01*
G01X-13131D02*
X-45131D01*
G01X59859Y583825D02*
Y590125D01*
X66159D01*
G01X62812Y581857D02*
Y588157D01*
X69112D01*
G01X95964Y510452D02*
X91314D01*
G01X81250Y658454D02*
X86250D01*
G01X89050Y658354D02*
X94050D01*
G01X94654Y641650D02*
Y636650D01*
G01Y649550D02*
Y644550D01*
G01X90850Y684654D02*
Y679654D01*
G01X90900Y676900D02*
Y671900D01*
G01X99249Y734515D02*
X104249D01*
G01X91520Y734491D02*
X96520D01*
G01X122320Y736191D02*
X127320D01*
G01X106949Y734515D02*
X111949D01*
G01X114649D02*
X119649D01*
G01X169260Y447399D02*
X159160D01*
G01X157460Y456499D02*
X167560D01*
G01X214300Y713900D02*
X209300D01*
G01X206220Y742991D02*
X189620D01*
G01X264300Y447400D02*
X254200D01*
G01X252500Y456500D02*
X262600D01*
G01X220197Y609568D02*
X226497D01*
Y603268D01*
G01X222100Y713900D02*
X217100D01*
G01X270600Y660600D02*
Y666600D01*
G01X313770Y520291D02*
X320470D01*
G01X340921Y554267D02*
X331921D01*
G01X322136Y631404D02*
X327136D01*
G01X326540Y614000D02*
Y609000D01*
G01X329936Y631304D02*
X334936D01*
G01X326540Y621900D02*
Y616900D01*
G01X324574Y693770D02*
Y688770D01*
G01X318970Y702574D02*
X323970D01*
G01X311170Y702674D02*
X316170D01*
G01X324574Y685870D02*
Y680870D01*
G01X317036Y662304D02*
X322036D01*
G01X309136D02*
X314136D01*
G01X295970Y734974D02*
X300970D01*
G01X303870D02*
X308870D01*
G01X359462Y124901D02*
X376062D01*
G01X372992Y237274D02*
Y228174D01*
G01X365589Y517069D02*
X357589D01*
G01X351839Y578269D02*
X361339Y578279D01*
G01X347510Y697980D02*
X356510D01*
G01X456569Y-65072D02*
Y-145072D01*
G01X530070Y58990D02*
X520970D01*
G01X594069Y-65072D02*
Y-145072D01*
G01X579600Y60235D02*
Y65975D01*
G01X623734Y351900D02*
Y345200D01*
G01X663800Y434400D02*
Y439400D01*
G01X644027Y403437D02*
X648677D01*
G01X662100Y527000D02*
X657100D01*
G01X618500Y470500D02*
Y475500D01*
G01Y478500D02*
Y483500D01*
G01X654000Y527000D02*
X649000D01*
G01X665500Y701700D02*
Y706700D01*
G01Y694000D02*
Y699000D01*
G01Y686300D02*
Y691300D01*
G01X709069Y-65072D02*
Y-145072D01*
G01X725100Y436000D02*
Y431000D01*
G01Y467200D02*
Y462200D01*
G01Y443800D02*
Y438800D01*
G01Y451600D02*
Y446600D01*
G01Y459400D02*
Y454400D01*
G01X705780Y502070D02*
X714880D01*
G01X680900Y534100D02*
Y539100D01*
G01X679200Y564900D02*
Y569900D01*
G01X680876Y557229D02*
Y562229D01*
G01Y541829D02*
Y546829D01*
G01Y549529D02*
Y554529D01*
G01X879478Y716322D02*
X703278D01*
Y633022D01*
X879478D01*
Y716322D01*
G01X684600Y644900D02*
Y661500D01*
G01Y665100D02*
Y681700D01*
G01X768700Y55480D02*
Y61220D01*
G01X809606Y59252D02*
X803866D01*
G01X825100Y420700D02*
X841700D01*
G01X799900D02*
X816500D01*
G01X818550Y523454D02*
X823550D01*
G01X810650D02*
X815650D01*
G01X825750Y492754D02*
X830750D01*
G01X833550Y492654D02*
X838550D01*
G01X839454Y484150D02*
Y479150D01*
G01X876569Y-65072D02*
Y-145072D01*
G01X883212Y304655D02*
X887862D01*
G01X1046569Y-65072D02*
Y-145072D01*
G01X1244069Y-65072D02*
Y-145072D01*
G01X1272069Y-49072D02*
G02I-12000J0D01*
G01X1266919D02*
G02I-6850J0D01*
G01X1276069D02*
X1244069D01*
G01X1260069Y-65072D02*
Y-33072D01*
G54D13*
G01X84908Y44292D02*
G02I-4200J0D01*
G01X65224Y34449D02*
G02I-4200J0D01*
G01X37664D02*
G02I-4200J0D01*
G01X60302Y24606D02*
G02I-4200J0D01*
G01X42586D02*
G02I-4200J0D01*
G01X112468Y44292D02*
G02I-4200J0D01*
G01X107546Y34449D02*
G02I-4200J0D01*
G01X89830D02*
G02I-4200J0D01*
G01X177389Y669291D02*
G02I-14200J0D01*
G01X343731Y47253D02*
G02X334931I-4400J0D01*
G01D02*
Y52353D01*
G01D02*
G02X343731I4400J0D01*
G01Y90729D02*
G02X334931I-4400J0D01*
G01D02*
Y93129D01*
G01D02*
G02X343731I4400J0D01*
G01X357043Y70787D02*
G02I-3500J0D01*
G01X349957Y66850D02*
G02I-3500J0D01*
G01X357043Y62913D02*
G02I-3500J0D01*
G01X349957Y57007D02*
G02I-3500J0D01*
G01X357043Y55039D02*
G02I-3500J0D01*
G01X365069Y51003D02*
Y48603D01*
G01X357043Y55039D02*
G02I-3500J0D01*
G01X365069Y48603D02*
G02X356269I-4400J0D01*
G01D02*
Y51003D01*
G01D02*
G02X365069I4400J0D01*
G01X349957Y57007D02*
G02I-3500J0D01*
G01X343731Y52353D02*
Y47253D01*
G01Y93129D02*
Y90729D01*
G01X365069Y94479D02*
Y89379D01*
G01X356329Y88653D02*
G02X356269Y89379I4340J724D01*
G01D02*
Y94479D01*
G01D02*
G02X365069I4400J0D01*
G01X357022Y86917D02*
G02X356329Y88653I-3479J-382D01*
G01X365069Y89379D02*
G02X357022Y86917I-4400J0D01*
G01X349957Y84567D02*
G02I-3500J0D01*
G01X357043Y78661D02*
G02I-3500J0D01*
G01X349957Y74724D02*
G02I-3500J0D01*
G01X588703Y24409D02*
G02I-3900J0D01*
G01X578703D02*
G02I-3900J0D01*
G01X568703D02*
G02I-3900J0D01*
G01X604500Y574400D02*
G02I-4200J0D01*
G01X594500D02*
G02I-4200J0D01*
G01X614500D02*
G02I-4200J0D01*
G01X777680Y24409D02*
G02I-3900J0D01*
G01X767680D02*
G02I-3900J0D01*
G01X757680D02*
G02I-3900J0D01*
G01X804924D02*
G02I-3900J0D01*
G01X824924D02*
G02I-3900J0D01*
G01X814924D02*
G02I-3900J0D01*
G54D14*
G01X125200Y511400D02*
X121600D01*
Y515300D01*
G01X96564Y510852D02*
Y509002D01*
G01X90664Y510852D02*
Y509002D01*
G01X202551Y665571D02*
X204851D01*
G01X263531Y696424D02*
X266381D01*
Y693724D01*
G01X251131Y696624D02*
X253981D01*
Y693924D01*
G01X271200Y682500D02*
X268350D01*
Y685200D01*
G01X320056Y193705D02*
Y191705D01*
G01X316900Y592100D02*
Y594950D01*
X319600D01*
G01X280333Y621667D02*
X283933D01*
Y617767D01*
G01X393277Y74690D02*
Y73190D01*
G01X364800Y113900D02*
Y109900D01*
X359000D01*
G01X369135Y221773D02*
X371985D01*
Y219073D01*
G01X366300Y483200D02*
X363450D01*
Y485900D01*
G01X369161Y655349D02*
X373361D01*
Y651449D01*
G01X373800Y703400D02*
Y699400D01*
X368000D01*
G01X524493Y38885D02*
Y40385D01*
G01X557700Y63980D02*
X560550D01*
Y61280D01*
G01X542400Y44650D02*
X548400D01*
Y50000D01*
G01X643427Y403037D02*
Y404887D01*
G01X649327Y403037D02*
Y404887D01*
G01X707984Y474780D02*
X710834D01*
Y472080D01*
G01X783820Y43212D02*
X780970D01*
Y45912D01*
G01X762700Y95900D02*
X759850D01*
Y98600D01*
G01X772100Y82600D02*
X774950D01*
Y79900D01*
G01X895250Y231404D02*
Y227432D01*
X892322D01*
G01X882612Y304255D02*
Y306105D01*
G01X888512Y304255D02*
Y306105D01*
G54D15*
G01X120197Y59055D02*
Y98425D01*
G01X184173Y433268D02*
X223543D01*
G01X264050Y599850D02*
X271800D01*
G01X287520Y98425D02*
Y59055D01*
G01X338761Y196814D02*
Y204564D01*
G01X355538Y539531D02*
X363288D01*
G01X408268Y347638D02*
Y316929D01*
G01Y690803D02*
Y721512D01*
G01X568110Y316929D02*
Y347638D01*
G01Y721512D02*
Y690803D01*
G01X672096Y446471D02*
X664346D01*
G01X853850Y385950D02*
X846100D01*
G54D16*
G01X35670Y44570D02*
X32470D01*
G01X95240Y51360D02*
X92040D01*
G01X308852Y548470D02*
X302152D01*
G01X610942Y352616D02*
Y345916D01*
G01X611097Y570085D02*
X616097D01*
Y575085D01*
G54D17*
G01X849800Y597600D02*
G03I-10900J0D01*
G54D18*
G01X283945Y544394D02*
X280545D01*
G54D19*
G01X870270Y515690D02*
X869610D01*
G01X869710Y515780D02*
X870370D01*
G01X870460Y515890D02*
X869810D01*
G01X869910Y515980D02*
X870560D01*
G01X870660Y516090D02*
X870000D01*
G01X870100Y516190D02*
X870750D01*
G01X870850Y516280D02*
X870200D01*
G01X870290Y516390D02*
X870950D01*
G01X871040Y516480D02*
X870390D01*
G01X870480Y516590D02*
X871140D01*
G01X871240Y516690D02*
X870580D01*
G01X870680Y516780D02*
X871330D01*
G01X871430Y516890D02*
X870785D01*
G01X870780D02*
X870830D01*
G01X870870Y516980D02*
X870910D01*
G01X870870D02*
X871520D01*
G01X871620Y517090D02*
X870970D01*
G01X871070Y517190D02*
X871720D01*
G01X871820Y517280D02*
X871160D01*
G01X871260Y517390D02*
X871910D01*
G01X872010Y517480D02*
X871350D01*
G01X871450Y517590D02*
X872110D01*
G01X872200Y517690D02*
X871550D01*
G01X871650Y517780D02*
X872300D01*
G01X872390Y517890D02*
X871740D01*
G01X871840Y517980D02*
X872490D01*
G01X872590Y518090D02*
X871930D01*
G01X872030Y518190D02*
X872690D01*
G01X872780Y518280D02*
X872130D01*
G01X872220Y518390D02*
X872880D01*
G01X873070Y518590D02*
X872420D01*
G01X872610Y518780D02*
X873260D01*
G01X873220Y526930D02*
X868040Y532520D01*
G01X873800Y526990D02*
X877030Y523510D01*
G01X874060Y523190D02*
X873590D01*
G01X873580Y523390D02*
X874040D01*
G01X874020Y523590D02*
X873560D01*
G01X873540Y523780D02*
X874010D01*
G01X873990Y523980D02*
X873520D01*
G01X873500Y524190D02*
X873970D01*
G01X873960Y524390D02*
X873490D01*
G01X873470Y524590D02*
X873940D01*
G01X873920Y524780D02*
X873450D01*
G01X873440Y524980D02*
X873910D01*
G01X873890Y525190D02*
X873420D01*
G01X873400Y525390D02*
X873870D01*
G01X873850Y525590D02*
X873390D01*
G01X873370Y525780D02*
X873840D01*
G01X873820Y525980D02*
X873350D01*
G01X873340Y526090D02*
X873850D01*
G01X874350Y526390D02*
X873320D01*
G01X873300Y526590D02*
X874170D01*
G01X873240Y526900D02*
X873220Y526930D01*
G01X873280Y526800D02*
X873240Y526900D01*
G01X873280Y526790D02*
Y526800D01*
G01Y526780D02*
Y526790D01*
G01X873980Y526780D02*
X873280D01*
G01D02*
X873720Y521630D01*
G01X873730Y521590D02*
X874200D01*
G01X874210Y521390D02*
X873740D01*
G01X873760Y521190D02*
X874230D01*
G01X874250Y520980D02*
X873780D01*
G01X873800Y520780D02*
X874270D01*
G01X874310Y520690D02*
X873810D01*
G01X873820Y520040D02*
X873720Y519930D01*
G01X873850Y520110D02*
X873820Y520040D01*
G01X873670Y519890D02*
X874360D01*
G01Y519690D02*
X873480D01*
G01X873290Y519480D02*
X874380D01*
G01X873740Y519280D02*
X873090D01*
G01X873000Y519190D02*
X873650D01*
G01X873550Y519090D02*
X872900D01*
G01X872800Y518980D02*
X873460D01*
G01X873360Y518890D02*
X872710D01*
G01X872520Y518690D02*
X873170D01*
G01X872970Y518480D02*
X872320D01*
G01X873700Y521890D02*
X874170D01*
G01X874150Y522090D02*
X873690D01*
G01X873670Y522280D02*
X874140D01*
G01X874120Y522480D02*
X873650D01*
G01X873630Y522690D02*
X874100D01*
G01X874090Y522890D02*
X873620D01*
G01X873610Y522980D02*
X874080D01*
G01X874070Y523090D02*
X873600D01*
G01X873580Y523280D02*
X874050D01*
G01X874040Y523480D02*
X873570D01*
G01X873550Y523690D02*
X874020D01*
G01X874000Y523890D02*
X873530D01*
G01X873520Y524090D02*
X873980D01*
G01X873960Y524280D02*
X873500D01*
G01X873480Y524480D02*
X873950D01*
G01X873930Y524690D02*
X873460D01*
G01X873450Y524890D02*
X873910D01*
G01X873900Y525090D02*
X873430D01*
G01X873410Y525280D02*
X873880D01*
G01X873860Y525480D02*
X873390D01*
G01X873380Y525690D02*
X873840D01*
G01X873830Y525890D02*
X873360D01*
G01X873990Y526110D02*
X876720Y523170D01*
G01X873870Y526130D02*
X873990Y526110D01*
G01X873820Y526030D02*
X873870Y526130D01*
G01X874090Y522780D02*
X873630D01*
G01X873640Y522590D02*
X874110D01*
G01X874130Y522390D02*
X873660D01*
G01X873680Y522190D02*
X874150D01*
G01X874160Y521980D02*
X873690D01*
G01X873710Y521780D02*
X874180D01*
G01X874190Y521690D02*
X873720D01*
G01X873850Y520170D02*
Y520110D01*
G01X873720Y521630D02*
X873850Y520170D01*
G01X873840Y520090D02*
X874520D01*
G01X874370Y519910D02*
X874350Y519840D01*
G01X874420Y519990D02*
X874370Y519910D01*
G01X874350Y519780D02*
X873580D01*
G01X873390Y519590D02*
X874370D01*
G01X874390Y519280D02*
X873890D01*
G01X873860Y519320D02*
X873760Y519300D01*
G01X874130Y516880D02*
X874240D01*
G01X874130Y516890D02*
Y516880D01*
G01X873930Y519240D02*
X874130Y516890D01*
G01X873860Y519320D02*
X873930Y519240D01*
G01X874230Y516980D02*
X874120D01*
G01X874125D02*
X879720D01*
G01X879785Y516890D02*
X874130D01*
G01X874370Y515840D02*
X875260D01*
G01X874330Y515880D02*
X874370Y515840D01*
G01X874330Y516560D02*
Y515880D01*
G01X874300Y516630D02*
X874330Y516560D01*
G01X874150Y516790D02*
X874300Y516630D01*
G01X874140Y516810D02*
X874150Y516790D01*
G01X874130Y516870D02*
X874140Y516810D01*
G01X875300Y515890D02*
X874330D01*
G01Y516090D02*
X875300D01*
G01Y516280D02*
X874330D01*
G01Y516480D02*
X875300D01*
G01X874580Y517190D02*
X874110D01*
G01X874090Y517280D02*
X874560D01*
G01X874550Y517480D02*
X874080D01*
G01X874060Y517690D02*
X874530D01*
G01X874510Y517890D02*
X874040D01*
G01X874030Y518090D02*
X874500D01*
G01X874480Y518280D02*
X874010D01*
G01X873990Y518480D02*
X874460D01*
G01X874450Y518690D02*
X873980D01*
G01X873960Y518890D02*
X874430D01*
G01X874410Y519090D02*
X873950D01*
G01X873840Y520280D02*
X874710D01*
G01X874900Y520480D02*
X873820D01*
G01X873790Y520890D02*
X874260D01*
G01X874270Y520740D02*
X873820Y526030D01*
G01X874010Y526090D02*
X874630D01*
G01X874820Y525890D02*
X874200D01*
G01X874380Y525690D02*
X875000D01*
G01X874260Y526480D02*
X873310D01*
G01X873290Y526690D02*
X874080D01*
G01X873890Y526890D02*
X873250D01*
G01X874210Y521480D02*
X873740D01*
G01X873750Y521280D02*
X874220D01*
G01X874240Y521090D02*
X873770D01*
G01X874340Y520650D02*
X874440Y520680D01*
G01X874270Y520740D02*
X874340Y520650D01*
G01X874250Y516690D02*
X880030D01*
G01X874570Y517260D02*
X874350Y519840D01*
G01X874570Y517190D02*
Y517260D01*
G01X874670Y517100D02*
X874570Y517190D01*
G01X878770Y517100D02*
X874670D01*
G01X874420Y519980D02*
X873770D01*
G01X873850Y520190D02*
X874610D01*
G01X874430Y519990D02*
X874420D01*
G01X874430Y520000D02*
Y519990D01*
G01Y520000D02*
X877020Y522690D01*
G01X876830Y522480D02*
X876190D01*
G01X875990Y522280D02*
X876640D01*
G01X876450Y522090D02*
X875800D01*
G01X875610Y521890D02*
X876250D01*
G01X876160Y521780D02*
X875510D01*
G01X875560Y521840D02*
X874440Y520680D01*
G01X874450Y520690D02*
X875090D01*
G01X875000Y520590D02*
X873820D01*
G01X873830Y520390D02*
X874810D01*
G01X874550Y520780D02*
X875190D01*
G01X875290Y520890D02*
X874650D01*
G01X874740Y520980D02*
X875390D01*
G01X875480Y521090D02*
X874840D01*
G01X874930Y521190D02*
X875580D01*
G01X875670Y521280D02*
X875030D01*
G01X875130Y521390D02*
X875770D01*
G01X875870Y521480D02*
X875220D01*
G01X875320Y521590D02*
X875960D01*
G01X876060Y521690D02*
X875410D01*
G01X876240Y523690D02*
X876870D01*
G01X876680Y523890D02*
X876060D01*
G01X875870Y524090D02*
X876490D01*
G01X876310Y524280D02*
X875680D01*
G01X875590Y524390D02*
X876210D01*
G01X876120Y524480D02*
X875500D01*
G01X875410Y524590D02*
X876030D01*
G01X875930Y524690D02*
X875310D01*
G01X875220Y524780D02*
X875840D01*
G01X875750Y524890D02*
X875130D01*
G01X875030Y524980D02*
X875660D01*
G01X875560Y525090D02*
X874940D01*
G01X874850Y525190D02*
X875470D01*
G01X875380Y525280D02*
X874750D01*
G01X874660Y525390D02*
X875280D01*
G01X875190Y525480D02*
X874570D01*
G01X874480Y525590D02*
X875100D01*
G01X874910Y525780D02*
X874290D01*
G01X874100Y525980D02*
X874720D01*
G01X874540Y526190D02*
X873340D01*
G01X873330Y526280D02*
X874450D01*
G01X876300Y525560D02*
X876340Y525520D01*
G01X874390Y519390D02*
X873190D01*
G01X873930Y519190D02*
X874400D01*
G01X874420Y518980D02*
X873950D01*
G01X873970Y518780D02*
X874440D01*
G01X874450Y518590D02*
X873980D01*
G01X874000Y518390D02*
X874470D01*
G01X874490Y518190D02*
X874020D01*
G01X874040Y517980D02*
X874500D01*
G01X874520Y517780D02*
X874060D01*
G01X874070Y517590D02*
X874540D01*
G01X874560Y517390D02*
X874090D01*
G01X874320Y516590D02*
X875370D01*
G01X875300Y515880D02*
X875260Y515840D01*
G01X875300Y516520D02*
Y515880D01*
G01X875400Y516620D02*
X875300Y516520D01*
G01Y515980D02*
X874330D01*
G01Y516190D02*
X875300D01*
G01Y516390D02*
X874330D01*
G01X878870Y517570D02*
Y517580D01*
G01X878860Y517500D02*
X878870Y517570D01*
G01X878860Y517240D02*
Y517500D01*
G01X878870Y517220D02*
X878860Y517240D01*
G01X878770Y517100D02*
X878870Y517220D01*
G01Y517590D02*
X879640D01*
G01X879600Y517390D02*
X878860D01*
G01X878840Y517190D02*
X879640D01*
G01X877480Y523020D02*
Y523160D01*
G01X880180Y520120D02*
X877480Y523020D01*
G01X877500Y523190D02*
X876710D01*
G01X876720Y523030D02*
X875560Y521840D01*
G01X876720Y523170D02*
Y523030D01*
G01X875710Y521980D02*
X876350D01*
G01X876540Y522190D02*
X875900D01*
G01X876090Y522390D02*
X876740D01*
G01X876930Y522590D02*
X876280D01*
G01X877170Y522690D02*
X878850Y520870D01*
G01X877020Y522690D02*
X877170D01*
G01X876380D02*
X877020D01*
G01X878840Y520890D02*
X879470D01*
G01X879280Y521090D02*
X878650D01*
G01X878470Y521280D02*
X879100D01*
G01X878910Y521480D02*
X878280D01*
G01X878190Y521590D02*
X878820D01*
G01X878720Y521690D02*
X878090D01*
G01X878000Y521780D02*
X878630D01*
G01X878540Y521890D02*
X877910D01*
G01X877820Y521980D02*
X878450D01*
G01X878350Y522090D02*
X877720D01*
G01X877630Y522190D02*
X878260D01*
G01X878170Y522280D02*
X877540D01*
G01X877450Y522390D02*
X878080D01*
G01X877980Y522480D02*
X877350D01*
G01X877260Y522590D02*
X877890D01*
G01X877800Y522690D02*
X877150D01*
G01X877520Y522980D02*
X876670D01*
G01X876720Y523090D02*
X877480D01*
G01X877600Y523280D02*
X876610D01*
G01X876520Y523390D02*
X877700D01*
G01X877800Y523480D02*
X876430D01*
G01X876340Y523590D02*
X876960D01*
G01X877170Y523510D02*
X878600Y524980D01*
G01X877030Y523510D02*
X877170D01*
G01X878500Y524890D02*
X879140D01*
G01X878950Y524690D02*
X878310D01*
G01X878220Y524590D02*
X878850D01*
G01X878760Y524480D02*
X878120D01*
G01X878020Y524390D02*
X878660D01*
G01X878570Y524280D02*
X877930D01*
G01X877830Y524190D02*
X878470D01*
G01X878370Y524090D02*
X877730D01*
G01X877640Y523980D02*
X878280D01*
G01X878180Y523890D02*
X877540D01*
G01X877450Y523780D02*
X878080D01*
G01X877990Y523690D02*
X877350D01*
G01X877250Y523590D02*
X877890D01*
G01X877610Y522890D02*
X876580D01*
G01X876480Y522780D02*
X877700D01*
G01X876770Y523780D02*
X876150D01*
G01X875960Y523980D02*
X876590D01*
G01X876400Y524190D02*
X875780D01*
G01X876390Y525520D02*
X878880D01*
G01X876340D02*
X876390D01*
G01X878890Y525280D02*
X879530D01*
G01X879340Y525090D02*
X878700D01*
G01X879820Y525590D02*
X876300D01*
G01X876340Y526550D02*
X876390D01*
G01X876300Y526510D02*
X876340Y526550D01*
G01X876300Y525560D02*
Y526510D01*
G01Y526390D02*
X879560D01*
G01X879590Y526190D02*
X876300D01*
G01Y525980D02*
X880210D01*
G01X880010Y525780D02*
X876300D01*
G01X879510Y526550D02*
X876390D01*
G01X876300Y526480D02*
X879560D01*
G01X879550Y526510D02*
X879510Y526550D01*
G01X879730Y526160D02*
X879930Y526360D01*
G01X879620Y526130D02*
X879730Y526160D01*
G01X879560Y526230D02*
X879620Y526130D01*
G01X879560Y526410D02*
Y526230D01*
G01Y526420D02*
Y526410D01*
G01X879550Y526510D02*
X879560Y526420D01*
G01X879760Y526190D02*
X880400D01*
G01X879560Y526280D02*
X876300D01*
G01X878410Y524780D02*
X879050D01*
G01X878970Y525460D02*
X878880Y525520D01*
G01X878950Y525350D02*
X878970Y525460D01*
G01X878600Y524980D02*
X878950Y525350D01*
G01X879240Y524980D02*
X878600D01*
G01X878930Y525480D02*
X879720D01*
G01X879630Y525390D02*
X878960D01*
G01X878800Y525190D02*
X879430D01*
G01X879000Y521390D02*
X878370D01*
G01X878560Y521190D02*
X879190D01*
G01X879370Y520980D02*
X878740D01*
G01X878930Y520780D02*
X879560D01*
G01X879650Y520690D02*
X879020D01*
G01X879110Y520590D02*
X879750D01*
G01X879840Y520480D02*
X879210D01*
G01X879300Y520390D02*
X879930D01*
G01X880120Y520190D02*
X879490D01*
G01X879670Y519980D02*
X880810D01*
G01X880800Y519890D02*
X879770D01*
G01X878910Y517760D02*
X878870Y517580D01*
G01X878910Y517770D02*
Y517760D01*
G01X879020Y518080D02*
X878910Y517770D01*
G01X879030Y518090D02*
X879020Y518080D01*
G01X879240Y518400D02*
X879030Y518090D01*
G01X879250Y518410D02*
X879240Y518400D01*
G01X879490Y518630D02*
X879250Y518410D01*
G01X879500Y518630D02*
X879490D01*
G01X879620Y518710D02*
X879500Y518630D01*
G01X879630Y518720D02*
X879620Y518710D01*
G01X879690Y518750D02*
X879630Y518720D01*
G01X879850Y518820D02*
X879690Y518750D01*
G01X878860Y517480D02*
X879620D01*
G01X879660Y517090D02*
X874110D01*
G01X879650Y517110D02*
X879660Y517090D01*
G01X879600Y517370D02*
X879650Y517110D01*
G01X879600Y517380D02*
Y517370D01*
G01Y517400D02*
Y517380D01*
G01X874150Y516780D02*
X879890D01*
G01X879810Y516850D02*
X879750Y516940D01*
G01X879820Y516840D02*
X879810Y516850D01*
G01X879830Y516830D02*
X879820Y516840D01*
G01X879670Y517080D02*
X879660Y517090D01*
G01X879750Y516950D02*
X879670Y517080D01*
G01X879620Y517280D02*
X878860D01*
G01X878890Y517690D02*
X879660D01*
G01X879650Y517660D02*
X879600Y517400D01*
G01X879660Y517680D02*
X879650Y517660D01*
G01X879880Y517410D02*
X879890Y517430D01*
G01X879830Y517940D02*
X880050Y518100D01*
G01X879820Y517930D02*
X879830Y517940D01*
G01X879810Y517910D02*
X879820Y517930D01*
G01X879670Y517700D02*
X879810Y517910D01*
G01X879660Y517680D02*
X879670Y517700D01*
G01X879890Y517980D02*
X878990D01*
G01X878950Y517890D02*
X879790D01*
G01X879720Y517780D02*
X878910D01*
G01X879090Y518190D02*
X880350D01*
G01X879760Y518780D02*
X881430D01*
G01X881520Y518690D02*
X879580D01*
G01X879340Y518480D02*
X881710D01*
G01X881890Y518280D02*
X879170D01*
G01X879750Y516890D02*
X879790D01*
G01X879830Y516830D02*
X880050Y516670D01*
G01X879620Y516090D02*
X881170D01*
G01X881330Y516190D02*
X879440D01*
G01X879000Y516620D02*
X875400D01*
G01X879080Y516590D02*
X879000Y516620D01*
G01X879090Y516580D02*
X879080Y516590D01*
G01X879090Y516570D02*
Y516580D01*
G01X879130Y516500D02*
X879090Y516570D01*
G01X879140Y516500D02*
X879130D01*
G01X879150Y516490D02*
X879140Y516500D01*
G01X879220Y516390D02*
X879150Y516490D01*
G01X879230Y516380D02*
X879220Y516390D01*
G01X879460Y516160D02*
X879230Y516380D01*
G01Y516390D02*
X881570D01*
G01X879480Y516150D02*
X879460Y516160D01*
G01X880280Y515850D02*
X880620Y515860D01*
G01X880270Y515850D02*
X880280D01*
G01X880260D02*
X880270D01*
G01X880100Y515870D02*
X880260Y515850D01*
G01X880080Y515870D02*
X880100D01*
G01X879480Y516150D02*
X880080Y515870D01*
G01X880730Y515890D02*
X880060D01*
G01Y516660D02*
X880050Y516670D01*
G01X880080Y516660D02*
X880060D01*
G01X880250Y516600D02*
X880080Y516660D01*
G01X880470Y516590D02*
X880490D01*
G01X880340D02*
X880470D01*
G01X880270Y516600D02*
X880340Y516590D01*
G01X880250Y516600D02*
X880270D01*
G01X879910Y517220D02*
X879880Y517410D01*
G01X879920Y517190D02*
X879910Y517220D01*
G01X880090Y516970D02*
X879920Y517190D01*
G01X880110Y516960D02*
X880090Y516970D01*
G01X880280Y516880D02*
X880110Y516960D01*
G01X880290Y516880D02*
X880280D01*
G01X880330Y516870D02*
X880290Y516880D01*
G01X880390Y516870D02*
X880330D01*
G01X880410D02*
X880390D01*
G01X880440Y517900D02*
X880450D01*
G01X880350D02*
X880440D01*
G01X880330Y517890D02*
X880350Y517900D01*
G01X880020Y517730D02*
X880330Y517890D01*
G01X880000Y517710D02*
X880020Y517730D01*
G01X879890Y517430D02*
X880000Y517710D01*
G01X880060Y518110D02*
X880050Y518100D01*
G01X880080Y518110D02*
X880060D01*
G01X880250Y518170D02*
X880080Y518110D01*
G01X880270Y518170D02*
X880250D01*
G01X880340Y518180D02*
X880270Y518170D01*
G01X880360Y518190D02*
X880340Y518180D01*
G01X880420Y518190D02*
X880360D01*
G01X880450Y518180D02*
X880420Y518190D01*
G01X880030Y518090D02*
X879030D01*
G01X879940Y517570D02*
X880880D01*
G01X880900Y517370D02*
X879890D01*
G01X879940Y517170D02*
X880850D01*
G01X880670Y516970D02*
X880100D01*
G01X880410Y516870D02*
X880540Y516890D01*
G01X880740Y517760D02*
X880090D01*
G01X880490Y518180D02*
X880690Y518130D01*
G01X880450Y518180D02*
X880490D01*
G01X879940Y518850D02*
X879850Y518820D01*
G01X879950Y518860D02*
X879940Y518850D01*
G01X880090Y518890D02*
X879950Y518860D01*
G01X880170Y518910D02*
X880090Y518890D01*
G01X879950Y519690D02*
X878850Y520870D01*
G01X880210Y519410D02*
X879950Y519690D01*
G01X880240Y519360D02*
X880210Y519410D01*
G01X880270Y519210D02*
X880240Y519360D01*
G01X880280Y519190D02*
X880270Y519210D01*
G01X880280Y519170D02*
Y519190D01*
G01X880260Y519000D02*
X880280Y519170D01*
G01X880260Y518990D02*
Y519000D01*
G01X880170Y518910D02*
X880260Y518990D01*
G01X879390Y520280D02*
X880030D01*
G01X880350Y520180D02*
X880860Y526410D01*
G01X880290Y520100D02*
X880350Y520180D01*
G01X880180Y520120D02*
X880290Y520100D01*
G01X879950Y526390D02*
X879930Y526360D01*
G01X880590Y526390D02*
X879950D01*
G01D02*
X880760Y527230D01*
G01X880340Y526780D02*
X882600D01*
G01Y526590D02*
X880150D01*
G01X879850Y526280D02*
X880490D01*
G01X880300Y526090D02*
X876300D01*
G01Y525890D02*
X880110D01*
G01X879910Y525690D02*
X876300D01*
G01X880520Y522190D02*
X880980D01*
G01X880970Y521980D02*
X880500D01*
G01X880480Y521780D02*
X880950D01*
G01X880940Y521590D02*
X880470D01*
G01X880450Y521390D02*
X880920D01*
G01X880910Y521190D02*
X880440D01*
G01X880420Y520980D02*
X880890D01*
G01X880870Y520780D02*
X880410D01*
G01X880390Y520590D02*
X880850D01*
G01X880840Y520390D02*
X880370D01*
G01X880350Y520190D02*
X880820D01*
G01X880780Y519690D02*
X879950D01*
G01X880140Y519480D02*
X880780D01*
G01X880960Y519280D02*
X880260D01*
G01X880270Y519090D02*
X881150D01*
G01X881320Y526280D02*
X880850D01*
G01X880690Y526490D02*
X877480Y523160D01*
G01X880800Y526510D02*
X880690Y526490D01*
G01X880860Y526410D02*
X880800Y526510D01*
G01X880580Y522980D02*
X881050D01*
G01X881060Y523090D02*
X880590D01*
G01X880610Y523280D02*
X881080D01*
G01X881090Y523480D02*
X880630D01*
G01X880640Y523690D02*
X881110D01*
G01X881120Y523890D02*
X880660D01*
G01X880670Y524090D02*
X881140D01*
G01X881160Y524280D02*
X880690D01*
G01X880710Y524480D02*
X881170D01*
G01X881190Y524690D02*
X880720D01*
G01X880740Y524890D02*
X881210D01*
G01X881220Y525090D02*
X880760D01*
G01X880770Y525280D02*
X881240D01*
G01X881250Y525480D02*
X880790D01*
G01X880800Y525690D02*
X881270D01*
G01X881290Y525890D02*
X880820D01*
G01X880840Y526090D02*
X881300D01*
G01X880690Y526480D02*
X880050D01*
G01X880570Y522780D02*
X881040D01*
G01X881020Y522590D02*
X880550D01*
G01X880540Y522390D02*
X881000D01*
G01X880990Y522280D02*
X880530D01*
G01X880510Y522090D02*
X880980D01*
G01X880960Y521890D02*
X880490D01*
G01X880480Y521690D02*
X880950D01*
G01X880930Y521480D02*
X880460D01*
G01X880450Y521280D02*
X880910D01*
G01X880900Y521090D02*
X880430D01*
G01X880410Y520890D02*
X880880D01*
G01X880860Y520690D02*
X880400D01*
G01X880380Y520480D02*
X880850D01*
G01X880830Y520280D02*
X880360D01*
G01X880820Y520090D02*
X879580D01*
G01X879860Y519780D02*
X880790D01*
G01X880780Y519590D02*
X880050D01*
G01X880220Y519390D02*
X880860D01*
G01X880800Y519450D02*
X881760Y518430D01*
G01X882080Y518090D02*
X880750D01*
G01X880730Y518110D02*
X880690Y518130D01*
G01X880730Y518110D02*
X881040Y517850D01*
G01X880810Y517670D02*
X879980D01*
G01X879900Y517470D02*
X880890D01*
G01X880700Y517800D02*
X880450Y517900D01*
G01X880720Y517790D02*
X880700Y517800D01*
G01X880870Y517590D02*
X880720Y517790D01*
G01X880880Y517560D02*
X880870Y517590D01*
G01X880540Y517870D02*
X880270D01*
G01X880560Y516890D02*
X880540D01*
G01X880780Y517030D02*
X880560Y516890D01*
G01X880790Y517050D02*
X880780Y517030D01*
G01X880900Y517280D02*
X880790Y517050D01*
G01X880910Y517300D02*
X880900Y517280D01*
G01X880880Y517560D02*
X880910Y517300D01*
G01X880750Y516690D02*
X881770D01*
G01X880630Y515860D02*
X880620D01*
G01X880920Y515930D02*
X880630Y515860D01*
G01X880930Y515940D02*
X880920Y515930D01*
G01X881440Y516250D02*
X880930Y515940D01*
G01X880690Y516640D02*
X880730Y516660D01*
G01X880490Y516590D02*
X880690Y516640D01*
G01X880800Y517070D02*
X880020D01*
G01X879900Y517260D02*
X880900D01*
G01X880790Y519470D02*
X880770Y519540D01*
G01X880800Y519460D02*
X880790Y519470D01*
G01X880800Y519450D02*
Y519460D01*
G01X880820Y526480D02*
X881350D01*
G01X881340Y526470D02*
X880770Y519540D01*
G01X881050Y519190D02*
X880280D01*
G01X880250Y518980D02*
X881240D01*
G01X881330Y518890D02*
X880060D01*
G01X879450Y518590D02*
X881610D01*
G01X881800Y518390D02*
X879230D01*
G01X879080Y516590D02*
X881710D01*
G01X881530Y516340D02*
X881440Y516250D01*
G01X881590Y516410D02*
X881530Y516340D01*
G01X881720Y516600D02*
X881590Y516410D01*
G01X881480Y516280D02*
X879330D01*
G01X879150Y516480D02*
X881640D01*
G01X881840Y516850D02*
X881900Y517020D01*
G01X881800Y516750D02*
X881840Y516850D01*
G01X881800Y516740D02*
Y516750D01*
G01X881730Y516610D02*
X881800Y516740D01*
G01X881720Y516600D02*
X881730Y516610D01*
G01X881890Y516980D02*
X881075D01*
G01X881080D02*
X881140D01*
G01X881040Y516920D02*
X880730Y516660D01*
G01X881070Y516970D02*
X881040Y516920D01*
G01X880870Y516780D02*
X881820D01*
G01X881850Y516890D02*
X881060D01*
G01X881820D02*
X881850D01*
G01X881070Y517800D02*
X881040Y517850D01*
G01X881190Y517410D02*
X881070Y517800D01*
G01X881190Y517350D02*
Y517410D01*
G01X881070Y516970D02*
X881190Y517350D01*
G01X881000Y517890D02*
X882260D01*
G01X882450Y517690D02*
X881110D01*
G01X881170Y517480D02*
X882630D01*
G01X881930Y517280D02*
X881170D01*
G01X881110Y517090D02*
X881910D01*
G01X881000Y515980D02*
X879840D01*
G01X880540Y522480D02*
X881010D01*
G01X881030Y522690D02*
X880560D01*
G01X880580Y522890D02*
X881040D01*
G01X881070Y523190D02*
X880600D01*
G01X880610Y523390D02*
X881080D01*
G01X881100Y523590D02*
X880630D01*
G01X880650Y523780D02*
X881110D01*
G01X881130Y523980D02*
X880670D01*
G01X880680Y524190D02*
X881150D01*
G01X881170Y524390D02*
X880700D01*
G01X880710Y524590D02*
X881180D01*
G01X881200Y524780D02*
X880730D01*
G01X880750Y524980D02*
X881210D01*
G01X881230Y525190D02*
X880760D01*
G01X880780Y525390D02*
X881240D01*
G01X881260Y525590D02*
X880800D01*
G01X880810Y525780D02*
X881280D01*
G01X881300Y525980D02*
X880830D01*
G01X880840Y526190D02*
X881310D01*
G01X881330Y526390D02*
X880860D01*
G01X881340Y526470D02*
X881430Y526560D01*
G01X882560D02*
X881430D01*
G01X882600Y526580D02*
X882560Y526560D01*
G01X882600Y526590D02*
Y526580D01*
G01Y528410D02*
Y526590D01*
G01Y526890D02*
X880430D01*
G01X880240Y526690D02*
X882600D01*
G01X881980Y518190D02*
X880430D01*
G01X880870Y517980D02*
X882170D01*
G01X882350Y517780D02*
X881080D01*
G01X881130Y517590D02*
X882540D01*
G01X882730Y517390D02*
X882040D01*
G01X881900Y517040D02*
Y517020D01*
G01X881940Y517310D02*
X881900Y517040D01*
G01X882000Y517390D02*
X881940Y517310D01*
G01X881920Y517190D02*
X881140D01*
G01X882000Y517390D02*
X882110Y517370D01*
G01X881190Y517390D02*
X882000D01*
G01X882190Y517280D02*
X882820D01*
G01X882910Y517190D02*
X882280D01*
G01X882370Y517090D02*
X883010D01*
G01X883060Y516980D02*
X883100D01*
G01X883110D02*
X882470D01*
G01X882560Y516890D02*
X883195D01*
G01X883190D02*
X883140D01*
G01X883295Y516780D02*
X882650D01*
G01X882740Y516690D02*
X883380D01*
G01X883470Y516590D02*
X882835D01*
G01X882935Y516480D02*
X883570D01*
G01X883660Y516390D02*
X883020D01*
G01X883125Y516280D02*
X883750D01*
G01X883850Y516190D02*
X883210D01*
G01X883300Y516090D02*
X883940D01*
G01X884030Y515980D02*
X883390D01*
G01X883480Y515890D02*
X884130D01*
G01X884310Y515690D02*
X883670D01*
G01X883580Y515780D02*
X884220D01*
G01X884400Y515590D02*
X883760D01*
G01X883860Y515480D02*
X884500D01*
G01X884590Y515390D02*
X883950D01*
G01X884040Y515280D02*
X884680D01*
G01X884780Y515190D02*
X884130D01*
G01X884230Y515090D02*
X884870D01*
G01X884960Y514980D02*
X884320D01*
G01X884410Y514890D02*
X885060D01*
G01X885150Y514780D02*
X884510D01*
G01X884600Y514690D02*
X885240D01*
G01X885430Y514480D02*
X884790D01*
G01X884970Y514280D02*
X885580D01*
G01X885570Y514340D02*
X881760Y518430D01*
G01X885240Y514000D02*
X885260Y513980D01*
G01X882110Y517370D02*
X885240Y514000D01*
G01X885160Y514090D02*
X885380D01*
G01X868300Y514320D02*
X873720Y519930D01*
G01X868270Y514290D02*
X868300Y514320D01*
G01X868280Y514270D02*
X868270Y514290D01*
G01X868590Y514000D02*
X868280Y514270D01*
G01X868620Y513990D02*
X868590Y514000D01*
G01X868640D02*
X868620Y513990D01*
G01X873760Y519300D02*
X868640Y514000D01*
G01X868720Y514090D02*
X868490D01*
G01X868370Y514190D02*
X868820D01*
G01X868920Y514280D02*
X868270D01*
G01X868360Y514390D02*
X869020D01*
G01X869110Y514480D02*
X868460D01*
G01X868550Y514590D02*
X869210D01*
G01X869300Y514690D02*
X868650D01*
G01X868740Y514780D02*
X869400D01*
G01X869500Y514890D02*
X868840D01*
G01X868940Y514980D02*
X869590D01*
G01X869690Y515090D02*
X869040D01*
G01X869130Y515190D02*
X869790D01*
G01X869880Y515280D02*
X869230D01*
G01X869330Y515390D02*
X869980D01*
G01X870080Y515480D02*
X869420D01*
G01X869520Y515590D02*
X870170D01*
G01X885340Y514590D02*
X884690D01*
G01X884880Y514390D02*
X885520D01*
G01X885290Y514000D02*
X885260Y513980D01*
G01X885580Y514290D02*
X885290Y514000D01*
G01X885590Y514310D02*
X885580Y514290D01*
G01Y514320D02*
X885590Y514310D01*
G01X885570Y514340D02*
X885580Y514320D01*
G01X885060Y514190D02*
X885480D01*
G01X867970Y533200D02*
X868000Y533220D01*
G01X867970Y532660D02*
Y533200D01*
G01X867980Y532640D02*
X867970Y532660D01*
G01X868030Y532530D02*
X867980Y532640D01*
G01X868040Y532520D02*
X868030Y532530D01*
G01X867970Y533190D02*
X868030D01*
G01X867970Y533090D02*
X868120D01*
G01X868210Y532980D02*
X867970D01*
G01Y532890D02*
X868310D01*
G01X868400Y532780D02*
X867970D01*
G01Y532690D02*
X868490D01*
G01X868590Y532590D02*
X868000D01*
G01X868070Y532480D02*
X868680D01*
G01X868770Y532390D02*
X868160D01*
G01X868250Y532280D02*
X868860D01*
G01X868960Y532190D02*
X868350D01*
G01X868440Y532090D02*
X869050D01*
G01X869140Y531980D02*
X868530D01*
G01X868620Y531890D02*
X869240D01*
G01X869330Y531780D02*
X868720D01*
G01X868810Y531690D02*
X869420D01*
G01X869520Y531590D02*
X868900D01*
G01X869000Y531480D02*
X869610D01*
G01X869700Y531390D02*
X869090D01*
G01X869180Y531280D02*
X869800D01*
G01X869890Y531190D02*
X869280D01*
G01X869370Y531090D02*
X869980D01*
G01X870080Y530980D02*
X869460D01*
G01X869550Y530890D02*
X870170D01*
G01X870260Y530780D02*
X869650D01*
G01X869740Y530690D02*
X870350D01*
G01X870450Y530590D02*
X869830D01*
G01X869930Y530480D02*
X870540D01*
G01X870630Y530390D02*
X870020D01*
G01X870110Y530280D02*
X870720D01*
G01X870820Y530190D02*
X870210D01*
G01X870300Y530090D02*
X870910D01*
G01X871000Y529980D02*
X870390D01*
G01X870480Y529890D02*
X871100D01*
G01X871190Y529780D02*
X870580D01*
G01X870670Y529690D02*
X871280D01*
G01X871380Y529590D02*
X870760D01*
G01X870850Y529480D02*
X871470D01*
G01X871560Y529390D02*
X870950D01*
G01X871040Y529280D02*
X871660D01*
G01X871750Y529190D02*
X871130D01*
G01X871220Y529090D02*
X871840D01*
G01X871940Y528980D02*
X871320D01*
G01X871410Y528890D02*
X872030D01*
G01X872120Y528780D02*
X871500D01*
G01X871590Y528690D02*
X872220D01*
G01X872310Y528590D02*
X871690D01*
G01X871780Y528480D02*
X872400D01*
G01X872490Y528390D02*
X871870D01*
G01X871970Y528280D02*
X872590D01*
G01X872680Y528190D02*
X872060D01*
G01X872150Y528090D02*
X872770D01*
G01X872870Y527980D02*
X872250D01*
G01X872430Y527780D02*
X873670D01*
G01X873680Y527590D02*
X872620D01*
G01X872370Y529880D02*
X872880D01*
G01X872330Y529840D02*
X872370Y529880D01*
G01X872330Y529380D02*
Y529840D01*
G01X872370Y529340D02*
X872330Y529380D01*
G01Y529780D02*
X882580D01*
G01X882510Y529590D02*
X872330D01*
G01Y529390D02*
X882350D01*
G01X874980Y530690D02*
X873550D01*
G01X872970Y529950D02*
X872880Y529880D01*
G01X872990Y530000D02*
X872970Y529950D01*
G01X872990Y530010D02*
Y530000D01*
G01X873110Y530260D02*
X872990Y530010D01*
G01X873130Y530270D02*
X873110Y530260D01*
G01X873560Y530690D02*
X873130Y530270D01*
G01X872890Y529890D02*
X873620D01*
G01X873730Y530220D02*
X873840Y530290D01*
G01X873560Y530050D02*
X873730Y530220D01*
G01X873540Y529940D02*
X873560Y530050D01*
G01X873630Y529880D02*
X873540Y529940D01*
G01X873700Y530190D02*
X873080D01*
G01X873030Y530090D02*
X873600D01*
G01X873550Y529980D02*
X872980D01*
G01X873240Y530390D02*
X874920D01*
G01Y530590D02*
X873450D01*
G01X873790Y526990D02*
X873800D01*
G01X873750Y527040D02*
X873790Y526990D01*
G01X873720Y527100D02*
X873750Y527040D01*
G01X873540Y529230D02*
X873720Y527100D01*
G01X873640Y529340D02*
X873540Y529230D01*
G01X873180Y526980D02*
X873800D01*
G01X873730Y527090D02*
X873080D01*
G01X872990Y527190D02*
X873720D01*
G01X873710Y527280D02*
X872900D01*
G01X872800Y527390D02*
X873700D01*
G01X873690Y527480D02*
X872710D01*
G01X872520Y527690D02*
X873670D01*
G01X873660Y527890D02*
X873180D01*
G01X872970Y529340D02*
X872370D01*
G01X873070Y529250D02*
X872970Y529340D01*
G01X873190Y527900D02*
X873070Y529250D01*
G01X873030Y529280D02*
X873590D01*
G01X873540Y529190D02*
X873080D01*
G01X873090Y529090D02*
X873560D01*
G01Y528980D02*
X873090D01*
G01X873100Y528890D02*
X873570D01*
G01X873580Y528780D02*
X873110D01*
G01X873120Y528690D02*
X873590D01*
G01X873600Y528590D02*
X873130D01*
G01X873140Y528480D02*
X873610D01*
G01Y528390D02*
X873150D01*
G01Y528280D02*
X873620D01*
G01X873630Y528190D02*
X873170D01*
G01Y528090D02*
X873640D01*
G01X873650Y527980D02*
X873180D01*
G01X873020Y527830D02*
X868000Y533220D01*
G01X873130Y527800D02*
X873020Y527830D01*
G01X873190Y527900D02*
X873130Y527800D01*
G01X872340Y527890D02*
X872960D01*
G01X873950Y530300D02*
X873840Y530290D01*
G01X874000Y530210D02*
X873950Y530300D01*
G01X874000Y529980D02*
Y530210D01*
G01X873900Y529880D02*
X874000Y529980D01*
G01X873630Y529880D02*
X873900D01*
G01X873830Y530280D02*
X873140D01*
G01X874010Y531270D02*
X874040Y531290D01*
G01X874000Y531240D02*
X874010Y531270D01*
G01X874000Y531040D02*
Y531240D01*
G01X873990Y531000D02*
X874000Y531040D01*
G01X873970Y530950D02*
X873990Y531000D01*
G01X873920Y530890D02*
X873970Y530950D01*
G01X873830Y530850D02*
X873920Y530890D01*
G01X873560Y530690D02*
X873830Y530850D01*
G01X874040Y531280D02*
X874870D01*
G01X874000Y531090D02*
X876890D01*
G01X876880Y530890D02*
X873900D01*
G01X873950Y530280D02*
X874920D01*
G01Y530090D02*
X874000D01*
G01X873910Y529890D02*
X875020D01*
G01X874920Y529980D02*
X874000D01*
G01X875020Y529880D02*
X874920Y529980D01*
G01X874000Y530190D02*
X874920D01*
G01X876250Y530890D02*
X876360Y530780D01*
G01X875980Y530860D02*
X876250Y530890D01*
G01X875700Y530830D02*
X875980Y530860D01*
G01X875580Y530820D02*
X875700Y530830D01*
G01X875480Y530800D02*
X875580Y530820D01*
G01X875230Y530760D02*
X875480Y530800D01*
G01X875220Y530760D02*
X875230D01*
G01X875130Y530740D02*
X875220Y530760D01*
G01X875120Y530740D02*
X875130D01*
G01X875000Y530720D02*
X875120Y530740D01*
G01X874920Y530620D02*
X875000Y530720D01*
G01X874920Y529980D02*
Y530620D01*
G01X874860Y531290D02*
X874040D01*
G01X874880Y531280D02*
X874860Y531290D01*
G01X874910Y531270D02*
X874880Y531280D01*
G01X874940Y531250D02*
X874910Y531270D01*
G01X875020Y531230D02*
X874940Y531250D01*
G01X875040Y531240D02*
X875020Y531230D01*
G01X875280Y531280D02*
X875040Y531240D01*
G01X875780Y531350D02*
X875280Y531280D01*
G01X875900Y531360D02*
X875780Y531350D01*
G01X875960Y531360D02*
X875900D01*
G01X876120Y531380D02*
X875960Y531360D01*
G01X876260Y531390D02*
X876120Y531380D01*
G01X873720Y530780D02*
X875370D01*
G01X874920Y530480D02*
X873350D01*
G01X875020Y529880D02*
X880860D01*
G01X878930Y531390D02*
X876240D01*
G01X876260D02*
X876360Y531490D01*
G01Y530440D02*
Y530780D01*
G01X876400Y530390D02*
X876360Y530440D01*
G01X876350Y530780D02*
X878980D01*
G01X878850Y530390D02*
X876400D01*
G01X878900Y530440D02*
X878850Y530390D01*
G01X878900Y530720D02*
Y530440D01*
G01X876360Y530480D02*
X878900D01*
G01Y530590D02*
X876360D01*
G01Y530690D02*
X878900D01*
G01X878450Y531000D02*
Y530960D01*
G01X878350Y531100D02*
X878450Y531000D01*
G01X876910Y531100D02*
X878350D01*
G01X876810Y531000D02*
X876910Y531100D01*
G01X876810Y530960D02*
Y531000D01*
G01X876910Y530850D02*
X876810Y530960D01*
G01X878350Y530850D02*
X876910D01*
G01X878450Y530960D02*
X878350Y530850D01*
G01X878450Y530980D02*
X880420D01*
G01X880130Y531090D02*
X878360D01*
G01X876360Y531520D02*
Y531490D01*
G01X876400Y531560D02*
X876360Y531520D01*
G01X878850Y531560D02*
X876400D01*
G01X878900Y531520D02*
X878850Y531560D01*
G01X878900Y531420D02*
Y531520D01*
G01X876350Y531480D02*
X878900D01*
G01X876810Y530980D02*
X873980D01*
G01X874000Y531190D02*
X879760D01*
G01X878980Y531320D02*
X878900Y531420D01*
G01X879030Y531320D02*
X878980D01*
G01X879590Y531230D02*
X879030Y531320D01*
G01X879770Y531190D02*
X879590Y531230D01*
G01X879210Y531280D02*
X875340D01*
G01X879410Y530750D02*
X879820Y530660D01*
G01X879120Y530800D02*
X879410Y530750D01*
G01X879090Y530800D02*
X879120D01*
G01X879010Y530820D02*
X879090Y530800D01*
G01X878900Y530720D02*
X879010Y530820D01*
G01X879200Y530780D02*
X880790D01*
G01X880100Y530580D02*
X879820Y530660D01*
G01X880110Y530570D02*
X880100Y530580D01*
G01X880220Y530540D02*
X880110Y530570D01*
G01X880220Y530530D02*
Y530540D01*
G01X880330Y530490D02*
X880220Y530530D01*
G01X880340Y530480D02*
X880330Y530490D01*
G01X881200Y530480D02*
X880340D01*
G01X880060Y530590D02*
X881090D01*
G01X879890Y531150D02*
X879770Y531190D01*
G01X880000Y531130D02*
X879890Y531150D01*
G01X880240Y531050D02*
X880000Y531130D01*
G01X880350Y531010D02*
X880240Y531050D01*
G01X880410Y530990D02*
X880350Y531010D01*
G01X879700Y530690D02*
X880950D01*
G01X880630Y530890D02*
X878380D01*
G01X880950Y529930D02*
X880860Y529880D01*
G01X880940Y530030D02*
X880950Y529930D01*
G01X880870Y530140D02*
X880940Y530030D01*
G01X880850Y530160D02*
X880870Y530140D01*
G01X880550Y530380D02*
X880850Y530160D01*
G01X880540Y530390D02*
X880550Y530380D01*
G01X880530Y530390D02*
X880540D01*
G01X880340Y530480D02*
X880530Y530390D01*
G01X880870Y529890D02*
X882590D01*
G01X882570Y530090D02*
X880910D01*
G01X880680Y530280D02*
X882490D01*
G01X882600Y528280D02*
X880820D01*
G01X880790Y527260D02*
X880760Y527230D01*
G01X880820Y527320D02*
X880790Y527260D01*
G01X880820Y528340D02*
Y527320D01*
G01X880720Y527190D02*
X881390D01*
G01X881560Y527390D02*
X880820D01*
G01Y527590D02*
X881750D01*
G01X881940Y527780D02*
X880820D01*
G01Y527890D02*
X882600D01*
G01Y528090D02*
X880820D01*
G01X880930Y528420D02*
X881030Y528520D01*
G01X880860Y528420D02*
X880930D01*
G01X880820Y528380D02*
X880860Y528420D01*
G01X880820Y528340D02*
Y528380D01*
G01X880530Y526980D02*
X882600D01*
G01X880560Y530930D02*
X880410Y530990D01*
G01X880570Y530920D02*
X880560Y530930D01*
G01X881820Y530640D02*
X881880Y530650D01*
G01X881810Y530640D02*
X881820D01*
G01X881700Y530610D02*
X881810Y530640D01*
G01X881690Y530610D02*
X881700D01*
G01X881560Y530560D02*
X881690Y530610D01*
G01X881560Y530550D02*
Y530560D01*
G01X881500Y530520D02*
X881560Y530550D01*
G01X881480Y530500D02*
X881500Y530520D01*
G01X881420Y530450D02*
X881480Y530500D01*
G01X881400Y530430D02*
X881420Y530450D01*
G01X881260Y530430D02*
X881400D01*
G01X881080Y530600D02*
X881260Y530430D01*
G01X881070Y530610D02*
X881080Y530600D01*
G01X880570Y530920D02*
X881070Y530610D01*
G01X881630Y530590D02*
X882150D01*
G01X882200Y529280D02*
X881040D01*
G01X881090Y529230D02*
X881030Y528520D01*
G01X881000Y528480D02*
X881550D01*
G01X881840Y529210D02*
X881870Y529200D01*
G01X881760Y529220D02*
X881840Y529210D01*
G01X881690Y529240D02*
X881760Y529220D01*
G01X881680Y529240D02*
X881690D01*
G01X881550Y529150D02*
X881680Y529240D01*
G01X881500Y528540D02*
X881550Y529150D01*
G01X881600Y528430D02*
X881500Y528540D01*
G01X881600Y529190D02*
X881090D01*
G01X880990Y529340D02*
X873640D01*
G01X881090Y529230D02*
X880990Y529340D01*
G01X880630Y527090D02*
X881450D01*
G01X881420Y527240D02*
X881970Y527820D01*
G01X881390Y527190D02*
X881420Y527240D01*
G01X881390Y527150D02*
Y527190D01*
G01X881490Y527040D02*
X881390Y527150D01*
G01X881850Y527690D02*
X880820D01*
G01Y527480D02*
X881650D01*
G01X881460Y527280D02*
X880800D01*
G01X881760Y528420D02*
X881880D01*
G01X881600Y528430D02*
X881760Y528420D01*
G01X881510Y528590D02*
X881040D01*
G01X881050Y528690D02*
X881520D01*
G01Y528780D02*
X881060D01*
G01Y528890D02*
X881530D01*
G01X881540Y528980D02*
X881070D01*
G01X881080Y529090D02*
X881550D01*
G01X881950Y530650D02*
X881880D01*
G01X881960Y530640D02*
X881950Y530650D01*
G01X882220Y530570D02*
X881960Y530640D01*
G01X882230Y530560D02*
X882220Y530570D01*
G01X882430Y530390D02*
X882230Y530560D01*
G01X882440Y530380D02*
X882430Y530390D01*
G01X882560Y530150D02*
X882440Y530380D01*
G01X882570Y530130D02*
X882560Y530150D01*
G01X882590Y529850D02*
X882570Y530130D01*
G01X882590Y529840D02*
Y529850D01*
G01X882510Y529580D02*
X882590Y529840D01*
G01X882500Y529570D02*
X882510Y529580D01*
G01X882340Y529370D02*
X882500Y529570D01*
G01X882330Y529350D02*
X882340Y529370D01*
G01X882100Y529230D02*
X882330Y529350D01*
G01X882080Y529230D02*
X882100D01*
G01X881960Y529210D02*
X882080Y529230D01*
G01X881950Y529210D02*
X881960D01*
G01X881890Y529200D02*
X881950Y529210D01*
G01X881870Y529200D02*
X881890D01*
G01X881460Y530480D02*
X882320D01*
G01X882430Y530390D02*
X880540D01*
G01X880820Y530190D02*
X882540D01*
G01X882580Y529980D02*
X880950D01*
G01X882440Y529480D02*
X872330D01*
G01Y529690D02*
X882540D01*
G01X882850Y529390D02*
X883480D01*
G01X883580Y529480D02*
X882950D01*
G01X883040Y529590D02*
X883680D01*
G01X883770Y529690D02*
X883140D01*
G01X883240Y529780D02*
X883870D01*
G01X883960Y529890D02*
X883340D01*
G01X883430Y529980D02*
X884060D01*
G01X884160Y530090D02*
X883530D01*
G01X883630Y530190D02*
X884260D01*
G01X884450Y530390D02*
X883820D01*
G01X884010Y530590D02*
X884640D01*
G01X883390Y529280D02*
X882760D01*
G01X882660Y529190D02*
X883290D01*
G01X883190Y529090D02*
X882560D01*
G01X882460Y528980D02*
X883100D01*
G01X883000Y528890D02*
X882370D01*
G01X882270Y528780D02*
X882910D01*
G01X882810Y528690D02*
X882180D01*
G01X882080Y528590D02*
X882710D01*
G01X882600Y528420D02*
Y528410D01*
G01X882630Y528500D02*
X882600Y528420D01*
G01X882080Y527840D02*
X881970Y527820D01*
G01X882140Y527740D02*
X882080Y527840D01*
G01X882140Y527140D02*
Y527740D01*
G01X882040Y527040D02*
X882140Y527140D01*
G01X881490Y527040D02*
X882040D01*
G01X882110Y527780D02*
X882600D01*
G01Y527690D02*
X882140D01*
G01Y527590D02*
X882600D01*
G01Y527480D02*
X882140D01*
G01Y527390D02*
X882600D01*
G01Y527280D02*
X882140D01*
G01Y527190D02*
X882600D01*
G01Y527090D02*
X882090D01*
G01X882600Y527980D02*
X880820D01*
G01Y528190D02*
X882600D01*
G01Y528390D02*
X880820D01*
G01X881880Y528420D02*
X881950Y528450D01*
G01X881980Y528480D02*
X882620D01*
G01X881950Y528450D02*
X886530Y533190D01*
G01X886560Y532580D02*
X882630Y528500D01*
G01X883720Y530280D02*
X884350D01*
G01X884540Y530480D02*
X883910D01*
G01X884110Y530690D02*
X884740D01*
G01X884840Y530780D02*
X884210D01*
G01X884300Y530890D02*
X884930D01*
G01X885030Y530980D02*
X884400D01*
G01X884500Y531090D02*
X885120D01*
G01X885220Y531190D02*
X884590D01*
G01X884780Y531390D02*
X885410D01*
G01X885610Y531590D02*
X884980D01*
G01X885170Y531780D02*
X885800D01*
G01X885700Y531690D02*
X885080D01*
G01X885270Y531890D02*
X885890D01*
G01X885990Y531980D02*
X885360D01*
G01X885460Y532090D02*
X886090D01*
G01X886190Y532190D02*
X885560D01*
G01X885650Y532280D02*
X886280D01*
G01X886380Y532390D02*
X885750D01*
G01X885850Y532480D02*
X886470D01*
G01X886580Y532690D02*
X886040D01*
G01X886570Y532610D02*
X886580Y532690D01*
G01X886560Y532580D02*
X886570Y532610D01*
G01X885950Y532590D02*
X886560D01*
G01X886580Y533180D02*
X886530Y533190D01*
G01X886580Y532690D02*
Y533180D01*
G01X886520Y533190D02*
X886560D01*
G01X886580Y533090D02*
X886430D01*
G01X886330Y532980D02*
X886580D01*
G01Y532890D02*
X886230D01*
G01X886140Y532780D02*
X886580D01*
G01X885510Y531480D02*
X884880D01*
G01X884690Y531280D02*
X885320D01*
M02*
